G04 ================== begin FILE IDENTIFICATION RECORD ==================*
G04 Layout Name:  9127_F0T_Expander_BD_F_v02_0110_1240.brd*
G04 Film Name:    gnd6*
G04 File Format:  Gerber RS274X*
G04 File Origin:  Cadence Allegro 17.2-S081*
G04 Origin Date:  Wed Jan 11 16:06:30 2023*
G04 *
G04 Layer:  DRAWING FORMAT/TITLE_BLOCK_A*
G04 Layer:  PIN/SPECIAL_DRILL*
G04 Layer:  VIA CLASS/GND6*
G04 Layer:  PIN/GND6*
G04 Layer:  MANUFACTURING/PHOTOPLOT_OUTLINE*
G04 Layer:  ETCH/GND6*
G04 Layer:  DRAWING FORMAT/TITLE_BLOCK*
G04 Layer:  DRAWING FORMAT/TITLE_DATA_GND6*
G04 *
G04 Offset:    (0.00 0.00)*
G04 Mirror:    No*
G04 Mode:      Negative*
G04 Rotation:  0*
G04 FullContactRelief:  No*
G04 UndefLineWidth:     6.00*
G04 ================== end FILE IDENTIFICATION RECORD ====================*
%FSLAX25Y25*MOIN*%
%IR0*IPPOS*OFA0.00000B0.00000*MIA0B0*SFA1.00000B1.00000*%
%ADD15C,.03*%
%ADD53C,.06*%
%ADD23C,.024*%
%ADD54C,.061*%
%ADD33C,.0322*%
%ADD45C,.071*%
%ADD41C,.026*%
%AMMACRO28*
4,1,36,0.0,.01,
-.001736,.009848,
-.00342,.009397,
-.005,.00866,
-.006428,.00766,
-.00766,.006428,
-.00866,.005,
-.009397,.00342,
-.009848,.001736,
-.01,0.0,
-.009848,-.001736,
-.009397,-.00342,
-.00866,-.005,
-.00766,-.006428,
-.006428,-.00766,
-.005,-.00866,
-.00342,-.009397,
-.001736,-.009848,
0.0,-.01,
.001736,-.009848,
.00342,-.009397,
.005,-.00866,
.006428,-.00766,
.00766,-.006428,
.00866,-.005,
.009397,-.00342,
.009848,-.001736,
.01,0.0,
.009848,.001736,
.009397,.00342,
.00866,.005,
.00766,.006428,
.006428,.00766,
.005,.00866,
.00342,.009397,
.001736,.009848,
0.0,.01,
0.0*
%
%ADD28MACRO28*%
%ADD51C,.082*%
%ADD43C,.028*%
%AMMACRO38*
4,1,20,-.0075,-.05555,
-.0075,-.06273,
-.013677,-.060878,
-.019439,-.057981,
-.024611,-.054127,
-.029034,-.049434,
-.032576,-.044045,
-.035127,-.038122,
-.036612,-.031846,
-.037,-.0265,
-.037,-.0075,
-.03,-.0075,
-.03,-.0265,
-.029544,-.03171,
-.028191,-.036762,
-.02598,-.041502,
-.022981,-.045786,
-.019282,-.049484,
-.014998,-.052484,
-.010258,-.054694,
-.0075,-.05555,
270.*
4,1,20,.0075,-.06273,
.0075,-.05555,
.01243,-.053806,
.016983,-.051232,
.02102,-.047906,
.024418,-.043931,
.027073,-.039425,
.028906,-.034527,
.029861,-.029385,
.03,-.0265,
.03,-.0075,
.037,-.0075,
.037,-.0265,
.036438,-.032925,
.034769,-.039154,
.032043,-.044999,
.028344,-.050282,
.023784,-.054842,
.018501,-.058541,
.012656,-.061266,
.0075,-.06273,
270.*
4,1,20,-.0075,.06273,
-.0075,.05555,
-.01243,.053806,
-.016983,.051232,
-.02102,.047906,
-.024418,.043931,
-.027073,.039425,
-.028906,.034527,
-.029861,.029385,
-.03,.0265,
-.03,.0075,
-.037,.0075,
-.037,.0265,
-.036438,.032925,
-.034769,.039154,
-.032043,.044999,
-.028344,.050282,
-.023784,.054842,
-.018501,.058541,
-.012656,.061266,
-.0075,.06273,
270.*
4,1,20,.0075,.05555,
.0075,.06273,
.013677,.060878,
.019439,.057981,
.024611,.054127,
.029034,.049434,
.032576,.044045,
.035127,.038122,
.036612,.031846,
.037,.0265,
.037,.0075,
.03,.0075,
.03,.0265,
.029544,.03171,
.028191,.036762,
.02598,.041502,
.022981,.045786,
.019282,.049484,
.014998,.052484,
.010258,.054694,
.0075,.05555,
270.*
%
%ADD38MACRO38*%
%AMMACRO30*
4,1,36,.0025,0.0,
.002462,.000434,
.002349,.000855,
.002165,.00125,
.001915,.001607,
.001607,.001915,
.00125,.002165,
.000855,.002349,
.000434,.002462,
0.0,.0025,
-.000434,.002462,
-.000855,.002349,
-.00125,.002165,
-.001607,.001915,
-.001915,.001607,
-.002165,.00125,
-.002349,.000855,
-.002462,.000434,
-.0025,0.0,
-.002462,-.000434,
-.002349,-.000855,
-.002165,-.00125,
-.001915,-.001607,
-.001607,-.001915,
-.00125,-.002165,
-.000855,-.002349,
-.000434,-.002462,
0.0,-.0025,
.000434,-.002462,
.000855,-.002349,
.00125,-.002165,
.001607,-.001915,
.001915,-.001607,
.002165,-.00125,
.002349,-.000855,
.002462,-.000434,
.0025,0.0,
315.*
%
%ADD30MACRO30*%
%AMMACRO14*
4,1,36,.0025,0.0,
.002462,.000434,
.002349,.000855,
.002165,.00125,
.001915,.001607,
.001607,.001915,
.00125,.002165,
.000855,.002349,
.000434,.002462,
0.0,.0025,
-.000434,.002462,
-.000855,.002349,
-.00125,.002165,
-.001607,.001915,
-.001915,.001607,
-.002165,.00125,
-.002349,.000855,
-.002462,.000434,
-.0025,0.0,
-.002462,-.000434,
-.002349,-.000855,
-.002165,-.00125,
-.001915,-.001607,
-.001607,-.001915,
-.00125,-.002165,
-.000855,-.002349,
-.000434,-.002462,
0.0,-.0025,
.000434,-.002462,
.000855,-.002349,
.00125,-.002165,
.001607,-.001915,
.001915,-.001607,
.002165,-.00125,
.002349,-.000855,
.002462,-.000434,
.0025,0.0,
180.*
%
%ADD14MACRO14*%
%AMMACRO10*
4,1,36,.0025,0.0,
.002462,.000434,
.002349,.000855,
.002165,.00125,
.001915,.001607,
.001607,.001915,
.00125,.002165,
.000855,.002349,
.000434,.002462,
0.0,.0025,
-.000434,.002462,
-.000855,.002349,
-.00125,.002165,
-.001607,.001915,
-.001915,.001607,
-.002165,.00125,
-.002349,.000855,
-.002462,.000434,
-.0025,0.0,
-.002462,-.000434,
-.002349,-.000855,
-.002165,-.00125,
-.001915,-.001607,
-.001607,-.001915,
-.00125,-.002165,
-.000855,-.002349,
-.000434,-.002462,
0.0,-.0025,
.000434,-.002462,
.000855,-.002349,
.00125,-.002165,
.001607,-.001915,
.001915,-.001607,
.002165,-.00125,
.002349,-.000855,
.002462,-.000434,
.0025,0.0,
270.*
%
%ADD10MACRO10*%
%AMMACRO46*
4,1,36,-.0025,0.0,
-.002462,.000434,
-.002349,.000855,
-.002165,.00125,
-.001915,.001607,
-.001607,.001915,
-.00125,.002165,
-.000855,.002349,
-.000434,.002462,
0.0,.0025,
.000434,.002462,
.000855,.002349,
.00125,.002165,
.001607,.001915,
.001915,.001607,
.002165,.00125,
.002349,.000855,
.002462,.000434,
.0025,0.0,
.002462,-.000434,
.002349,-.000855,
.002165,-.00125,
.001915,-.001607,
.001607,-.001915,
.00125,-.002165,
.000855,-.002349,
.000434,-.002462,
0.0,-.0025,
-.000434,-.002462,
-.000855,-.002349,
-.00125,-.002165,
-.001607,-.001915,
-.001915,-.001607,
-.002165,-.00125,
-.002349,-.000855,
-.002462,-.000434,
-.0025,0.0,
180.*
%
%ADD46MACRO46*%
%AMMACRO36*
4,1,36,.003,0.0,
.002954,.000521,
.002819,.001026,
.002598,.0015,
.002298,.001928,
.001928,.002298,
.0015,.002598,
.001026,.002819,
.000521,.002954,
0.0,.003,
-.000521,.002954,
-.001026,.002819,
-.0015,.002598,
-.001928,.002298,
-.002298,.001928,
-.002598,.0015,
-.002819,.001026,
-.002954,.000521,
-.003,0.0,
-.002954,-.000521,
-.002819,-.001026,
-.002598,-.0015,
-.002298,-.001928,
-.001928,-.002298,
-.0015,-.002598,
-.001026,-.002819,
-.000521,-.002954,
0.0,-.003,
.000521,-.002954,
.001026,-.002819,
.0015,-.002598,
.001928,-.002298,
.002298,-.001928,
.002598,-.0015,
.002819,-.001026,
.002954,-.000521,
.003,0.0,
270.*
%
%ADD36MACRO36*%
%AMMACRO25*
4,1,36,.003,0.0,
.002954,.000521,
.002819,.001026,
.002598,.0015,
.002298,.001928,
.001928,.002298,
.0015,.002598,
.001026,.002819,
.000521,.002954,
0.0,.003,
-.000521,.002954,
-.001026,.002819,
-.0015,.002598,
-.001928,.002298,
-.002298,.001928,
-.002598,.0015,
-.002819,.001026,
-.002954,.000521,
-.003,0.0,
-.002954,-.000521,
-.002819,-.001026,
-.002598,-.0015,
-.002298,-.001928,
-.001928,-.002298,
-.0015,-.002598,
-.001026,-.002819,
-.000521,-.002954,
0.0,-.003,
.000521,-.002954,
.001026,-.002819,
.0015,-.002598,
.001928,-.002298,
.002298,-.001928,
.002598,-.0015,
.002819,-.001026,
.002954,-.000521,
.003,0.0,
180.*
%
%ADD25MACRO25*%
%ADD22C,.074*%
%AMMACRO42*
4,1,36,-.003,0.0,
-.002954,.000521,
-.002819,.001026,
-.002598,.0015,
-.002298,.001928,
-.001928,.002298,
-.0015,.002598,
-.001026,.002819,
-.000521,.002954,
0.0,.003,
.000521,.002954,
.001026,.002819,
.0015,.002598,
.001928,.002298,
.002298,.001928,
.002598,.0015,
.002819,.001026,
.002954,.000521,
.003,0.0,
.002954,-.000521,
.002819,-.001026,
.002598,-.0015,
.002298,-.001928,
.001928,-.002298,
.0015,-.002598,
.001026,-.002819,
.000521,-.002954,
0.0,-.003,
-.000521,-.002954,
-.001026,-.002819,
-.0015,-.002598,
-.001928,-.002298,
-.002298,-.001928,
-.002598,-.0015,
-.002819,-.001026,
-.002954,-.000521,
-.003,0.0,
180.*
%
%ADD42MACRO42*%
%ADD26C,.0435*%
%ADD34C,.0257*%
%ADD58C,.087*%
%ADD18C,.0277*%
%AMMACRO44*
4,1,18,.09673,.06845,
.107147,.050613,
.114308,.031238,
.117996,.010914,
.118098,-.009741,
.114613,-.030101,
.107644,-.049546,
.097406,-.067485,
.09673,-.06845,
.10175,-.07347,
.112962,-.054685,
.120742,-.034239,
.124853,-.012752,
.125171,.009122,
.121685,.030719,
.114502,.051383,
.10384,.070486,
.10175,.07347,
.09673,.06845,
90.*
4,1,18,.06845,-.09673,
.050613,-.107147,
.031238,-.114308,
.010914,-.117996,
-.009741,-.118098,
-.030101,-.114613,
-.049546,-.107644,
-.067485,-.097406,
-.06845,-.09673,
-.07347,-.10175,
-.054685,-.112962,
-.034239,-.120742,
-.012752,-.124853,
.009122,-.125171,
.030719,-.121685,
.051383,-.114502,
.070486,-.10384,
.07347,-.10175,
.06845,-.09673,
90.*
4,1,18,-.09673,-.06845,
-.107147,-.050613,
-.114308,-.031238,
-.117996,-.010914,
-.118098,.009741,
-.114613,.030101,
-.107644,.049546,
-.097406,.067485,
-.09673,.06845,
-.10175,.07347,
-.112962,.054685,
-.120742,.034239,
-.124853,.012752,
-.125171,-.009122,
-.121685,-.030719,
-.114502,-.051383,
-.10384,-.070486,
-.10175,-.07347,
-.09673,-.06845,
90.*
4,1,18,-.06845,.09673,
-.050613,.107147,
-.031238,.114308,
-.010914,.117996,
.009741,.118098,
.030101,.114613,
.049546,.107644,
.067485,.097406,
.06845,.09673,
.07347,.10175,
.054685,.112962,
.034239,.120742,
.012752,.124853,
-.009122,.125171,
-.030719,.121685,
-.051383,.114502,
-.070486,.10384,
-.07347,.10175,
-.06845,.09673,
90.*
%
%ADD44MACRO44*%
%AMMACRO11*
4,1,15,.06231,.03403,
.067273,.022693,
.070191,.010666,
.070977,-.001684,
.069606,-.013984,
.066121,-.025858,
.06231,-.03403,
.06745,-.03917,
.073227,-.026862,
.076779,-.013739,
.077998,-.000197,
.076848,.01335,
.073362,.026492,
.067647,.038828,
.06745,.03917,
.06231,.03403,
0.0*
4,1,15,.03403,-.06231,
.022693,-.067273,
.010666,-.070191,
-.001684,-.070977,
-.013984,-.069606,
-.025858,-.066121,
-.03403,-.06231,
-.03917,-.06745,
-.026862,-.073227,
-.013739,-.076779,
-.000197,-.077998,
.01335,-.076848,
.026492,-.073362,
.038828,-.067647,
.03917,-.06745,
.03403,-.06231,
0.0*
4,1,15,-.06231,-.03403,
-.067273,-.022693,
-.070191,-.010666,
-.070977,.001684,
-.069606,.013984,
-.066121,.025858,
-.06231,.03403,
-.06745,.03917,
-.073227,.026862,
-.076779,.013739,
-.077998,.000197,
-.076848,-.01335,
-.073362,-.026492,
-.067647,-.038828,
-.06745,-.03917,
-.06231,-.03403,
0.0*
4,1,15,-.03403,.06231,
-.022693,.067273,
-.010666,.070191,
.001684,.070977,
.013984,.069606,
.025858,.066121,
.03403,.06231,
.03917,.06745,
.026862,.073227,
.013739,.076779,
.000197,.077998,
-.01335,.076848,
-.026492,.073362,
-.038828,.067647,
-.03917,.06745,
-.03403,.06231,
0.0*
%
%ADD11MACRO11*%
%ADD20C,.099*%
%AMMACRO19*
4,1,18,.09673,.06845,
.107147,.050613,
.114308,.031238,
.117996,.010914,
.118098,-.009741,
.114613,-.030101,
.107644,-.049546,
.097406,-.067485,
.09673,-.06845,
.10175,-.07347,
.112962,-.054685,
.120742,-.034239,
.124853,-.012752,
.125171,.009122,
.121685,.030719,
.114502,.051383,
.10384,.070486,
.10175,.07347,
.09673,.06845,
0.0*
4,1,18,.06845,-.09673,
.050613,-.107147,
.031238,-.114308,
.010914,-.117996,
-.009741,-.118098,
-.030101,-.114613,
-.049546,-.107644,
-.067485,-.097406,
-.06845,-.09673,
-.07347,-.10175,
-.054685,-.112962,
-.034239,-.120742,
-.012752,-.124853,
.009122,-.125171,
.030719,-.121685,
.051383,-.114502,
.070486,-.10384,
.07347,-.10175,
.06845,-.09673,
0.0*
4,1,18,-.09673,-.06845,
-.107147,-.050613,
-.114308,-.031238,
-.117996,-.010914,
-.118098,.009741,
-.114613,.030101,
-.107644,.049546,
-.097406,.067485,
-.09673,.06845,
-.10175,.07347,
-.112962,.054685,
-.120742,.034239,
-.124853,.012752,
-.125171,-.009122,
-.121685,-.030719,
-.114502,-.051383,
-.10384,-.070486,
-.10175,-.07347,
-.09673,-.06845,
0.0*
4,1,18,-.06845,.09673,
-.050613,.107147,
-.031238,.114308,
-.010914,.117996,
.009741,.118098,
.030101,.114613,
.049546,.107644,
.067485,.097406,
.06845,.09673,
.07347,.10175,
.054685,.112962,
.034239,.120742,
.012752,.124853,
-.009122,.125171,
-.030719,.121685,
-.051383,.114502,
-.070486,.10384,
-.07347,.10175,
-.06845,.09673,
0.0*
%
%ADD19MACRO19*%
%ADD32C,.0299*%
%AMMACRO61*
4,1,19,-.0075,-.03785,
-.011528,-.036185,
-.015205,-.033846,
-.01842,-.030904,
-.021075,-.027448,
-.02309,-.023584,
-.024404,-.019428,
-.024975,-.015108,
-.025,-.014,
-.025,-.0075,
-.018,-.0075,
-.018,-.014,
-.017727,-.017125,
-.016915,-.020155,
-.015589,-.022998,
-.01379,-.025567,
-.011572,-.027785,
-.009002,-.029584,
-.0075,-.03036,
-.0075,-.03785,
180.*
4,1,19,.0075,-.03785,
.0075,-.03036,
.010227,-.02881,
.012643,-.02681,
.014676,-.024421,
.016262,-.021715,
.017355,-.018774,
.017921,-.015689,
.018,-.014,
.018,-.0075,
.025,-.0075,
.025,-.014,
.02462,-.018342,
.023492,-.022551,
.02165,-.026501,
.019151,-.030071,
.016069,-.033153,
.012499,-.035652,
.008549,-.037494,
.0075,-.03785,
180.*
4,1,19,-.025,.0075,
-.025,.014,
-.02462,.018342,
-.023492,.022551,
-.02165,.026501,
-.019151,.030071,
-.016069,.033153,
-.012499,.035652,
-.008549,.037494,
-.0075,.03785,
-.0075,.03036,
-.010227,.02881,
-.012643,.02681,
-.014676,.024421,
-.016262,.021715,
-.017355,.018774,
-.017921,.015689,
-.018,.014,
-.018,.0075,
-.025,.0075,
180.*
4,1,19,.018,.0075,
.018,.014,
.017727,.017125,
.016915,.020155,
.015589,.022998,
.01379,.025567,
.011572,.027785,
.009002,.029584,
.0075,.03036,
.0075,.03785,
.011528,.036185,
.015205,.033846,
.01842,.030904,
.021075,.027448,
.02309,.023584,
.024404,.019428,
.024975,.015108,
.025,.014,
.025,.0075,
.018,.0075,
180.*
%
%ADD61MACRO61*%
%AMMACRO37*
4,1,16,.02584,.01524,
.028094,.010521,
.029494,.005483,
.029998,.000278,
.029591,-.004935,
.028284,-.009999,
.026118,-.014758,
.02584,-.01524,
.03092,-.02032,
.033979,-.014642,
.036005,-.008519,
.036938,-.002138,
.036748,.004309,
.035441,.010625,
.033058,.016618,
.03092,.02032,
.02584,.01524,
0.0*
4,1,16,.01524,-.02584,
.010521,-.028094,
.005483,-.029494,
.000278,-.029998,
-.004935,-.029591,
-.009999,-.028284,
-.014758,-.026118,
-.01524,-.02584,
-.02032,-.03092,
-.014642,-.033979,
-.008519,-.036005,
-.002138,-.036938,
.004309,-.036748,
.010625,-.035441,
.016618,-.033058,
.02032,-.03092,
.01524,-.02584,
0.0*
4,1,16,-.02584,-.01524,
-.028094,-.010521,
-.029494,-.005483,
-.029998,-.000278,
-.029591,.004935,
-.028284,.009999,
-.026118,.014758,
-.02584,.01524,
-.03092,.02032,
-.033979,.014642,
-.036005,.008519,
-.036938,.002138,
-.036748,-.004309,
-.035441,-.010625,
-.033058,-.016618,
-.03092,-.02032,
-.02584,-.01524,
0.0*
4,1,16,-.01524,.02584,
-.010521,.028094,
-.005483,.029494,
-.000278,.029998,
.004935,.029591,
.009999,.028284,
.014758,.026118,
.01524,.02584,
.02032,.03092,
.014642,.033979,
.008519,.036005,
.002138,.036938,
-.004309,.036748,
-.010625,.035441,
-.016618,.033058,
-.02032,.03092,
-.01524,.02584,
0.0*
%
%ADD37MACRO37*%
%AMMACRO50*
4,1,15,.02142,.01082,
.022973,.006936,
.023829,.002841,
.02396,-.00134,
.023364,-.00548,
.022057,-.009454,
.02142,-.01082,
.02657,-.01597,
.02894,-.011114,
.03043,-.005919,
.030995,-.000545,
.030619,.004845,
.029313,.010088,
.027115,.015025,
.02657,.01597,
.02142,.01082,
90.*
4,1,15,.01082,-.02142,
.006936,-.022973,
.002841,-.023829,
-.00134,-.02396,
-.00548,-.023364,
-.009454,-.022057,
-.01082,-.02142,
-.01597,-.02657,
-.011114,-.02894,
-.005919,-.03043,
-.000545,-.030995,
.004845,-.030619,
.010088,-.029313,
.015025,-.027115,
.01597,-.02657,
.01082,-.02142,
90.*
4,1,15,-.02142,-.01082,
-.022973,-.006936,
-.023829,-.002841,
-.02396,.00134,
-.023364,.00548,
-.022057,.009454,
-.02142,.01082,
-.02657,.01597,
-.02894,.011114,
-.03043,.005919,
-.030995,.000545,
-.030619,-.004845,
-.029313,-.010088,
-.027115,-.015025,
-.02657,-.01597,
-.02142,-.01082,
90.*
4,1,15,-.01082,.02142,
-.006936,.022973,
-.002841,.023829,
.00134,.02396,
.00548,.023364,
.009454,.022057,
.01082,.02142,
.01597,.02657,
.011114,.02894,
.005919,.03043,
.000545,.030995,
-.004845,.030619,
-.010088,.029313,
-.015025,.027115,
-.01597,.02657,
-.01082,.02142,
90.*
%
%ADD50MACRO50*%
%AMMACRO48*
4,1,18,.07103,.05689,
.07983,.043691,
.086204,.029165,
.089959,.013753,
.09098,-.002077,
.089237,-.017844,
.084783,-.033069,
.077753,-.047289,
.07103,-.05689,
.07601,-.06186,
.085597,-.047721,
.092583,-.032132,
.096757,-.015567,
.09799,.001471,
.096246,.018464,
.091577,.034897,
.084126,.050269,
.07601,.06186,
.07103,.05689,
90.*
4,1,18,.05689,-.07103,
.043691,-.07983,
.029165,-.086204,
.013753,-.089959,
-.002077,-.09098,
-.017844,-.089237,
-.033069,-.084783,
-.047289,-.077753,
-.05689,-.07103,
-.06186,-.07601,
-.047721,-.085597,
-.032132,-.092583,
-.015567,-.096757,
.001471,-.09799,
.018464,-.096246,
.034897,-.091577,
.050269,-.084126,
.06186,-.07601,
.05689,-.07103,
90.*
4,1,18,-.07103,-.05689,
-.07983,-.043691,
-.086204,-.029165,
-.089959,-.013753,
-.09098,.002077,
-.089237,.017844,
-.084783,.033069,
-.077753,.047289,
-.07103,.05689,
-.07601,.06186,
-.085597,.047721,
-.092583,.032132,
-.096757,.015567,
-.09799,-.001471,
-.096246,-.018464,
-.091577,-.034897,
-.084126,-.050269,
-.07601,-.06186,
-.07103,-.05689,
90.*
4,1,18,-.05689,.07103,
-.043691,.07983,
-.029165,.086204,
-.013753,.089959,
.002077,.09098,
.017844,.089237,
.033069,.084783,
.047289,.077753,
.05689,.07103,
.06186,.07601,
.047721,.085597,
.032132,.092583,
.015567,.096757,
-.001471,.09799,
-.018464,.096246,
-.034897,.091577,
-.050269,.084126,
-.06186,.07601,
-.05689,.07103,
90.*
%
%ADD48MACRO48*%
%AMMACRO62*
4,1,19,-.0075,-.04535,
-.011528,-.043685,
-.015205,-.041346,
-.01842,-.038404,
-.021075,-.034948,
-.02309,-.031084,
-.024404,-.026928,
-.024975,-.022608,
-.025,-.0215,
-.025,-.0075,
-.018,-.0075,
-.018,-.0215,
-.017727,-.024625,
-.016915,-.027655,
-.015589,-.030498,
-.01379,-.033067,
-.011572,-.035285,
-.009002,-.037084,
-.0075,-.03786,
-.0075,-.04535,
180.*
4,1,19,.0075,-.04535,
.0075,-.03786,
.010227,-.03631,
.012643,-.03431,
.014676,-.031921,
.016262,-.029215,
.017355,-.026274,
.017921,-.023189,
.018,-.0215,
.018,-.0075,
.025,-.0075,
.025,-.0215,
.02462,-.025842,
.023492,-.030051,
.02165,-.034001,
.019151,-.037571,
.016069,-.040653,
.012499,-.043152,
.008549,-.044994,
.0075,-.04535,
180.*
4,1,19,-.025,.0075,
-.025,.0215,
-.02462,.025842,
-.023492,.030051,
-.02165,.034001,
-.019151,.037571,
-.016069,.040653,
-.012499,.043152,
-.008549,.044994,
-.0075,.04535,
-.0075,.03786,
-.010227,.03631,
-.012643,.03431,
-.014676,.031921,
-.016262,.029215,
-.017355,.026274,
-.017921,.023189,
-.018,.0215,
-.018,.0075,
-.025,.0075,
180.*
4,1,19,.018,.0075,
.018,.0215,
.017727,.024625,
.016915,.027655,
.015589,.030498,
.01379,.033067,
.011572,.035285,
.009002,.037084,
.0075,.03786,
.0075,.04535,
.011528,.043685,
.015205,.041346,
.01842,.038404,
.021075,.034948,
.02309,.031084,
.024404,.026928,
.024975,.022608,
.025,.0215,
.025,.0075,
.018,.0075,
180.*
%
%ADD62MACRO62*%
%AMMACRO55*
4,1,15,.02475,.01414,
.026829,.009627,
.028094,.004822,
.028504,-.000129,
.028049,-.005077,
.026741,-.009871,
.02475,-.01414,
.02984,-.01923,
.032726,-.013756,
.034617,-.007864,
.035457,-.001734,
.03522,.00445,
.033912,.010498,
.031574,.016227,
.02984,.01923,
.02475,.01414,
0.0*
4,1,15,.01414,-.02475,
.009627,-.026829,
.004822,-.028094,
-.000129,-.028504,
-.005077,-.028049,
-.009871,-.026741,
-.01414,-.02475,
-.01923,-.02984,
-.013756,-.032726,
-.007864,-.034617,
-.001734,-.035457,
.00445,-.03522,
.010498,-.033912,
.016227,-.031574,
.01923,-.02984,
.01414,-.02475,
0.0*
4,1,15,-.02475,-.01414,
-.026829,-.009627,
-.028094,-.004822,
-.028504,.000129,
-.028049,.005077,
-.026741,.009871,
-.02475,.01414,
-.02984,.01923,
-.032726,.013756,
-.034617,.007864,
-.035457,.001734,
-.03522,-.00445,
-.033912,-.010498,
-.031574,-.016227,
-.02984,-.01923,
-.02475,-.01414,
0.0*
4,1,15,-.01414,.02475,
-.009627,.026829,
-.004822,.028094,
.000129,.028504,
.005077,.028049,
.009871,.026741,
.01414,.02475,
.01923,.02984,
.013756,.032726,
.007864,.034617,
.001734,.035457,
-.00445,.03522,
-.010498,.033912,
-.016227,.031574,
-.01923,.02984,
-.01414,.02475,
0.0*
%
%ADD55MACRO55*%
%AMMACRO59*
4,1,15,.03682,.01914,
.039584,.012455,
.041146,.005393,
.041457,-.001834,
.040509,-.009005,
.03833,-.015903,
.03682,-.01914,
.04197,-.0243,
.045552,-.016643,
.04775,-.00848,
.048497,-.000059,
.047771,.008363,
.045593,.016531,
.042029,.024197,
.04197,.0243,
.03682,.01914,
90.*
4,1,15,.01914,-.03682,
.012455,-.039584,
.005393,-.041146,
-.001834,-.041457,
-.009005,-.040509,
-.015903,-.03833,
-.01914,-.03682,
-.0243,-.04197,
-.016643,-.045552,
-.00848,-.04775,
-.000059,-.048497,
.008363,-.047771,
.016531,-.045593,
.024197,-.042029,
.0243,-.04197,
.01914,-.03682,
90.*
4,1,15,-.03682,-.01914,
-.039584,-.012455,
-.041146,-.005393,
-.041457,.001834,
-.040509,.009005,
-.03833,.015903,
-.03682,.01914,
-.04197,.0243,
-.045552,.016643,
-.04775,.00848,
-.048497,.000059,
-.047771,-.008363,
-.045593,-.016531,
-.042029,-.024197,
-.04197,-.0243,
-.03682,-.01914,
90.*
4,1,15,-.01914,.03682,
-.012455,.039584,
-.005393,.041146,
.001834,.041457,
.009005,.040509,
.015903,.03833,
.01914,.03682,
.0243,.04197,
.016643,.045552,
.00848,.04775,
.000059,.048497,
-.008363,.047771,
-.016531,.045593,
-.024197,.042029,
-.0243,.04197,
-.01914,.03682,
90.*
%
%ADD59MACRO59*%
%AMMACRO60*
4,1,15,-.03682,.01914,
-.039584,.012455,
-.041146,.005393,
-.041457,-.001834,
-.040509,-.009005,
-.03833,-.015903,
-.03682,-.01914,
-.04197,-.0243,
-.045552,-.016643,
-.04775,-.00848,
-.048497,-.000059,
-.047771,.008363,
-.045593,.016531,
-.042029,.024197,
-.04197,.0243,
-.03682,.01914,
90.*
4,1,15,-.01914,-.03682,
-.012455,-.039584,
-.005393,-.041146,
.001834,-.041457,
.009005,-.040509,
.015903,-.03833,
.01914,-.03682,
.0243,-.04197,
.016643,-.045552,
.00848,-.04775,
.000059,-.048497,
-.008363,-.047771,
-.016531,-.045593,
-.024197,-.042029,
-.0243,-.04197,
-.01914,-.03682,
90.*
4,1,15,.03682,-.01914,
.039584,-.012455,
.041146,-.005393,
.041457,.001834,
.040509,.009005,
.03833,.015903,
.03682,.01914,
.04197,.0243,
.045552,.016643,
.04775,.00848,
.048497,.000059,
.047771,-.008363,
.045593,-.016531,
.042029,-.024197,
.04197,-.0243,
.03682,-.01914,
90.*
4,1,15,.01914,.03682,
.012455,.039584,
.005393,.041146,
-.001834,.041457,
-.009005,.040509,
-.015903,.03833,
-.01914,.03682,
-.0243,.04197,
-.016643,.045552,
-.00848,.04775,
-.000059,.048497,
.008363,.047771,
.016531,.045593,
.024197,.042029,
.0243,.04197,
.01914,.03682,
90.*
%
%ADD60MACRO60*%
%ADD63C,.142*%
%ADD13C,.125*%
%ADD29C,.208*%
%ADD47C,.164*%
%ADD17C,.155*%
%ADD39C,.256*%
%AMMACRO31*
4,1,36,0.0,.0085,
.001476,.008371,
.002907,.007987,
.00425,.007361,
.005464,.006511,
.006511,.005464,
.007361,.00425,
.007987,.002907,
.008371,.001476,
.0085,0.0,
.008371,-.001476,
.007987,-.002907,
.007361,-.00425,
.006511,-.005464,
.005464,-.006511,
.00425,-.007361,
.002907,-.007987,
.001476,-.008371,
0.0,-.0085,
-.001476,-.008371,
-.002907,-.007987,
-.00425,-.007361,
-.005464,-.006511,
-.006511,-.005464,
-.007361,-.00425,
-.007987,-.002907,
-.008371,-.001476,
-.0085,0.0,
-.008371,.001476,
-.007987,.002907,
-.007361,.00425,
-.006511,.005464,
-.005464,.006511,
-.00425,.007361,
-.002907,.007987,
-.001476,.008371,
0.0,.0085,
180.*
%
%ADD31MACRO31*%
%AMMACRO49*
4,1,36,0.0,.0185,
-.003212,.018219,
-.006327,.017384,
-.00925,.016021,
-.011892,.014172,
-.014172,.011892,
-.016021,.00925,
-.017384,.006327,
-.018219,.003212,
-.0185,0.0,
-.018219,-.003212,
-.017384,-.006327,
-.016021,-.00925,
-.014172,-.011892,
-.011892,-.014172,
-.00925,-.016021,
-.006327,-.017384,
-.003212,-.018219,
0.0,-.0185,
.003212,-.018219,
.006327,-.017384,
.00925,-.016021,
.011892,-.014172,
.014172,-.011892,
.016021,-.00925,
.017384,-.006327,
.018219,-.003212,
.0185,0.0,
.018219,.003212,
.017384,.006327,
.016021,.00925,
.014172,.011892,
.011892,.014172,
.00925,.016021,
.006327,.017384,
.003212,.018219,
0.0,.0185,
270.*
%
%ADD49MACRO49*%
%AMMACRO21*
4,1,20,-.0075,-.05555,
-.0075,-.06273,
-.013677,-.060878,
-.019439,-.057981,
-.024611,-.054127,
-.029034,-.049434,
-.032576,-.044045,
-.035127,-.038122,
-.036612,-.031846,
-.037,-.0265,
-.037,-.0075,
-.03,-.0075,
-.03,-.0265,
-.029544,-.03171,
-.028191,-.036762,
-.02598,-.041502,
-.022981,-.045786,
-.019282,-.049484,
-.014998,-.052484,
-.010258,-.054694,
-.0075,-.05555,
90.*
4,1,20,.0075,-.06273,
.0075,-.05555,
.01243,-.053806,
.016983,-.051232,
.02102,-.047906,
.024418,-.043931,
.027073,-.039425,
.028906,-.034527,
.029861,-.029385,
.03,-.0265,
.03,-.0075,
.037,-.0075,
.037,-.0265,
.036438,-.032925,
.034769,-.039154,
.032043,-.044999,
.028344,-.050282,
.023784,-.054842,
.018501,-.058541,
.012656,-.061266,
.0075,-.06273,
90.*
4,1,20,-.0075,.06273,
-.0075,.05555,
-.01243,.053806,
-.016983,.051232,
-.02102,.047906,
-.024418,.043931,
-.027073,.039425,
-.028906,.034527,
-.029861,.029385,
-.03,.0265,
-.03,.0075,
-.037,.0075,
-.037,.0265,
-.036438,.032925,
-.034769,.039154,
-.032043,.044999,
-.028344,.050282,
-.023784,.054842,
-.018501,.058541,
-.012656,.061266,
-.0075,.06273,
90.*
4,1,20,.0075,.05555,
.0075,.06273,
.013677,.060878,
.019439,.057981,
.024611,.054127,
.029034,.049434,
.032576,.044045,
.035127,.038122,
.036612,.031846,
.037,.0265,
.037,.0075,
.03,.0075,
.03,.0265,
.029544,.03171,
.028191,.036762,
.02598,.041502,
.022981,.045786,
.019282,.049484,
.014998,.052484,
.010258,.054694,
.0075,.05555,
90.*
%
%ADD21MACRO21*%
%AMMACRO16*
4,1,36,.0025,0.0,
.002462,.000434,
.002349,.000855,
.002165,.00125,
.001915,.001607,
.001607,.001915,
.00125,.002165,
.000855,.002349,
.000434,.002462,
0.0,.0025,
-.000434,.002462,
-.000855,.002349,
-.00125,.002165,
-.001607,.001915,
-.001915,.001607,
-.002165,.00125,
-.002349,.000855,
-.002462,.000434,
-.0025,0.0,
-.002462,-.000434,
-.002349,-.000855,
-.002165,-.00125,
-.001915,-.001607,
-.001607,-.001915,
-.00125,-.002165,
-.000855,-.002349,
-.000434,-.002462,
0.0,-.0025,
.000434,-.002462,
.000855,-.002349,
.00125,-.002165,
.001607,-.001915,
.001915,-.001607,
.002165,-.00125,
.002349,-.000855,
.002462,-.000434,
.0025,0.0,
90.*
%
%ADD16MACRO16*%
%AMMACRO35*
4,1,36,.003,0.0,
.002954,.000521,
.002819,.001026,
.002598,.0015,
.002298,.001928,
.001928,.002298,
.0015,.002598,
.001026,.002819,
.000521,.002954,
0.0,.003,
-.000521,.002954,
-.001026,.002819,
-.0015,.002598,
-.001928,.002298,
-.002298,.001928,
-.002598,.0015,
-.002819,.001026,
-.002954,.000521,
-.003,0.0,
-.002954,-.000521,
-.002819,-.001026,
-.002598,-.0015,
-.002298,-.001928,
-.001928,-.002298,
-.0015,-.002598,
-.001026,-.002819,
-.000521,-.002954,
0.0,-.003,
.000521,-.002954,
.001026,-.002819,
.0015,-.002598,
.001928,-.002298,
.002298,-.001928,
.002598,-.0015,
.002819,-.001026,
.002954,-.000521,
.003,0.0,
90.*
%
%ADD35MACRO35*%
%AMMACRO12*
4,1,36,.0025,0.0,
.002462,.000434,
.002349,.000855,
.002165,.00125,
.001915,.001607,
.001607,.001915,
.00125,.002165,
.000855,.002349,
.000434,.002462,
0.0,.0025,
-.000434,.002462,
-.000855,.002349,
-.00125,.002165,
-.001607,.001915,
-.001915,.001607,
-.002165,.00125,
-.002349,.000855,
-.002462,.000434,
-.0025,0.0,
-.002462,-.000434,
-.002349,-.000855,
-.002165,-.00125,
-.001915,-.001607,
-.001607,-.001915,
-.00125,-.002165,
-.000855,-.002349,
-.000434,-.002462,
0.0,-.0025,
.000434,-.002462,
.000855,-.002349,
.00125,-.002165,
.001607,-.001915,
.001915,-.001607,
.002165,-.00125,
.002349,-.000855,
.002462,-.000434,
.0025,0.0,
0.0*
%
%ADD12MACRO12*%
%AMMACRO52*
4,1,36,-.0025,0.0,
-.002462,.000434,
-.002349,.000855,
-.002165,.00125,
-.001915,.001607,
-.001607,.001915,
-.00125,.002165,
-.000855,.002349,
-.000434,.002462,
0.0,.0025,
.000434,.002462,
.000855,.002349,
.00125,.002165,
.001607,.001915,
.001915,.001607,
.002165,.00125,
.002349,.000855,
.002462,.000434,
.0025,0.0,
.002462,-.000434,
.002349,-.000855,
.002165,-.00125,
.001915,-.001607,
.001607,-.001915,
.00125,-.002165,
.000855,-.002349,
.000434,-.002462,
0.0,-.0025,
-.000434,-.002462,
-.000855,-.002349,
-.00125,-.002165,
-.001607,-.001915,
-.001915,-.001607,
-.002165,-.00125,
-.002349,-.000855,
-.002462,-.000434,
-.0025,0.0,
0.0*
%
%ADD52MACRO52*%
%AMMACRO27*
4,1,36,.003,0.0,
.002954,.000521,
.002819,.001026,
.002598,.0015,
.002298,.001928,
.001928,.002298,
.0015,.002598,
.001026,.002819,
.000521,.002954,
0.0,.003,
-.000521,.002954,
-.001026,.002819,
-.0015,.002598,
-.001928,.002298,
-.002298,.001928,
-.002598,.0015,
-.002819,.001026,
-.002954,.000521,
-.003,0.0,
-.002954,-.000521,
-.002819,-.001026,
-.002598,-.0015,
-.002298,-.001928,
-.001928,-.002298,
-.0015,-.002598,
-.001026,-.002819,
-.000521,-.002954,
0.0,-.003,
.000521,-.002954,
.001026,-.002819,
.0015,-.002598,
.001928,-.002298,
.002298,-.001928,
.002598,-.0015,
.002819,-.001026,
.002954,-.000521,
.003,0.0,
0.0*
%
%ADD27MACRO27*%
%AMMACRO24*
4,1,36,-.003,0.0,
-.002954,.000521,
-.002819,.001026,
-.002598,.0015,
-.002298,.001928,
-.001928,.002298,
-.0015,.002598,
-.001026,.002819,
-.000521,.002954,
0.0,.003,
.000521,.002954,
.001026,.002819,
.0015,.002598,
.001928,.002298,
.002298,.001928,
.002598,.0015,
.002819,.001026,
.002954,.000521,
.003,0.0,
.002954,-.000521,
.002819,-.001026,
.002598,-.0015,
.002298,-.001928,
.001928,-.002298,
.0015,-.002598,
.001026,-.002819,
.000521,-.002954,
0.0,-.003,
-.000521,-.002954,
-.001026,-.002819,
-.0015,-.002598,
-.001928,-.002298,
-.002298,-.001928,
-.002598,-.0015,
-.002819,-.001026,
-.002954,-.000521,
-.003,0.0,
0.0*
%
%ADD24MACRO24*%
%AMMACRO40*
4,1,16,.02584,.01524,
.028094,.010521,
.029494,.005483,
.029998,.000278,
.029591,-.004935,
.028284,-.009999,
.026118,-.014758,
.02584,-.01524,
.03092,-.02032,
.033979,-.014642,
.036005,-.008519,
.036938,-.002138,
.036748,.004309,
.035441,.010625,
.033058,.016618,
.03092,.02032,
.02584,.01524,
180.*
4,1,16,.01524,-.02584,
.010521,-.028094,
.005483,-.029494,
.000278,-.029998,
-.004935,-.029591,
-.009999,-.028284,
-.014758,-.026118,
-.01524,-.02584,
-.02032,-.03092,
-.014642,-.033979,
-.008519,-.036005,
-.002138,-.036938,
.004309,-.036748,
.010625,-.035441,
.016618,-.033058,
.02032,-.03092,
.01524,-.02584,
180.*
4,1,16,-.02584,-.01524,
-.028094,-.010521,
-.029494,-.005483,
-.029998,-.000278,
-.029591,.004935,
-.028284,.009999,
-.026118,.014758,
-.02584,.01524,
-.03092,.02032,
-.033979,.014642,
-.036005,.008519,
-.036938,.002138,
-.036748,-.004309,
-.035441,-.010625,
-.033058,-.016618,
-.03092,-.02032,
-.02584,-.01524,
180.*
4,1,16,-.01524,.02584,
-.010521,.028094,
-.005483,.029494,
-.000278,.029998,
.004935,.029591,
.009999,.028284,
.014758,.026118,
.01524,.02584,
.02032,.03092,
.014642,.033979,
.008519,.036005,
.002138,.036938,
-.004309,.036748,
-.010625,.035441,
-.016618,.033058,
-.02032,.03092,
-.01524,.02584,
180.*
%
%ADD40MACRO40*%
%AMMACRO56*
4,1,15,.03682,.01914,
.039584,.012455,
.041146,.005393,
.041457,-.001834,
.040509,-.009005,
.03833,-.015903,
.03682,-.01914,
.04197,-.0243,
.045552,-.016643,
.04775,-.00848,
.048497,-.000059,
.047771,.008363,
.045593,.016531,
.042029,.024197,
.04197,.0243,
.03682,.01914,
270.*
4,1,15,.01914,-.03682,
.012455,-.039584,
.005393,-.041146,
-.001834,-.041457,
-.009005,-.040509,
-.015903,-.03833,
-.01914,-.03682,
-.0243,-.04197,
-.016643,-.045552,
-.00848,-.04775,
-.000059,-.048497,
.008363,-.047771,
.016531,-.045593,
.024197,-.042029,
.0243,-.04197,
.01914,-.03682,
270.*
4,1,15,-.03682,-.01914,
-.039584,-.012455,
-.041146,-.005393,
-.041457,.001834,
-.040509,.009005,
-.03833,.015903,
-.03682,.01914,
-.04197,.0243,
-.045552,.016643,
-.04775,.00848,
-.048497,.000059,
-.047771,-.008363,
-.045593,-.016531,
-.042029,-.024197,
-.04197,-.0243,
-.03682,-.01914,
270.*
4,1,15,-.01914,.03682,
-.012455,.039584,
-.005393,.041146,
.001834,.041457,
.009005,.040509,
.015903,.03833,
.01914,.03682,
.0243,.04197,
.016643,.045552,
.00848,.04775,
.000059,.048497,
-.008363,.047771,
-.016531,.045593,
-.024197,.042029,
-.0243,.04197,
-.01914,.03682,
270.*
%
%ADD56MACRO56*%
%AMMACRO57*
4,1,15,-.03682,.01914,
-.039584,.012455,
-.041146,.005393,
-.041457,-.001834,
-.040509,-.009005,
-.03833,-.015903,
-.03682,-.01914,
-.04197,-.0243,
-.045552,-.016643,
-.04775,-.00848,
-.048497,-.000059,
-.047771,.008363,
-.045593,.016531,
-.042029,.024197,
-.04197,.0243,
-.03682,.01914,
270.*
4,1,15,-.01914,-.03682,
-.012455,-.039584,
-.005393,-.041146,
.001834,-.041457,
.009005,-.040509,
.015903,-.03833,
.01914,-.03682,
.0243,-.04197,
.016643,-.045552,
.00848,-.04775,
.000059,-.048497,
-.008363,-.047771,
-.016531,-.045593,
-.024197,-.042029,
-.0243,-.04197,
-.01914,-.03682,
270.*
4,1,15,.03682,-.01914,
.039584,-.012455,
.041146,-.005393,
.041457,.001834,
.040509,.009005,
.03833,.015903,
.03682,.01914,
.04197,.0243,
.045552,.016643,
.04775,.00848,
.048497,.000059,
.047771,-.008363,
.045593,-.016531,
.042029,-.024197,
.04197,-.0243,
.03682,-.01914,
270.*
4,1,15,.01914,.03682,
.012455,.039584,
.005393,.041146,
-.001834,.041457,
-.009005,.040509,
-.015903,.03833,
-.01914,.03682,
-.0243,.04197,
-.016643,.045552,
-.00848,.04775,
-.000059,.048497,
.008363,.047771,
.016531,.045593,
.024197,.042029,
.0243,.04197,
.01914,.03682,
270.*
%
%ADD57MACRO57*%
%ADD64C,.006*%
%ADD76C,.03006*%
%ADD80C,.07005*%
%ADD73C,.08404*%
%ADD66C,.07306*%
%ADD79C,.09208*%
%ADD74C,.07606*%
%ADD72C,.08408*%
%ADD78C,.07608*%
%ADD71C,.08409*%
%ADD70O,.1621X.2251*%
%ADD69O,.03604X.07004*%
%ADD67O,.03006X.06406*%
%ADD81C,.16206*%
%ADD68O,.03606X.07006*%
%ADD77C,.17406*%
%ADD65C,.16506*%
%ADD75C,.21786*%
G75*
%LPD*%
G75*
G36*
G01X-1490433Y-1677216D02*
X4496476D01*
Y3837819D01*
X-1490433D01*
Y-1677216D01*
G37*
%LPC*%
G75*
G36*
G01X630370Y-100983D02*
G02X624496Y-95109I0J5874D01*
G01Y-32983D01*
G03X614622Y-23109I-9874J0D01*
G01X68874D01*
G03X59000Y-32983I0J-9874D01*
G01Y-95109D01*
G02X53126Y-100983I-5874J0D01*
G01X7874D01*
G02X2000Y-95109I0J5874D01*
G01Y-15748D01*
G02X7874Y-9874I5874J0D01*
G01X31358D01*
G03X41232Y0I0J9874D01*
G01Y34843D01*
G02X47106Y40717I5874J0D01*
G01X54980D01*
G02X60854Y34843I0J-5874D01*
G01Y0D01*
G03X70728Y-9874I9874J0D01*
G01X133720D01*
G03X143594Y0I0J9874D01*
G01Y34843D01*
G02X149468Y40717I5874J0D01*
G01X157343D01*
G02X163217Y34843I0J-5874D01*
G01Y0D01*
G03X173091Y-9874I9874J0D01*
G01X236083D01*
G03X245957Y0I0J9874D01*
G01Y34843D01*
G02X251831Y40717I5874J0D01*
G01X259705D01*
G02X265579Y34843I0J-5874D01*
G01Y0D01*
G03X275453Y-9874I9874J0D01*
G01X338445D01*
G03X348319Y0I0J9874D01*
G01Y34843D01*
G02X354193Y40717I5874J0D01*
G01X362067D01*
G02X367941Y34843I0J-5874D01*
G01Y0D01*
G03X377815Y-9874I9874J0D01*
G01X488445D01*
G03X498319Y0I0J9874D01*
G01Y34843D01*
G02X504193Y40717I5874J0D01*
G01X512067D01*
G02X517941Y34843I0J-5874D01*
G01Y0D01*
G03X527815Y-9874I9874J0D01*
G01X590807D01*
G03X600681Y0I0J9874D01*
G01Y34843D01*
G02X606555Y40717I5874J0D01*
G01X614429D01*
G02X620303Y34843I0J-5874D01*
G01Y0D01*
G03X630177Y-9874I9874J0D01*
G01X693169D01*
G03X703043Y0I0J9874D01*
G01Y34843D01*
G02X708917Y40717I5874J0D01*
G01X716791D01*
G02X722665Y34843I0J-5874D01*
G01Y0D01*
G03X732539Y-9874I9874J0D01*
G01X795531D01*
G03X805405Y0I0J9874D01*
G01Y34843D01*
G02X811279Y40717I5874J0D01*
G01X819154D01*
G02X825028Y34843I0J-5874D01*
G01Y0D01*
G03X834902Y-9874I9874J0D01*
G01X945531D01*
G03X955405Y0I0J9874D01*
G01Y34843D01*
G02X961279Y40717I5874J0D01*
G01X969154D01*
G02X975028Y34843I0J-5874D01*
G01Y0D01*
G03X984902Y-9874I9874J0D01*
G01X1047894D01*
G03X1057768Y0I0J9874D01*
G01Y34843D01*
G02X1063642Y40717I5874J0D01*
G01X1071516D01*
G02X1077390Y34843I0J-5874D01*
G01Y0D01*
G03X1087264Y-9874I9874J0D01*
G01X1150256D01*
G03X1160130Y0I0J9874D01*
G01Y34843D01*
G02X1166004Y40717I5874J0D01*
G01X1173878D01*
G02X1179752Y34843I0J-5874D01*
G01Y0D01*
G03X1189626Y-9874I9874J0D01*
G01X1252618D01*
G03X1262492Y0I0J9874D01*
G01Y34843D01*
G02X1268366Y40717I5874J0D01*
G01X1276240D01*
G02X1282114Y34843I0J-5874D01*
G01Y0D01*
G03X1291988Y-9874I9874J0D01*
G01X1402618D01*
G03X1412492Y0I0J9874D01*
G01Y34843D01*
G02X1418366Y40717I5874J0D01*
G01X1426240D01*
G02X1432114Y34843I0J-5874D01*
G01Y0D01*
G03X1441988Y-9874I9874J0D01*
G01X1504980D01*
G03X1514854Y0I0J9874D01*
G01Y34843D01*
G02X1520728Y40717I5874J0D01*
G01X1528602D01*
G02X1534476Y34843I0J-5874D01*
G01Y0D01*
G03X1544350Y-9874I9874J0D01*
G01X1607343D01*
G03X1617217Y0I0J9874D01*
G01Y34843D01*
G02X1623091Y40717I5874J0D01*
G01X1630965D01*
G02X1636839Y34843I0J-5874D01*
G01Y0D01*
G03X1646713Y-9874I9874J0D01*
G01X1709705D01*
G03X1719579Y0I0J9874D01*
G01Y34843D01*
G02X1725453Y40717I5874J0D01*
G01X1733327D01*
G02X1739201Y34843I0J-5874D01*
G01Y0D01*
G03X1749075Y-9874I9874J0D01*
G01X1833071D01*
G02X1838945Y-15748I0J-5874D01*
G01Y-95109D01*
G02X1833071Y-100983I-5874J0D01*
G01X630370D01*
G37*
G36*
G01X1838945Y1528497D02*
Y970427D01*
G02X1838260Y967674I-5874J0D01*
G02X1837222Y966276I-5247J2812D01*
G01X1826874Y955928D01*
G03X1823980Y948943I6985J-6986D01*
G01Y344836D01*
G03X1826874Y337852I9877J1D01*
G01X1837222Y327503D01*
G02X1838941Y323354I-4150J-4150D01*
G01Y7874D01*
G02X1833071Y2004I-5870J0D01*
G01X1756949D01*
G02X1751079Y7874I0J5870D01*
G01Y46654D01*
G03X1745138Y52595I-5941J0D01*
G01X1713642D01*
G03X1707701Y46654I0J-5941D01*
G01Y7874D01*
G02X1701831Y2004I-5870J0D01*
G01X1654587D01*
G02X1648717Y7874I0J5870D01*
G01Y46654D01*
G03X1642776Y52595I-5941J0D01*
G01X1611280D01*
G03X1605339Y46654I0J-5941D01*
G01Y7874D01*
G02X1599469Y2004I-5870J0D01*
G01X1552224D01*
G02X1546354Y7874I0J5870D01*
G01Y46654D01*
G03X1540413Y52595I-5941J0D01*
G01X1508917D01*
G03X1502976Y46654I0J-5941D01*
G01Y7874D01*
G02X1497106Y2004I-5870J0D01*
G01X1449862D01*
G02X1443992Y7874I0J5870D01*
G01Y46654D01*
G03X1438051Y52595I-5941J0D01*
G01X1406555D01*
G03X1400614Y46654I0J-5941D01*
G01Y7874D01*
G02X1394744Y2004I-5870J0D01*
G01X1299862D01*
G02X1293992Y7874I0J5870D01*
G01Y46654D01*
G03X1288051Y52595I-5941J0D01*
G01X1256555D01*
G03X1250614Y46654I0J-5941D01*
G01Y7874D01*
G02X1244744Y2004I-5870J0D01*
G01X1197500D01*
G02X1191630Y7874I0J5870D01*
G01Y46654D01*
G03X1185689Y52595I-5941J0D01*
G01X1154193D01*
G03X1148252Y46654I0J-5941D01*
G01Y7874D01*
G02X1142382Y2004I-5870J0D01*
G01X1095138D01*
G02X1089268Y7874I0J5870D01*
G01Y46654D01*
G03X1083327Y52595I-5941J0D01*
G01X1051831D01*
G03X1045890Y46654I0J-5941D01*
G01Y7874D01*
G02X1040020Y2004I-5870J0D01*
G01X992776D01*
G02X986906Y7874I0J5870D01*
G01Y46654D01*
G03X980965Y52595I-5941J0D01*
G01X949468D01*
G03X943527Y46654I0J-5942D01*
G01Y7874D01*
G02X937657Y2004I-5870J0D01*
G01X842776D01*
G02X836906Y7874I0J5870D01*
G01Y46654D01*
G03X830965Y52595I-5941J0D01*
G01X799468D01*
G03X793527Y46654I0J-5942D01*
G01Y7874D01*
G02X787657Y2004I-5870J0D01*
G01X740413D01*
G02X734543Y7874I0J5870D01*
G01Y46654D01*
G03X728602Y52595I-5941J0D01*
G01X697106D01*
G03X691165Y46654I0J-5941D01*
G01Y7874D01*
G02X685295Y2004I-5870J0D01*
G01X638051D01*
G02X632181Y7874I0J5870D01*
G01Y46654D01*
G03X626240Y52595I-5941J0D01*
G01X594744D01*
G03X588803Y46654I0J-5941D01*
G01Y7874D01*
G02X582933Y2004I-5870J0D01*
G01X535689D01*
G02X529819Y7874I0J5870D01*
G01Y46654D01*
G03X523878Y52595I-5941J0D01*
G01X492382D01*
G03X486441Y46654I0J-5941D01*
G01Y7874D01*
G02X480571Y2004I-5870J0D01*
G01X385689D01*
G02X379819Y7874I0J5870D01*
G01Y46654D01*
G03X373878Y52595I-5941J0D01*
G01X342382D01*
G03X336441Y46654I0J-5941D01*
G01Y7874D01*
G02X330571Y2004I-5870J0D01*
G01X283327D01*
G02X277457Y7874I0J5870D01*
G01Y46654D01*
G03X271516Y52595I-5941J0D01*
G01X240020D01*
G03X234079Y46654I0J-5941D01*
G01Y7874D01*
G02X228209Y2004I-5870J0D01*
G01X180965D01*
G02X175095Y7874I0J5870D01*
G01Y46654D01*
G03X169154Y52595I-5941J0D01*
G01X137657D01*
G03X131716Y46654I0J-5941D01*
G01Y7874D01*
G02X125846Y2004I-5870J0D01*
G01X78602D01*
G02X72732Y7874I0J5870D01*
G01Y46654D01*
G03X66791Y52595I-5941J0D01*
G01X35295D01*
G03X29354Y46654I0J-5941D01*
G01Y7874D01*
G02X23484Y2004I-5870J0D01*
G01X18462D01*
X18458Y2000D01*
X12364D01*
X12360Y2004D01*
X7874D01*
G02X2004Y7874I0J5870D01*
G01Y323354D01*
G02X3723Y327503I5869J-1D01*
G01X14071Y337852D01*
G03X16965Y344836I-6983J6985D01*
G01Y948943D01*
G03X14071Y955928I-9879J-1D01*
G01X3723Y966276D01*
G02X2004Y970426I4151J4151D01*
G01Y1640118D01*
G02X7874Y1645988I5870J0D01*
G01X26771D01*
X26775Y1645992D01*
X31442D01*
X31446Y1645988D01*
X789296D01*
G02X793646Y1644059I0J-5870D01*
G03X800964Y1640815I7319J6634D01*
G01X1070059D01*
G03X1077377Y1644059I-1J9878D01*
G02X1081727Y1645988I4350J-3941D01*
G01X1833071D01*
G02X1838941Y1640118I0J-5870D01*
G01X1838945Y1528497D01*
G37*
G36*
G01X1833071Y1818880D02*
G02X1838945Y1813006I0J-5874D01*
G01Y1663740D01*
G02X1833071Y1657866I-5874J0D01*
G01X1763543D01*
G02X1757669Y1663740I0J5874D01*
G01Y1689331D01*
G03X1747795Y1699205I-9874J0D01*
G01X1461575D01*
G03X1451701Y1689331I0J-9874D01*
G01Y1663740D01*
G02X1445827Y1657866I-5874J0D01*
G01X1417087D01*
G02X1411213Y1663740I0J5874D01*
G01Y1689331D01*
G03X1401339Y1699205I-9874J0D01*
G01X1115118D01*
G03X1105244Y1689331I0J-9874D01*
G01Y1663740D01*
G02X1099370Y1657866I-5874J0D01*
G01X1090079D01*
G02X1084205Y1663740I0J5874D01*
G01Y1695110D01*
G03X1074331Y1704984I-9874J0D01*
G01X796693D01*
G03X786819Y1695110I0J-9874D01*
G01Y1663740D01*
G02X780945Y1657866I-5874J0D01*
G01X741575D01*
G02X735701Y1663740I0J5874D01*
G01Y1689331D01*
G03X725827Y1699205I-9874J0D01*
G01X439607D01*
G03X429733Y1689331I0J-9874D01*
G01Y1663740D01*
G02X423859Y1657866I-5874J0D01*
G01X395118D01*
G02X389244Y1663740I0J5874D01*
G01Y1689331D01*
G03X379370Y1699205I-9874J0D01*
G01X93150D01*
G03X83276Y1689331I0J-9874D01*
G01Y1663740D01*
G02X77402Y1657866I-5874J0D01*
G01X7874D01*
G02X2000Y1663740I0J5874D01*
G01Y1813006D01*
G02X7874Y1818880I5874J0D01*
G01X1833071D01*
G37*
%LPD*%
G75*
G36*
G01X607977Y1552080D02*
X555513D01*
G02X555210Y1552383I0J303D01*
G01Y1643194D01*
G02X555513Y1643498I303J1D01*
G01X608266D01*
G02X608570Y1643194I0J-304D01*
G01Y1552672D01*
X607977Y1552080D01*
G37*
G36*
G01X208954Y1643834D02*
G02X209256Y1644136I302J0D01*
G01X261611D01*
G02X261912Y1643834I-1J-302D01*
G01Y1642872D01*
Y1552470D01*
X261722Y1552280D01*
X208952D01*
Y1642872D01*
X208954D01*
Y1643834D01*
G37*
G36*
G01X1232576D02*
G02X1232878Y1644136I302J0D01*
G01X1285233D01*
G02X1285534Y1643834I-1J-302D01*
G01Y1643226D01*
Y1552461D01*
X1285353Y1552280D01*
X1232574D01*
Y1643226D01*
X1232576D01*
Y1643834D01*
G37*
G36*
G01X1579032D02*
G02X1579335Y1644136I303J-1D01*
G01X1631688D01*
G02X1631990Y1643834I0J-302D01*
G01Y1643174D01*
X1631992D01*
Y1552573D01*
X1631698Y1552280D01*
X1579032D01*
Y1643174D01*
Y1643834D01*
G37*
G36*
G01X177763Y1512216D02*
X180583D01*
G02X180786Y1512014I1J-202D01*
G01Y1511392D01*
G03X180836Y1511260I200J0D01*
G02Y1508348I-1664J-1456D01*
G03X180786Y1508216I150J-132D01*
G01Y1506273D01*
G03X180836Y1506141I200J0D01*
G02Y1503229I-1664J-1456D01*
G03X180786Y1503097I150J-132D01*
G01Y1502476D01*
G02X180583Y1502274I-203J1D01*
G01X177763D01*
G02X177560Y1502476I-1J202D01*
G01Y1503097D01*
G03X177510Y1503229I-200J0D01*
G02Y1506141I1664J1456D01*
G03X177560Y1506273I-150J132D01*
G01Y1508216D01*
G03X177510Y1508348I-200J0D01*
G02Y1511260I1664J1456D01*
G03X177560Y1511392I-150J132D01*
G01Y1512014D01*
G02X177763Y1512216I203J-1D01*
G37*
G36*
G01X350991D02*
X353811D01*
G02X354014Y1512014I1J-202D01*
G01Y1511392D01*
G03X354064Y1511260I200J0D01*
G02Y1508348I-1664J-1456D01*
G03X354014Y1508216I150J-132D01*
G01Y1506273D01*
G03X354064Y1506141I200J0D01*
G02Y1503229I-1664J-1456D01*
G03X354014Y1503097I150J-132D01*
G01Y1502476D01*
G02X353811Y1502274I-203J1D01*
G01X350991D01*
G02X350788Y1502476I-1J202D01*
G01Y1503097D01*
G03X350738Y1503229I-200J0D01*
G02Y1506141I1664J1456D01*
G03X350788Y1506273I-150J132D01*
G01Y1508216D01*
G03X350738Y1508348I-200J0D01*
G02Y1511260I1664J1456D01*
G03X350788Y1511392I-150J132D01*
G01Y1512014D01*
G02X350991Y1512216I203J-1D01*
G37*
G36*
G01X186425Y1516546D02*
X189245D01*
G02X189448Y1516344I1J-202D01*
G01Y1515722D01*
G03X189498Y1515590I200J0D01*
G02Y1512678I-1664J-1456D01*
G03X189448Y1512546I150J-132D01*
G01Y1510604D01*
G03X189498Y1510472I200J0D01*
G02Y1507560I-1664J-1456D01*
G03X189448Y1507428I150J-132D01*
G01Y1506806D01*
G02X189245Y1506604I-203J1D01*
G01X186425D01*
G02X186222Y1506806I-1J202D01*
G01Y1507428D01*
G03X186172Y1507560I-200J0D01*
G02Y1510472I1664J1456D01*
G03X186222Y1510604I-150J132D01*
G01Y1512546D01*
G03X186172Y1512678I-200J0D01*
G02Y1515590I1664J1456D01*
G03X186222Y1515722I-150J132D01*
G01Y1516344D01*
G02X186425Y1516546I203J-1D01*
G37*
G36*
G01X359653D02*
X362473D01*
G02X362676Y1516344I1J-202D01*
G01Y1515722D01*
G03X362726Y1515590I200J0D01*
G02Y1512678I-1664J-1456D01*
G03X362676Y1512546I150J-132D01*
G01Y1510604D01*
G03X362726Y1510472I200J0D01*
G02Y1507560I-1664J-1456D01*
G03X362676Y1507428I150J-132D01*
G01Y1506806D01*
G02X362473Y1506604I-203J1D01*
G01X359653D01*
G02X359450Y1506806I-1J202D01*
G01Y1507428D01*
G03X359400Y1507560I-200J0D01*
G02Y1510472I1664J1456D01*
G03X359450Y1510604I-150J132D01*
G01Y1512546D01*
G03X359400Y1512678I-200J0D01*
G02Y1515590I1664J1456D01*
G03X359450Y1515722I-150J132D01*
G01Y1516344D01*
G02X359653Y1516546I203J-1D01*
G37*
G36*
G01X177763Y1568516D02*
X180583D01*
G02X180786Y1568313I0J-203D01*
G01Y1567691D01*
G03X180836Y1567559I200J0D01*
G02Y1564647I-1664J-1456D01*
G03X180786Y1564515I150J-132D01*
G01Y1562573D01*
G03X180836Y1562441I200J0D01*
G02Y1559529I-1664J-1456D01*
G03X180786Y1559397I150J-132D01*
G01Y1558775D01*
G02X180583Y1558572I-203J0D01*
G01X177763D01*
G02X177560Y1558775I0J203D01*
G01Y1559397D01*
G03X177510Y1559529I-200J0D01*
G02Y1562441I1664J1456D01*
G03X177560Y1562573I-150J132D01*
G01Y1564515D01*
G03X177510Y1564647I-200J0D01*
G02Y1567559I1664J1456D01*
G03X177560Y1567691I-150J132D01*
G01Y1568313D01*
G02X177763Y1568516I203J0D01*
G37*
G36*
G01X350991D02*
X353811D01*
G02X354014Y1568313I0J-203D01*
G01Y1567691D01*
G03X354064Y1567559I200J0D01*
G02Y1564647I-1664J-1456D01*
G03X354014Y1564515I150J-132D01*
G01Y1562573D01*
G03X354064Y1562441I200J0D01*
G02Y1559529I-1664J-1456D01*
G03X354014Y1559397I150J-132D01*
G01Y1558775D01*
G02X353811Y1558572I-203J0D01*
G01X350991D01*
G02X350788Y1558775I0J203D01*
G01Y1559397D01*
G03X350738Y1559529I-200J0D01*
G02Y1562441I1664J1456D01*
G03X350788Y1562573I-150J132D01*
G01Y1564515D01*
G03X350738Y1564647I-200J0D01*
G02Y1567559I1664J1456D01*
G03X350788Y1567691I-150J132D01*
G01Y1568313D01*
G02X350991Y1568516I203J0D01*
G37*
G36*
G01X186425Y1572846D02*
X189245D01*
G02X189448Y1572644I1J-202D01*
G01Y1572022D01*
G03X189498Y1571890I200J0D01*
G02Y1568978I-1664J-1456D01*
G03X189448Y1568846I150J-132D01*
G01Y1566903D01*
G03X189498Y1566771I200J0D01*
G02Y1563859I-1664J-1456D01*
G03X189448Y1563727I150J-132D01*
G01Y1563106D01*
G02X189245Y1562904I-203J1D01*
G01X186425D01*
G02X186222Y1563106I-1J202D01*
G01Y1563727D01*
G03X186172Y1563859I-200J0D01*
G02Y1566771I1664J1456D01*
G03X186222Y1566903I-150J132D01*
G01Y1568846D01*
G03X186172Y1568978I-200J0D01*
G02Y1571890I1664J1456D01*
G03X186222Y1572022I-150J132D01*
G01Y1572644D01*
G02X186425Y1572846I203J-1D01*
G37*
G36*
G01X359653D02*
X362473D01*
G02X362676Y1572644I1J-202D01*
G01Y1572022D01*
G03X362726Y1571890I200J0D01*
G02Y1568978I-1664J-1456D01*
G03X362676Y1568846I150J-132D01*
G01Y1566903D01*
G03X362726Y1566771I200J0D01*
G02Y1563859I-1664J-1456D01*
G03X362676Y1563727I150J-132D01*
G01Y1563106D01*
G02X362473Y1562904I-203J1D01*
G01X359653D01*
G02X359450Y1563106I-1J202D01*
G01Y1563727D01*
G03X359400Y1563859I-200J0D01*
G02Y1566771I1664J1456D01*
G03X359450Y1566903I-150J132D01*
G01Y1568846D01*
G03X359400Y1568978I-200J0D01*
G02Y1571890I1664J1456D01*
G03X359450Y1572022I-150J132D01*
G01Y1572644D01*
G02X359653Y1572846I203J-1D01*
G37*
G36*
G01X177763Y1583870D02*
X180583D01*
G02X180786Y1583667I0J-203D01*
G01Y1583045D01*
G03X180836Y1582913I200J0D01*
G02Y1580001I-1664J-1456D01*
G03X180786Y1579869I150J-132D01*
G01Y1577927D01*
G03X180836Y1577795I200J0D01*
G02Y1574883I-1664J-1456D01*
G03X180786Y1574751I150J-132D01*
G01Y1574129D01*
G02X180583Y1573926I-203J0D01*
G01X177763D01*
G02X177560Y1574129I0J203D01*
G01Y1574751D01*
G03X177510Y1574883I-200J0D01*
G02Y1577795I1664J1456D01*
G03X177560Y1577927I-150J132D01*
G01Y1579869D01*
G03X177510Y1580001I-200J0D01*
G02Y1582913I1664J1456D01*
G03X177560Y1583045I-150J132D01*
G01Y1583667D01*
G02X177763Y1583870I203J0D01*
G37*
G36*
G01X956709Y1489429D02*
X1046333D01*
G02X1047217Y1489063I0J-1251D01*
G01X1048852Y1487428D01*
G02X1049218Y1486544I-885J-884D01*
G01Y1451702D01*
G02X1048852Y1450818I-1251J0D01*
G01X1046676Y1448642D01*
G02X1045792Y1448276I-884J885D01*
G01X929991D01*
G02X929107Y1448642I0J1251D01*
G01X927428Y1450321D01*
G02X927062Y1451205I885J884D01*
G01Y1481492D01*
G02X927428Y1482376I1251J0D01*
G01X929075Y1484023D01*
G02X929959Y1484389I884J-885D01*
G01X952618D01*
G03X952760Y1484448I0J200D01*
G01X953133Y1484821D01*
G03X953192Y1484963I-141J142D01*
G01Y1485912D01*
G02X953558Y1486796I1251J0D01*
G01X955825Y1489063D01*
G02X956709Y1489429I884J-885D01*
G37*
G36*
G01X404759Y1350874D02*
X408159D01*
G02Y1347270I0J-1802D01*
G01X404759D01*
G02Y1350874I0J1802D01*
G37*
G36*
G01X402489Y1419078D02*
X405889D01*
G02Y1415472I0J-1803D01*
G01X402489D01*
G02Y1419078I0J1803D01*
G37*
G36*
G01X1443660Y1308896D02*
X1440260D01*
G02Y1312500I0J1802D01*
G01X1443660D01*
G02Y1308896I0J-1802D01*
G37*
G36*
G01X970197Y665850D02*
X966797D01*
G02Y669456I0J1803D01*
G01X970197D01*
G02Y665850I0J-1803D01*
G37*
G36*
G01X501495Y772260D02*
X504895D01*
G02Y768654I0J-1803D01*
G01X501495D01*
G02Y772260I0J1803D01*
G37*
G36*
G01X909508Y623418D02*
X912908D01*
G02Y619814I0J-1802D01*
G01X909508D01*
G02Y623418I0J1802D01*
G37*
G36*
G01X900676Y623338D02*
X904076D01*
G02Y619734I0J-1802D01*
G01X900676D01*
G02Y623338I0J1802D01*
G37*
G36*
G01X526264Y665858D02*
X529664D01*
G02Y662254I0J-1802D01*
G01X526264D01*
G02Y665858I0J1802D01*
G37*
G36*
G01X534264Y663358D02*
X537664D01*
G02Y659754I0J-1802D01*
G01X534264D01*
G02Y663358I0J1802D01*
G37*
G36*
G01X538985Y734790D02*
X535585D01*
G02Y738396I0J1803D01*
G01X538985D01*
G02Y734790I0J-1803D01*
G37*
G36*
G01X530985Y739790D02*
X527585D01*
G02Y743396I0J1803D01*
G01X530985D01*
G02Y739790I0J-1803D01*
G37*
G36*
G01X517731Y742874D02*
X521131D01*
G02Y739268I0J-1803D01*
G01X517731D01*
G02Y742874I0J1803D01*
G37*
G36*
G01X511724Y739232D02*
X508324D01*
G02Y742838I0J1803D01*
G01X511724D01*
G02Y739232I0J-1803D01*
G37*
G36*
G01X415777Y306272D02*
X419177D01*
G02Y302668I0J-1802D01*
G01X415777D01*
G02Y306272I0J1802D01*
G37*
G36*
G01X423651Y309272D02*
X427051D01*
G02Y305668I0J-1802D01*
G01X423651D01*
G02Y309272I0J1802D01*
G37*
G36*
G01X431525Y306272D02*
X434925D01*
G02Y302668I0J-1802D01*
G01X431525D01*
G02Y306272I0J1802D01*
G37*
G36*
G01X434924Y368506D02*
X431524D01*
G02Y372112I0J1803D01*
G01X434924D01*
G02Y368506I0J-1803D01*
G37*
G36*
G01X26772Y1559218D02*
X20472D01*
G02Y1575428I0J8105D01*
G01X26772D01*
G02Y1559218I0J-8105D01*
G37*
G36*
G01X216125Y1441832D02*
X219525D01*
G02Y1438226I0J-1803D01*
G01X216125D01*
G02Y1441832I0J1803D01*
G37*
G36*
G01X413753Y1518690D02*
X417153D01*
G02Y1515084I0J-1803D01*
G01X413753D01*
G02Y1518690I0J1803D01*
G37*
G36*
G01X417334Y1475298D02*
X413934D01*
G02Y1478902I0J1802D01*
G01X417334D01*
G02Y1475298I0J-1802D01*
G37*
G36*
G01X919628Y334530D02*
X916228D01*
G02Y338136I0J1803D01*
G01X919628D01*
G02Y334530I0J-1803D01*
G37*
G36*
G01X905899Y304150D02*
X909299D01*
G02Y300544I0J-1803D01*
G01X905899D01*
G02Y304150I0J1803D01*
G37*
G36*
G01X1033891Y298096D02*
X1037291D01*
G02Y294490I0J-1803D01*
G01X1033891D01*
G02Y298096I0J1803D01*
G37*
G36*
G01X1318363Y312364D02*
X1321763D01*
G02Y308760I0J-1802D01*
G01X1318363D01*
G02Y312364I0J1802D01*
G37*
G36*
G01X1337508Y371598D02*
X1334108D01*
G02Y375204I0J1803D01*
G01X1337508D01*
G02Y371598I0J-1803D01*
G37*
G36*
G01X1326237Y309364D02*
X1329637D01*
G02Y305760I0J-1802D01*
G01X1326237D01*
G02Y309364I0J1802D01*
G37*
G36*
G01X1334111Y312364D02*
X1337511D01*
G02Y308760I0J-1802D01*
G01X1334111D01*
G02Y312364I0J1802D01*
G37*
G36*
G01X1518207Y1176748D02*
X1514467D01*
G02Y1179354I0J1303D01*
G01X1518207D01*
G02Y1176748I0J-1303D01*
G37*
G36*
G01Y1169268D02*
X1514467D01*
G02Y1171872I0J1302D01*
G01X1518207D01*
G02Y1169268I0J-1302D01*
G37*
G36*
G01X1513926Y907148D02*
X1510526D01*
G02Y910754I0J1803D01*
G01X1513926D01*
G02Y907148I0J-1803D01*
G37*
G36*
G01X1531299Y1174878D02*
X1527559D01*
G02Y1177482I0J1302D01*
G01X1531299D01*
G02Y1174878I0J-1302D01*
G37*
G36*
G01X146947Y1176748D02*
X143207D01*
G02Y1179354I0J1303D01*
G01X146947D01*
G02Y1176748I0J-1303D01*
G37*
G36*
G01Y1169268D02*
X143207D01*
G02Y1171872I0J1302D01*
G01X146947D01*
G02Y1169268I0J-1302D01*
G37*
G36*
G01X160039Y1174878D02*
X156299D01*
G02Y1177482I0J1302D01*
G01X160039D01*
G02Y1174878I0J-1302D01*
G37*
G36*
G01X604034Y1176748D02*
X600294D01*
G02Y1179354I0J1303D01*
G01X604034D01*
G02Y1176748I0J-1303D01*
G37*
G36*
G01Y1169268D02*
X600294D01*
G02Y1171872I0J1302D01*
G01X604034D01*
G02Y1169268I0J-1302D01*
G37*
G36*
G01X605733Y942940D02*
X609133D01*
G02Y939336I0J-1802D01*
G01X605733D01*
G02Y942940I0J1802D01*
G37*
G36*
G01X615256Y1176748D02*
X611516D01*
G02Y1179354I0J1303D01*
G01X615256D01*
G02Y1176748I0J-1303D01*
G37*
G36*
G01X1061120D02*
X1057380D01*
G02Y1179354I0J1303D01*
G01X1061120D01*
G02Y1176748I0J-1303D01*
G37*
G36*
G01Y1169268D02*
X1057380D01*
G02Y1171872I0J1302D01*
G01X1061120D01*
G02Y1169268I0J-1302D01*
G37*
G36*
G01X1769063Y921922D02*
X1765663D01*
G02Y925526I0J1802D01*
G01X1769063D01*
G02Y921922I0J-1802D01*
G37*
G36*
G01X1072342Y1176748D02*
X1068602D01*
G02Y1179354I0J1303D01*
G01X1072342D01*
G02Y1176748I0J-1303D01*
G37*
G36*
G01X647411Y379065D02*
X647412D01*
G02Y370659I0J-4203D01*
G01X647411D01*
G02Y379065I0J4203D01*
G37*
G36*
G01X815062Y1622338D02*
X821185Y1628461D01*
G02X822069Y1628827I884J-885D01*
G01X928166D01*
G02X929050Y1628461I0J-1251D01*
G01X934307Y1623204D01*
G02X934673Y1622320I-885J-884D01*
G01Y1586606D01*
G03X934732Y1586464I200J0D01*
G01X941369Y1579827D01*
G03X941511Y1579768I142J141D01*
G01X956943D01*
G02X957827Y1579402I0J-1251D01*
G01X962023Y1575206D01*
G02X962389Y1574322I-885J-884D01*
G01Y1544281D01*
G03X962448Y1544139I200J0D01*
G01X965638Y1540949D01*
G03X965780Y1540890I142J141D01*
G01X1020507D01*
G02X1021391Y1540524I0J-1251D01*
G01X1033708Y1528207D01*
G02X1034074Y1527323I-885J-884D01*
G01Y1492303D01*
G02X1033708Y1491419I-1251J0D01*
G01X1032711Y1490422D01*
G02X1031827Y1490056I-884J885D01*
G01X946582D01*
G02X945698Y1490422I0J1251D01*
G01X943533Y1492587D01*
G03X943391Y1492646I-142J-141D01*
G01X934180D01*
G03X934038Y1492587I0J-200D01*
G01X919334Y1477883D01*
G03X919275Y1477741I141J-142D01*
G01Y1464419D01*
G02X918909Y1463535I-1251J0D01*
G01X916381Y1461007D01*
G03X916322Y1460865I141J-142D01*
G01Y1460327D01*
G02X915956Y1459443I-1251J0D01*
G01X915720Y1459207D01*
G03X915661Y1459065I141J-142D01*
G01Y1445847D01*
G02X915295Y1444963I-1251J0D01*
G01X914298Y1443966D01*
G02X913414Y1443600I-884J885D01*
G01X899958D01*
G02X899074Y1443966I0J1251D01*
G01X898077Y1444963D01*
G02X897711Y1445847I885J884D01*
G01Y1459039D01*
G03X897652Y1459181I-200J0D01*
G01X897339Y1459494D01*
G02X896973Y1460378I885J884D01*
G01Y1461423D01*
G03X896914Y1461565I-200J0D01*
G01X892210Y1466269D01*
G02X891844Y1467153I885J884D01*
G01Y1472495D01*
G03X891785Y1472637I-200J0D01*
G01X887610Y1476812D01*
G03X887468Y1476871I-142J-141D01*
G01X881105D01*
G03X880963Y1476812I0J-200D01*
G01X874458Y1470307D01*
G03X874399Y1470165I141J-142D01*
G01Y1460390D01*
G02X874033Y1459506I-1251J0D01*
G01X873695Y1459168D01*
G03X873636Y1459026I141J-142D01*
G01Y1445822D01*
G02X873270Y1444938I-1251J0D01*
G01X872311Y1443979D01*
G02X871427Y1443613I-884J885D01*
G01X858101D01*
G02X857217Y1443979I0J1251D01*
G01X855946Y1445250D01*
G02X855580Y1446134I885J884D01*
G01Y1458923D01*
G03X855521Y1459065I-200J0D01*
G01X852317Y1462269D01*
G03X852175Y1462328I-142J-141D01*
G01X829373D01*
G03X829173Y1462128I0J-200D01*
G01Y1461246D01*
G02X828807Y1460362I-1251J0D01*
G01X827914Y1459469D01*
G02X827030Y1459103I-884J885D01*
G01X825637D01*
G03X825495Y1459044I0J-200D01*
G01X822876Y1456425D01*
G02X821992Y1456059I-884J885D01*
G01X821694D01*
G03X821494Y1455859I0J-200D01*
G01Y1445861D01*
G02X821128Y1444977I-1251J0D01*
G01X820169Y1444018D01*
G02X819285Y1443652I-884J885D01*
G01X805792D01*
G02X804908Y1444018I0J1251D01*
G01X803870Y1445056D01*
G02X803504Y1445940I885J884D01*
G01Y1460429D01*
G02X803870Y1461313I1251J0D01*
G01X804002Y1461445D01*
G03X804061Y1461587I-141J142D01*
G01Y1474910D01*
G02X804396Y1475762I1251J0D01*
G03X804450Y1475898I-146J137D01*
G01Y1487743D01*
X804385Y1487842D01*
X804329Y1487866D01*
G02Y1490628I590J1381D01*
G01X804385Y1490652D01*
X804450Y1490751D01*
Y1524316D01*
G02X804816Y1525200I1251J0D01*
G01X814637Y1535021D01*
G03X814696Y1535163I-141J142D01*
G01Y1621454D01*
G02X815062Y1622338I1251J0D01*
G37*
G36*
G01X111494Y1456412D02*
G02X111292Y1456210I-202J0D01*
G01X108472D01*
G02X108270Y1456413I1J203D01*
G01Y1457032D01*
G03X108220Y1457164I-200J0D01*
G02Y1460080I1661J1458D01*
G03X108270Y1460212I-150J132D01*
G01Y1462151D01*
G03X108220Y1462283I-200J0D01*
G02Y1465199I1661J1458D01*
G03X108270Y1465331I-150J132D01*
G01Y1465952D01*
G02X108472Y1466154I202J0D01*
G01X111292D01*
G02X111494Y1465951I-1J-203D01*
G01Y1465331D01*
G03X111544Y1465199I200J0D01*
G02Y1462283I-1661J-1458D01*
G03X111494Y1462151I150J-132D01*
G01Y1460212D01*
G03X111544Y1460080I200J0D01*
G02Y1457164I-1661J-1458D01*
G03X111494Y1457032I150J-132D01*
G01Y1456412D01*
G37*
G36*
G01X319368D02*
G02X319166Y1456210I-202J0D01*
G01X316346D01*
G02X316144Y1456413I1J203D01*
G01Y1457032D01*
G03X316094Y1457164I-200J0D01*
G02Y1460080I1661J1458D01*
G03X316144Y1460212I-150J132D01*
G01Y1462151D01*
G03X316094Y1462283I-200J0D01*
G02Y1465199I1661J1458D01*
G03X316144Y1465331I-150J132D01*
G01Y1465952D01*
G02X316346Y1466154I202J0D01*
G01X319166D01*
G02X319368Y1465951I-1J-203D01*
G01Y1465331D01*
G03X319418Y1465199I200J0D01*
G02Y1462283I-1661J-1458D01*
G03X319368Y1462151I150J-132D01*
G01Y1460212D01*
G03X319418Y1460080I200J0D01*
G02Y1457164I-1661J-1458D01*
G03X319368Y1457032I150J-132D01*
G01Y1456412D01*
G37*
G36*
G01X336690D02*
G02X336488Y1456210I-202J0D01*
G01X333668D01*
G02X333466Y1456413I1J203D01*
G01Y1457032D01*
G03X333416Y1457164I-200J0D01*
G02Y1460080I1661J1458D01*
G03X333466Y1460212I-150J132D01*
G01Y1462151D01*
G03X333416Y1462283I-200J0D01*
G02Y1465199I1661J1458D01*
G03X333466Y1465331I-150J132D01*
G01Y1465952D01*
G02X333668Y1466154I202J0D01*
G01X336488D01*
G02X336690Y1465951I-1J-203D01*
G01Y1465331D01*
G03X336740Y1465199I200J0D01*
G02Y1462283I-1661J-1458D01*
G03X336690Y1462151I150J-132D01*
G01Y1460212D01*
G03X336740Y1460080I200J0D01*
G02Y1457164I-1661J-1458D01*
G03X336690Y1457032I150J-132D01*
G01Y1456412D01*
G37*
G36*
G01X628157Y1466154D02*
X630977D01*
G02X631180Y1465951I0J-203D01*
G01Y1465329D01*
G03X631230Y1465197I200J0D01*
G02Y1462285I-1664J-1456D01*
G03X631180Y1462153I150J-132D01*
G01Y1460210D01*
G03X631230Y1460078I200J0D01*
G02Y1457166I-1664J-1456D01*
G03X631180Y1457034I150J-132D01*
G01Y1456413D01*
G02X630977Y1456210I-203J0D01*
G01X628157D01*
G02X627954Y1456413I0J203D01*
G01Y1457034D01*
G03X627904Y1457166I-200J0D01*
G02Y1460078I1664J1456D01*
G03X627954Y1460210I-150J132D01*
G01Y1462153D01*
G03X627904Y1462285I-200J0D01*
G02Y1465197I1664J1456D01*
G03X627954Y1465329I-150J132D01*
G01Y1465951D01*
G02X628157Y1466154I203J0D01*
G37*
G36*
G01X1133462Y1456412D02*
G02X1133260Y1456210I-202J0D01*
G01X1130440D01*
G02X1130238Y1456413I1J203D01*
G01Y1457032D01*
G03X1130188Y1457164I-200J0D01*
G02Y1460080I1661J1458D01*
G03X1130238Y1460212I-150J132D01*
G01Y1462151D01*
G03X1130188Y1462283I-200J0D01*
G02Y1465199I1661J1458D01*
G03X1130238Y1465331I-150J132D01*
G01Y1465952D01*
G02X1130440Y1466154I202J0D01*
G01X1133260D01*
G02X1133462Y1465951I-1J-203D01*
G01Y1465331D01*
G03X1133512Y1465199I200J0D01*
G02Y1462283I-1661J-1458D01*
G03X1133462Y1462151I150J-132D01*
G01Y1460212D01*
G03X1133512Y1460080I200J0D01*
G02Y1457164I-1661J-1458D01*
G03X1133462Y1457032I150J-132D01*
G01Y1456412D01*
G37*
G36*
G01X1147763Y1466154D02*
X1150583D01*
G02X1150786Y1465951I0J-203D01*
G01Y1465329D01*
G03X1150836Y1465197I200J0D01*
G02Y1462285I-1664J-1456D01*
G03X1150786Y1462153I150J-132D01*
G01Y1460210D01*
G03X1150836Y1460078I200J0D01*
G02Y1457166I-1664J-1456D01*
G03X1150786Y1457034I150J-132D01*
G01Y1456413D01*
G02X1150583Y1456210I-203J0D01*
G01X1147763D01*
G02X1147560Y1456413I0J203D01*
G01Y1457034D01*
G03X1147510Y1457166I-200J0D01*
G02Y1460078I1664J1456D01*
G03X1147560Y1460210I-150J132D01*
G01Y1462153D01*
G03X1147510Y1462285I-200J0D01*
G02Y1465197I1664J1456D01*
G03X1147560Y1465329I-150J132D01*
G01Y1465951D01*
G02X1147763Y1466154I203J0D01*
G37*
G36*
G01X1650125D02*
X1652945D01*
G02X1653148Y1465951I0J-203D01*
G01Y1465329D01*
G03X1653198Y1465197I200J0D01*
G02Y1462285I-1664J-1456D01*
G03X1653148Y1462153I150J-132D01*
G01Y1460210D01*
G03X1653198Y1460078I200J0D01*
G02Y1457166I-1664J-1456D01*
G03X1653148Y1457034I150J-132D01*
G01Y1456413D01*
G02X1652945Y1456210I-203J0D01*
G01X1650125D01*
G02X1649922Y1456413I0J203D01*
G01Y1457034D01*
G03X1649872Y1457166I-200J0D01*
G02Y1460078I1664J1456D01*
G03X1649922Y1460210I-150J132D01*
G01Y1462153D01*
G03X1649872Y1462285I-200J0D01*
G02Y1465197I1664J1456D01*
G03X1649922Y1465329I-150J132D01*
G01Y1465951D01*
G02X1650125Y1466154I203J0D01*
G37*
G36*
G01X1670470Y1456412D02*
G02X1670268Y1456210I-202J0D01*
G01X1667448D01*
G02X1667246Y1456413I1J203D01*
G01Y1457032D01*
G03X1667196Y1457164I-200J0D01*
G02Y1460080I1661J1458D01*
G03X1667246Y1460212I-150J132D01*
G01Y1462151D01*
G03X1667196Y1462283I-200J0D01*
G02Y1465199I1661J1458D01*
G03X1667246Y1465331I-150J132D01*
G01Y1465952D01*
G02X1667448Y1466154I202J0D01*
G01X1670268D01*
G02X1670470Y1465951I-1J-203D01*
G01Y1465331D01*
G03X1670520Y1465199I200J0D01*
G02Y1462283I-1661J-1458D01*
G03X1670470Y1462151I150J-132D01*
G01Y1460212D01*
G03X1670520Y1460080I200J0D01*
G02Y1457164I-1661J-1458D01*
G03X1670470Y1457032I150J-132D01*
G01Y1456412D01*
G37*
G36*
G01X117133Y1470484D02*
X119953D01*
G02X120156Y1470281I0J-203D01*
G01Y1469659D01*
G03X120206Y1469527I200J0D01*
G02Y1466615I-1664J-1456D01*
G03X120156Y1466483I150J-132D01*
G01Y1464541D01*
G03X120206Y1464409I200J0D01*
G02Y1461497I-1664J-1456D01*
G03X120156Y1461365I150J-132D01*
G01Y1460743D01*
G02X119953Y1460540I-203J0D01*
G01X117133D01*
G02X116930Y1460743I0J203D01*
G01Y1461365D01*
G03X116880Y1461497I-200J0D01*
G02Y1464409I1664J1456D01*
G03X116930Y1464541I-150J132D01*
G01Y1466483D01*
G03X116880Y1466615I-200J0D01*
G02Y1469527I1664J1456D01*
G03X116930Y1469659I-150J132D01*
G01Y1470281D01*
G02X117133Y1470484I203J0D01*
G37*
G36*
G01X310706Y1460742D02*
G02X310504Y1460540I-202J0D01*
G01X307684D01*
G02X307482Y1460743I1J203D01*
G01Y1461363D01*
G03X307432Y1461495I-200J0D01*
G02Y1464411I1661J1458D01*
G03X307482Y1464543I-150J132D01*
G01Y1466481D01*
G03X307432Y1466613I-200J0D01*
G02Y1469529I1661J1458D01*
G03X307482Y1469661I-150J132D01*
G01Y1470282D01*
G02X307684Y1470484I202J0D01*
G01X310504D01*
G02X310706Y1470281I-1J-203D01*
G01Y1469661D01*
G03X310756Y1469529I200J0D01*
G02Y1466613I-1661J-1458D01*
G03X310706Y1466481I150J-132D01*
G01Y1464543D01*
G03X310756Y1464411I200J0D01*
G02Y1461495I-1661J-1458D01*
G03X310706Y1461363I150J-132D01*
G01Y1460742D01*
G37*
G36*
G01X325007Y1470484D02*
X327827D01*
G02X328030Y1470281I0J-203D01*
G01Y1469659D01*
G03X328080Y1469527I200J0D01*
G02Y1466615I-1664J-1456D01*
G03X328030Y1466483I150J-132D01*
G01Y1464541D01*
G03X328080Y1464409I200J0D01*
G02Y1461497I-1664J-1456D01*
G03X328030Y1461365I150J-132D01*
G01Y1460743D01*
G02X327827Y1460540I-203J0D01*
G01X325007D01*
G02X324804Y1460743I0J203D01*
G01Y1461365D01*
G03X324754Y1461497I-200J0D01*
G02Y1464409I1664J1456D01*
G03X324804Y1464541I-150J132D01*
G01Y1466483D01*
G03X324754Y1466615I-200J0D01*
G02Y1469527I1664J1456D01*
G03X324804Y1469659I-150J132D01*
G01Y1470281D01*
G02X325007Y1470484I203J0D01*
G37*
G36*
G01X345352Y1460742D02*
G02X345150Y1460540I-202J0D01*
G01X342330D01*
G02X342128Y1460743I1J203D01*
G01Y1461363D01*
G03X342078Y1461495I-200J0D01*
G02Y1464411I1661J1458D01*
G03X342128Y1464543I-150J132D01*
G01Y1466481D01*
G03X342078Y1466613I-200J0D01*
G02Y1469529I1661J1458D01*
G03X342128Y1469661I-150J132D01*
G01Y1470282D01*
G02X342330Y1470484I202J0D01*
G01X345150D01*
G02X345352Y1470281I-1J-203D01*
G01Y1469661D01*
G03X345402Y1469529I200J0D01*
G02Y1466613I-1661J-1458D01*
G03X345352Y1466481I150J-132D01*
G01Y1464543D01*
G03X345402Y1464411I200J0D01*
G02Y1461495I-1661J-1458D01*
G03X345352Y1461363I150J-132D01*
G01Y1460742D01*
G37*
G36*
G01X639840D02*
G02X639638Y1460540I-202J0D01*
G01X636818D01*
G02X636616Y1460743I1J203D01*
G01Y1461363D01*
G03X636566Y1461495I-200J0D01*
G02Y1464411I1661J1458D01*
G03X636616Y1464543I-150J132D01*
G01Y1466481D01*
G03X636566Y1466613I-200J0D01*
G02Y1469529I1661J1458D01*
G03X636616Y1469661I-150J132D01*
G01Y1470282D01*
G02X636818Y1470484I202J0D01*
G01X639638D01*
G02X639840Y1470281I-1J-203D01*
G01Y1469661D01*
G03X639890Y1469529I200J0D01*
G02Y1466613I-1661J-1458D01*
G03X639840Y1466481I150J-132D01*
G01Y1464543D01*
G03X639890Y1464411I200J0D01*
G02Y1461495I-1661J-1458D01*
G03X639840Y1461363I150J-132D01*
G01Y1460742D01*
G37*
G36*
G01X1139101Y1470484D02*
X1141921D01*
G02X1142124Y1470281I0J-203D01*
G01Y1469659D01*
G03X1142174Y1469527I200J0D01*
G02Y1466615I-1664J-1456D01*
G03X1142124Y1466483I150J-132D01*
G01Y1464541D01*
G03X1142174Y1464409I200J0D01*
G02Y1461497I-1664J-1456D01*
G03X1142124Y1461365I150J-132D01*
G01Y1460743D01*
G02X1141921Y1460540I-203J0D01*
G01X1139101D01*
G02X1138898Y1460743I0J203D01*
G01Y1461365D01*
G03X1138848Y1461497I-200J0D01*
G02Y1464409I1664J1456D01*
G03X1138898Y1464541I-150J132D01*
G01Y1466483D01*
G03X1138848Y1466615I-200J0D01*
G02Y1469527I1664J1456D01*
G03X1138898Y1469659I-150J132D01*
G01Y1470281D01*
G02X1139101Y1470484I203J0D01*
G37*
G36*
G01X1159446Y1460742D02*
G02X1159244Y1460540I-202J0D01*
G01X1156424D01*
G02X1156222Y1460743I1J203D01*
G01Y1461363D01*
G03X1156172Y1461495I-200J0D01*
G02Y1464411I1661J1458D01*
G03X1156222Y1464543I-150J132D01*
G01Y1466481D01*
G03X1156172Y1466613I-200J0D01*
G02Y1469529I1661J1458D01*
G03X1156222Y1469661I-150J132D01*
G01Y1470282D01*
G02X1156424Y1470484I202J0D01*
G01X1159244D01*
G02X1159446Y1470281I-1J-203D01*
G01Y1469661D01*
G03X1159496Y1469529I200J0D01*
G02Y1466613I-1661J-1458D01*
G03X1159446Y1466481I150J-132D01*
G01Y1464543D01*
G03X1159496Y1464411I200J0D01*
G02Y1461495I-1661J-1458D01*
G03X1159446Y1461363I150J-132D01*
G01Y1460742D01*
G37*
G36*
G01X1661808D02*
G02X1661606Y1460540I-202J0D01*
G01X1658786D01*
G02X1658584Y1460743I1J203D01*
G01Y1461363D01*
G03X1658534Y1461495I-200J0D01*
G02Y1464411I1661J1458D01*
G03X1658584Y1464543I-150J132D01*
G01Y1466481D01*
G03X1658534Y1466613I-200J0D01*
G02Y1469529I1661J1458D01*
G03X1658584Y1469661I-150J132D01*
G01Y1470282D01*
G02X1658786Y1470484I202J0D01*
G01X1661606D01*
G02X1661808Y1470281I-1J-203D01*
G01Y1469661D01*
G03X1661858Y1469529I200J0D01*
G02Y1466613I-1661J-1458D01*
G03X1661808Y1466481I150J-132D01*
G01Y1464543D01*
G03X1661858Y1464411I200J0D01*
G02Y1461495I-1661J-1458D01*
G03X1661808Y1461363I150J-132D01*
G01Y1460742D01*
G37*
G36*
G01X1676109Y1470484D02*
X1678929D01*
G02X1679132Y1470281I0J-203D01*
G01Y1469659D01*
G03X1679182Y1469527I200J0D01*
G02Y1466615I-1664J-1456D01*
G03X1679132Y1466483I150J-132D01*
G01Y1464541D01*
G03X1679182Y1464409I200J0D01*
G02Y1461497I-1664J-1456D01*
G03X1679132Y1461365I150J-132D01*
G01Y1460743D01*
G02X1678929Y1460540I-203J0D01*
G01X1676109D01*
G02X1675906Y1460743I0J203D01*
G01Y1461365D01*
G03X1675856Y1461497I-200J0D01*
G02Y1464409I1664J1456D01*
G03X1675906Y1464541I-150J132D01*
G01Y1466483D01*
G03X1675856Y1466615I-200J0D01*
G02Y1469527I1664J1456D01*
G03X1675906Y1469659I-150J132D01*
G01Y1470281D01*
G02X1676109Y1470484I203J0D01*
G37*
G36*
G01X111494Y1471766D02*
G02X111292Y1471564I-202J0D01*
G01X108472D01*
G02X108270Y1471767I1J203D01*
G01Y1472387D01*
G03X108220Y1472519I-200J0D01*
G02Y1475435I1661J1458D01*
G03X108270Y1475567I-150J132D01*
G01Y1477505D01*
G03X108220Y1477637I-200J0D01*
G02Y1480553I1661J1458D01*
G03X108270Y1480685I-150J132D01*
G01Y1481306D01*
G02X108472Y1481508I202J0D01*
G01X111292D01*
G02X111494Y1481305I-1J-203D01*
G01Y1480685D01*
G03X111544Y1480553I200J0D01*
G02Y1477637I-1661J-1458D01*
G03X111494Y1477505I150J-132D01*
G01Y1475567D01*
G03X111544Y1475435I200J0D01*
G02Y1472519I-1661J-1458D01*
G03X111494Y1472387I150J-132D01*
G01Y1471766D01*
G37*
G36*
G01X319368D02*
G02X319166Y1471564I-202J0D01*
G01X316346D01*
G02X316144Y1471767I1J203D01*
G01Y1472387D01*
G03X316094Y1472519I-200J0D01*
G02Y1475435I1661J1458D01*
G03X316144Y1475567I-150J132D01*
G01Y1477505D01*
G03X316094Y1477637I-200J0D01*
G02Y1480553I1661J1458D01*
G03X316144Y1480685I-150J132D01*
G01Y1481306D01*
G02X316346Y1481508I202J0D01*
G01X319166D01*
G02X319368Y1481305I-1J-203D01*
G01Y1480685D01*
G03X319418Y1480553I200J0D01*
G02Y1477637I-1661J-1458D01*
G03X319368Y1477505I150J-132D01*
G01Y1475567D01*
G03X319418Y1475435I200J0D01*
G02Y1472519I-1661J-1458D01*
G03X319368Y1472387I150J-132D01*
G01Y1471766D01*
G37*
G36*
G01X336690D02*
G02X336488Y1471564I-202J0D01*
G01X333668D01*
G02X333466Y1471767I1J203D01*
G01Y1472387D01*
G03X333416Y1472519I-200J0D01*
G02Y1475435I1661J1458D01*
G03X333466Y1475567I-150J132D01*
G01Y1477505D01*
G03X333416Y1477637I-200J0D01*
G02Y1480553I1661J1458D01*
G03X333466Y1480685I-150J132D01*
G01Y1481306D01*
G02X333668Y1481508I202J0D01*
G01X336488D01*
G02X336690Y1481305I-1J-203D01*
G01Y1480685D01*
G03X336740Y1480553I200J0D01*
G02Y1477637I-1661J-1458D01*
G03X336690Y1477505I150J-132D01*
G01Y1475567D01*
G03X336740Y1475435I200J0D01*
G02Y1472519I-1661J-1458D01*
G03X336690Y1472387I150J-132D01*
G01Y1471766D01*
G37*
G36*
G01X628157Y1481508D02*
X630977D01*
G02X631180Y1481305I0J-203D01*
G01Y1480683D01*
G03X631230Y1480551I200J0D01*
G02Y1477639I-1664J-1456D01*
G03X631180Y1477507I150J-132D01*
G01Y1475565D01*
G03X631230Y1475433I200J0D01*
G02Y1472521I-1664J-1456D01*
G03X631180Y1472389I150J-132D01*
G01Y1471767D01*
G02X630977Y1471564I-203J0D01*
G01X628157D01*
G02X627954Y1471767I0J203D01*
G01Y1472389D01*
G03X627904Y1472521I-200J0D01*
G02Y1475433I1664J1456D01*
G03X627954Y1475565I-150J132D01*
G01Y1477507D01*
G03X627904Y1477639I-200J0D01*
G02Y1480551I1664J1456D01*
G03X627954Y1480683I-150J132D01*
G01Y1481305D01*
G02X628157Y1481508I203J0D01*
G37*
G36*
G01X1133462Y1471766D02*
G02X1133260Y1471564I-202J0D01*
G01X1130440D01*
G02X1130238Y1471767I1J203D01*
G01Y1472387D01*
G03X1130188Y1472519I-200J0D01*
G02Y1475435I1661J1458D01*
G03X1130238Y1475567I-150J132D01*
G01Y1477505D01*
G03X1130188Y1477637I-200J0D01*
G02Y1480553I1661J1458D01*
G03X1130238Y1480685I-150J132D01*
G01Y1481306D01*
G02X1130440Y1481508I202J0D01*
G01X1133260D01*
G02X1133462Y1481305I-1J-203D01*
G01Y1480685D01*
G03X1133512Y1480553I200J0D01*
G02Y1477637I-1661J-1458D01*
G03X1133462Y1477505I150J-132D01*
G01Y1475567D01*
G03X1133512Y1475435I200J0D01*
G02Y1472519I-1661J-1458D01*
G03X1133462Y1472387I150J-132D01*
G01Y1471766D01*
G37*
G36*
G01X1147763Y1481508D02*
X1150583D01*
G02X1150786Y1481305I0J-203D01*
G01Y1480683D01*
G03X1150836Y1480551I200J0D01*
G02Y1477639I-1664J-1456D01*
G03X1150786Y1477507I150J-132D01*
G01Y1475565D01*
G03X1150836Y1475433I200J0D01*
G02Y1472521I-1664J-1456D01*
G03X1150786Y1472389I150J-132D01*
G01Y1471767D01*
G02X1150583Y1471564I-203J0D01*
G01X1147763D01*
G02X1147560Y1471767I0J203D01*
G01Y1472389D01*
G03X1147510Y1472521I-200J0D01*
G02Y1475433I1664J1456D01*
G03X1147560Y1475565I-150J132D01*
G01Y1477507D01*
G03X1147510Y1477639I-200J0D01*
G02Y1480551I1664J1456D01*
G03X1147560Y1480683I-150J132D01*
G01Y1481305D01*
G02X1147763Y1481508I203J0D01*
G37*
G36*
G01X1650125D02*
X1652945D01*
G02X1653148Y1481305I0J-203D01*
G01Y1480683D01*
G03X1653198Y1480551I200J0D01*
G02Y1477639I-1664J-1456D01*
G03X1653148Y1477507I150J-132D01*
G01Y1475565D01*
G03X1653198Y1475433I200J0D01*
G02Y1472521I-1664J-1456D01*
G03X1653148Y1472389I150J-132D01*
G01Y1471767D01*
G02X1652945Y1471564I-203J0D01*
G01X1650125D01*
G02X1649922Y1471767I0J203D01*
G01Y1472389D01*
G03X1649872Y1472521I-200J0D01*
G02Y1475433I1664J1456D01*
G03X1649922Y1475565I-150J132D01*
G01Y1477507D01*
G03X1649872Y1477639I-200J0D01*
G02Y1480551I1664J1456D01*
G03X1649922Y1480683I-150J132D01*
G01Y1481305D01*
G02X1650125Y1481508I203J0D01*
G37*
G36*
G01X1670470Y1471766D02*
G02X1670268Y1471564I-202J0D01*
G01X1667448D01*
G02X1667246Y1471767I1J203D01*
G01Y1472387D01*
G03X1667196Y1472519I-200J0D01*
G02Y1475435I1661J1458D01*
G03X1667246Y1475567I-150J132D01*
G01Y1477505D01*
G03X1667196Y1477637I-200J0D01*
G02Y1480553I1661J1458D01*
G03X1667246Y1480685I-150J132D01*
G01Y1481306D01*
G02X1667448Y1481508I202J0D01*
G01X1670268D01*
G02X1670470Y1481305I-1J-203D01*
G01Y1480685D01*
G03X1670520Y1480553I200J0D01*
G02Y1477637I-1661J-1458D01*
G03X1670470Y1477505I150J-132D01*
G01Y1475567D01*
G03X1670520Y1475435I200J0D01*
G02Y1472519I-1661J-1458D01*
G03X1670470Y1472387I150J-132D01*
G01Y1471766D01*
G37*
G36*
G01X117133Y1485838D02*
X119953D01*
G02X120156Y1485635I0J-203D01*
G01Y1485014D01*
G03X120206Y1484882I200J0D01*
G02Y1481970I-1664J-1456D01*
G03X120156Y1481838I150J-132D01*
G01Y1479896D01*
G03X120206Y1479764I200J0D01*
G02Y1476852I-1664J-1456D01*
G03X120156Y1476720I150J-132D01*
G01Y1476097D01*
G02X119953Y1475894I-203J0D01*
G01X117133D01*
G02X116930Y1476097I0J203D01*
G01Y1476720D01*
G03X116880Y1476852I-200J0D01*
G02Y1479764I1664J1456D01*
G03X116930Y1479896I-150J132D01*
G01Y1481838D01*
G03X116880Y1481970I-200J0D01*
G02Y1484882I1664J1456D01*
G03X116930Y1485014I-150J132D01*
G01Y1485635D01*
G02X117133Y1485838I203J0D01*
G37*
G36*
G01X310706Y1476096D02*
G02X310504Y1475894I-202J0D01*
G01X307684D01*
G02X307482Y1476097I1J203D01*
G01Y1476718D01*
G03X307432Y1476850I-200J0D01*
G02Y1479766I1661J1458D01*
G03X307482Y1479898I-150J132D01*
G01Y1481836D01*
G03X307432Y1481968I-200J0D01*
G02Y1484884I1661J1458D01*
G03X307482Y1485016I-150J132D01*
G01Y1485636D01*
G02X307684Y1485838I202J0D01*
G01X310504D01*
G02X310706Y1485635I-1J-203D01*
G01Y1485016D01*
G03X310756Y1484884I200J0D01*
G02Y1481968I-1661J-1458D01*
G03X310706Y1481836I150J-132D01*
G01Y1479898D01*
G03X310756Y1479766I200J0D01*
G02Y1476850I-1661J-1458D01*
G03X310706Y1476718I150J-132D01*
G01Y1476096D01*
G37*
G36*
G01X325007Y1485838D02*
X327827D01*
G02X328030Y1485635I0J-203D01*
G01Y1485014D01*
G03X328080Y1484882I200J0D01*
G02Y1481970I-1664J-1456D01*
G03X328030Y1481838I150J-132D01*
G01Y1479896D01*
G03X328080Y1479764I200J0D01*
G02Y1476852I-1664J-1456D01*
G03X328030Y1476720I150J-132D01*
G01Y1476097D01*
G02X327827Y1475894I-203J0D01*
G01X325007D01*
G02X324804Y1476097I0J203D01*
G01Y1476720D01*
G03X324754Y1476852I-200J0D01*
G02Y1479764I1664J1456D01*
G03X324804Y1479896I-150J132D01*
G01Y1481838D01*
G03X324754Y1481970I-200J0D01*
G02Y1484882I1664J1456D01*
G03X324804Y1485014I-150J132D01*
G01Y1485635D01*
G02X325007Y1485838I203J0D01*
G37*
G36*
G01X345352Y1476096D02*
G02X345150Y1475894I-202J0D01*
G01X342330D01*
G02X342128Y1476097I1J203D01*
G01Y1476718D01*
G03X342078Y1476850I-200J0D01*
G02Y1479766I1661J1458D01*
G03X342128Y1479898I-150J132D01*
G01Y1481836D01*
G03X342078Y1481968I-200J0D01*
G02Y1484884I1661J1458D01*
G03X342128Y1485016I-150J132D01*
G01Y1485636D01*
G02X342330Y1485838I202J0D01*
G01X345150D01*
G02X345352Y1485635I-1J-203D01*
G01Y1485016D01*
G03X345402Y1484884I200J0D01*
G02Y1481968I-1661J-1458D01*
G03X345352Y1481836I150J-132D01*
G01Y1479898D01*
G03X345402Y1479766I200J0D01*
G02Y1476850I-1661J-1458D01*
G03X345352Y1476718I150J-132D01*
G01Y1476096D01*
G37*
G36*
G01X639840D02*
G02X639638Y1475894I-202J0D01*
G01X636818D01*
G02X636616Y1476097I1J203D01*
G01Y1476718D01*
G03X636566Y1476850I-200J0D01*
G02Y1479766I1661J1458D01*
G03X636616Y1479898I-150J132D01*
G01Y1481836D01*
G03X636566Y1481968I-200J0D01*
G02Y1484884I1661J1458D01*
G03X636616Y1485016I-150J132D01*
G01Y1485636D01*
G02X636818Y1485838I202J0D01*
G01X639638D01*
G02X639840Y1485635I-1J-203D01*
G01Y1485016D01*
G03X639890Y1484884I200J0D01*
G02Y1481968I-1661J-1458D01*
G03X639840Y1481836I150J-132D01*
G01Y1479898D01*
G03X639890Y1479766I200J0D01*
G02Y1476850I-1661J-1458D01*
G03X639840Y1476718I150J-132D01*
G01Y1476096D01*
G37*
G36*
G01X1139101Y1485838D02*
X1141921D01*
G02X1142124Y1485635I0J-203D01*
G01Y1485014D01*
G03X1142174Y1484882I200J0D01*
G02Y1481970I-1664J-1456D01*
G03X1142124Y1481838I150J-132D01*
G01Y1479896D01*
G03X1142174Y1479764I200J0D01*
G02Y1476852I-1664J-1456D01*
G03X1142124Y1476720I150J-132D01*
G01Y1476097D01*
G02X1141921Y1475894I-203J0D01*
G01X1139101D01*
G02X1138898Y1476097I0J203D01*
G01Y1476720D01*
G03X1138848Y1476852I-200J0D01*
G02Y1479764I1664J1456D01*
G03X1138898Y1479896I-150J132D01*
G01Y1481838D01*
G03X1138848Y1481970I-200J0D01*
G02Y1484882I1664J1456D01*
G03X1138898Y1485014I-150J132D01*
G01Y1485635D01*
G02X1139101Y1485838I203J0D01*
G37*
G36*
G01X1159446Y1476096D02*
G02X1159244Y1475894I-202J0D01*
G01X1156424D01*
G02X1156222Y1476097I1J203D01*
G01Y1476718D01*
G03X1156172Y1476850I-200J0D01*
G02Y1479766I1661J1458D01*
G03X1156222Y1479898I-150J132D01*
G01Y1481836D01*
G03X1156172Y1481968I-200J0D01*
G02Y1484884I1661J1458D01*
G03X1156222Y1485016I-150J132D01*
G01Y1485636D01*
G02X1156424Y1485838I202J0D01*
G01X1159244D01*
G02X1159446Y1485635I-1J-203D01*
G01Y1485016D01*
G03X1159496Y1484884I200J0D01*
G02Y1481968I-1661J-1458D01*
G03X1159446Y1481836I150J-132D01*
G01Y1479898D01*
G03X1159496Y1479766I200J0D01*
G02Y1476850I-1661J-1458D01*
G03X1159446Y1476718I150J-132D01*
G01Y1476096D01*
G37*
G36*
G01X1661808D02*
G02X1661606Y1475894I-202J0D01*
G01X1658786D01*
G02X1658584Y1476097I1J203D01*
G01Y1476718D01*
G03X1658534Y1476850I-200J0D01*
G02Y1479766I1661J1458D01*
G03X1658584Y1479898I-150J132D01*
G01Y1481836D01*
G03X1658534Y1481968I-200J0D01*
G02Y1484884I1661J1458D01*
G03X1658584Y1485016I-150J132D01*
G01Y1485636D01*
G02X1658786Y1485838I202J0D01*
G01X1661606D01*
G02X1661808Y1485635I-1J-203D01*
G01Y1485016D01*
G03X1661858Y1484884I200J0D01*
G02Y1481968I-1661J-1458D01*
G03X1661808Y1481836I150J-132D01*
G01Y1479898D01*
G03X1661858Y1479766I200J0D01*
G02Y1476850I-1661J-1458D01*
G03X1661808Y1476718I150J-132D01*
G01Y1476096D01*
G37*
G36*
G01X1676109Y1485838D02*
X1678929D01*
G02X1679132Y1485635I0J-203D01*
G01Y1485014D01*
G03X1679182Y1484882I200J0D01*
G02Y1481970I-1664J-1456D01*
G03X1679132Y1481838I150J-132D01*
G01Y1479896D01*
G03X1679182Y1479764I200J0D01*
G02Y1476852I-1664J-1456D01*
G03X1679132Y1476720I150J-132D01*
G01Y1476097D01*
G02X1678929Y1475894I-203J0D01*
G01X1676109D01*
G02X1675906Y1476097I0J203D01*
G01Y1476720D01*
G03X1675856Y1476852I-200J0D01*
G02Y1479764I1664J1456D01*
G03X1675906Y1479896I-150J132D01*
G01Y1481838D01*
G03X1675856Y1481970I-200J0D01*
G02Y1484882I1664J1456D01*
G03X1675906Y1485014I-150J132D01*
G01Y1485635D01*
G02X1676109Y1485838I203J0D01*
G37*
G36*
G01X111494Y1487120D02*
G02X111292Y1486918I-202J0D01*
G01X108472D01*
G02X108270Y1487121I1J203D01*
G01Y1487741D01*
G03X108220Y1487873I-200J0D01*
G02Y1490789I1661J1458D01*
G03X108270Y1490921I-150J132D01*
G01Y1492859D01*
G03X108220Y1492991I-200J0D01*
G02Y1495907I1661J1458D01*
G03X108270Y1496039I-150J132D01*
G01Y1496660D01*
G02X108472Y1496862I202J0D01*
G01X111292D01*
G02X111494Y1496659I-1J-203D01*
G01Y1496039D01*
G03X111544Y1495907I200J0D01*
G02Y1492991I-1661J-1458D01*
G03X111494Y1492859I150J-132D01*
G01Y1490921D01*
G03X111544Y1490789I200J0D01*
G02Y1487873I-1661J-1458D01*
G03X111494Y1487741I150J-132D01*
G01Y1487120D01*
G37*
G36*
G01X319368D02*
G02X319166Y1486918I-202J0D01*
G01X316346D01*
G02X316144Y1487121I1J203D01*
G01Y1487741D01*
G03X316094Y1487873I-200J0D01*
G02Y1490789I1661J1458D01*
G03X316144Y1490921I-150J132D01*
G01Y1492859D01*
G03X316094Y1492991I-200J0D01*
G02Y1495907I1661J1458D01*
G03X316144Y1496039I-150J132D01*
G01Y1496660D01*
G02X316346Y1496862I202J0D01*
G01X319166D01*
G02X319368Y1496659I-1J-203D01*
G01Y1496039D01*
G03X319418Y1495907I200J0D01*
G02Y1492991I-1661J-1458D01*
G03X319368Y1492859I150J-132D01*
G01Y1490921D01*
G03X319418Y1490789I200J0D01*
G02Y1487873I-1661J-1458D01*
G03X319368Y1487741I150J-132D01*
G01Y1487120D01*
G37*
G36*
G01X336690D02*
G02X336488Y1486918I-202J0D01*
G01X333668D01*
G02X333466Y1487121I1J203D01*
G01Y1487741D01*
G03X333416Y1487873I-200J0D01*
G02Y1490789I1661J1458D01*
G03X333466Y1490921I-150J132D01*
G01Y1492859D01*
G03X333416Y1492991I-200J0D01*
G02Y1495907I1661J1458D01*
G03X333466Y1496039I-150J132D01*
G01Y1496660D01*
G02X333668Y1496862I202J0D01*
G01X336488D01*
G02X336690Y1496659I-1J-203D01*
G01Y1496039D01*
G03X336740Y1495907I200J0D01*
G02Y1492991I-1661J-1458D01*
G03X336690Y1492859I150J-132D01*
G01Y1490921D01*
G03X336740Y1490789I200J0D01*
G02Y1487873I-1661J-1458D01*
G03X336690Y1487741I150J-132D01*
G01Y1487120D01*
G37*
G36*
G01X628157Y1496862D02*
X630977D01*
G02X631180Y1496659I0J-203D01*
G01Y1496037D01*
G03X631230Y1495905I200J0D01*
G02Y1492993I-1664J-1456D01*
G03X631180Y1492861I150J-132D01*
G01Y1490919D01*
G03X631230Y1490787I200J0D01*
G02Y1487875I-1664J-1456D01*
G03X631180Y1487743I150J-132D01*
G01Y1487121D01*
G02X630977Y1486918I-203J0D01*
G01X628157D01*
G02X627954Y1487121I0J203D01*
G01Y1487743D01*
G03X627904Y1487875I-200J0D01*
G02Y1490787I1664J1456D01*
G03X627954Y1490919I-150J132D01*
G01Y1492861D01*
G03X627904Y1492993I-200J0D01*
G02Y1495905I1664J1456D01*
G03X627954Y1496037I-150J132D01*
G01Y1496659D01*
G02X628157Y1496862I203J0D01*
G37*
G36*
G01X1133462Y1487120D02*
G02X1133260Y1486918I-202J0D01*
G01X1130440D01*
G02X1130238Y1487121I1J203D01*
G01Y1487741D01*
G03X1130188Y1487873I-200J0D01*
G02Y1490789I1661J1458D01*
G03X1130238Y1490921I-150J132D01*
G01Y1492859D01*
G03X1130188Y1492991I-200J0D01*
G02Y1495907I1661J1458D01*
G03X1130238Y1496039I-150J132D01*
G01Y1496660D01*
G02X1130440Y1496862I202J0D01*
G01X1133260D01*
G02X1133462Y1496659I-1J-203D01*
G01Y1496039D01*
G03X1133512Y1495907I200J0D01*
G02Y1492991I-1661J-1458D01*
G03X1133462Y1492859I150J-132D01*
G01Y1490921D01*
G03X1133512Y1490789I200J0D01*
G02Y1487873I-1661J-1458D01*
G03X1133462Y1487741I150J-132D01*
G01Y1487120D01*
G37*
G36*
G01X1147763Y1496862D02*
X1150583D01*
G02X1150786Y1496659I0J-203D01*
G01Y1496037D01*
G03X1150836Y1495905I200J0D01*
G02Y1492993I-1664J-1456D01*
G03X1150786Y1492861I150J-132D01*
G01Y1490919D01*
G03X1150836Y1490787I200J0D01*
G02Y1487875I-1664J-1456D01*
G03X1150786Y1487743I150J-132D01*
G01Y1487121D01*
G02X1150583Y1486918I-203J0D01*
G01X1147763D01*
G02X1147560Y1487121I0J203D01*
G01Y1487743D01*
G03X1147510Y1487875I-200J0D01*
G02Y1490787I1664J1456D01*
G03X1147560Y1490919I-150J132D01*
G01Y1492861D01*
G03X1147510Y1492993I-200J0D01*
G02Y1495905I1664J1456D01*
G03X1147560Y1496037I-150J132D01*
G01Y1496659D01*
G02X1147763Y1496862I203J0D01*
G37*
G36*
G01X1650125D02*
X1652945D01*
G02X1653148Y1496659I0J-203D01*
G01Y1496037D01*
G03X1653198Y1495905I200J0D01*
G02Y1492993I-1664J-1456D01*
G03X1653148Y1492861I150J-132D01*
G01Y1490919D01*
G03X1653198Y1490787I200J0D01*
G02Y1487875I-1664J-1456D01*
G03X1653148Y1487743I150J-132D01*
G01Y1487121D01*
G02X1652945Y1486918I-203J0D01*
G01X1650125D01*
G02X1649922Y1487121I0J203D01*
G01Y1487743D01*
G03X1649872Y1487875I-200J0D01*
G02Y1490787I1664J1456D01*
G03X1649922Y1490919I-150J132D01*
G01Y1492861D01*
G03X1649872Y1492993I-200J0D01*
G02Y1495905I1664J1456D01*
G03X1649922Y1496037I-150J132D01*
G01Y1496659D01*
G02X1650125Y1496862I203J0D01*
G37*
G36*
G01X1670470Y1487120D02*
G02X1670268Y1486918I-202J0D01*
G01X1667448D01*
G02X1667246Y1487121I1J203D01*
G01Y1487741D01*
G03X1667196Y1487873I-200J0D01*
G02Y1490789I1661J1458D01*
G03X1667246Y1490921I-150J132D01*
G01Y1492859D01*
G03X1667196Y1492991I-200J0D01*
G02Y1495907I1661J1458D01*
G03X1667246Y1496039I-150J132D01*
G01Y1496660D01*
G02X1667448Y1496862I202J0D01*
G01X1670268D01*
G02X1670470Y1496659I-1J-203D01*
G01Y1496039D01*
G03X1670520Y1495907I200J0D01*
G02Y1492991I-1661J-1458D01*
G03X1670470Y1492859I150J-132D01*
G01Y1490921D01*
G03X1670520Y1490789I200J0D01*
G02Y1487873I-1661J-1458D01*
G03X1670470Y1487741I150J-132D01*
G01Y1487120D01*
G37*
G36*
G01X117133Y1501192D02*
X119953D01*
G02X120156Y1500989I0J-203D01*
G01Y1500368D01*
G03X120206Y1500236I200J0D01*
G02Y1497324I-1664J-1456D01*
G03X120156Y1497192I150J-132D01*
G01Y1495250D01*
G03X120206Y1495118I200J0D01*
G02Y1492206I-1664J-1456D01*
G03X120156Y1492074I150J-132D01*
G01Y1491451D01*
G02X119953Y1491248I-203J0D01*
G01X117133D01*
G02X116930Y1491451I0J203D01*
G01Y1492074D01*
G03X116880Y1492206I-200J0D01*
G02Y1495118I1664J1456D01*
G03X116930Y1495250I-150J132D01*
G01Y1497192D01*
G03X116880Y1497324I-200J0D01*
G02Y1500236I1664J1456D01*
G03X116930Y1500368I-150J132D01*
G01Y1500989D01*
G02X117133Y1501192I203J0D01*
G37*
G36*
G01X310706Y1491450D02*
G02X310504Y1491248I-202J0D01*
G01X307684D01*
G02X307482Y1491451I1J203D01*
G01Y1492072D01*
G03X307432Y1492204I-200J0D01*
G02Y1495120I1661J1458D01*
G03X307482Y1495252I-150J132D01*
G01Y1497190D01*
G03X307432Y1497322I-200J0D01*
G02Y1500238I1661J1458D01*
G03X307482Y1500370I-150J132D01*
G01Y1500990D01*
G02X307684Y1501192I202J0D01*
G01X310504D01*
G02X310706Y1500989I-1J-203D01*
G01Y1500370D01*
G03X310756Y1500238I200J0D01*
G02Y1497322I-1661J-1458D01*
G03X310706Y1497190I150J-132D01*
G01Y1495252D01*
G03X310756Y1495120I200J0D01*
G02Y1492204I-1661J-1458D01*
G03X310706Y1492072I150J-132D01*
G01Y1491450D01*
G37*
G36*
G01X325007Y1501192D02*
X327827D01*
G02X328030Y1500989I0J-203D01*
G01Y1500368D01*
G03X328080Y1500236I200J0D01*
G02Y1497324I-1664J-1456D01*
G03X328030Y1497192I150J-132D01*
G01Y1495250D01*
G03X328080Y1495118I200J0D01*
G02Y1492206I-1664J-1456D01*
G03X328030Y1492074I150J-132D01*
G01Y1491451D01*
G02X327827Y1491248I-203J0D01*
G01X325007D01*
G02X324804Y1491451I0J203D01*
G01Y1492074D01*
G03X324754Y1492206I-200J0D01*
G02Y1495118I1664J1456D01*
G03X324804Y1495250I-150J132D01*
G01Y1497192D01*
G03X324754Y1497324I-200J0D01*
G02Y1500236I1664J1456D01*
G03X324804Y1500368I-150J132D01*
G01Y1500989D01*
G02X325007Y1501192I203J0D01*
G37*
G36*
G01X345352Y1491450D02*
G02X345150Y1491248I-202J0D01*
G01X342330D01*
G02X342128Y1491451I1J203D01*
G01Y1492072D01*
G03X342078Y1492204I-200J0D01*
G02Y1495120I1661J1458D01*
G03X342128Y1495252I-150J132D01*
G01Y1497190D01*
G03X342078Y1497322I-200J0D01*
G02Y1500238I1661J1458D01*
G03X342128Y1500370I-150J132D01*
G01Y1500990D01*
G02X342330Y1501192I202J0D01*
G01X345150D01*
G02X345352Y1500989I-1J-203D01*
G01Y1500370D01*
G03X345402Y1500238I200J0D01*
G02Y1497322I-1661J-1458D01*
G03X345352Y1497190I150J-132D01*
G01Y1495252D01*
G03X345402Y1495120I200J0D01*
G02Y1492204I-1661J-1458D01*
G03X345352Y1492072I150J-132D01*
G01Y1491450D01*
G37*
G36*
G01X639840D02*
G02X639638Y1491248I-202J0D01*
G01X636818D01*
G02X636616Y1491451I1J203D01*
G01Y1492072D01*
G03X636566Y1492204I-200J0D01*
G02Y1495120I1661J1458D01*
G03X636616Y1495252I-150J132D01*
G01Y1497190D01*
G03X636566Y1497322I-200J0D01*
G02Y1500238I1661J1458D01*
G03X636616Y1500370I-150J132D01*
G01Y1500990D01*
G02X636818Y1501192I202J0D01*
G01X639638D01*
G02X639840Y1500989I-1J-203D01*
G01Y1500370D01*
G03X639890Y1500238I200J0D01*
G02Y1497322I-1661J-1458D01*
G03X639840Y1497190I150J-132D01*
G01Y1495252D01*
G03X639890Y1495120I200J0D01*
G02Y1492204I-1661J-1458D01*
G03X639840Y1492072I150J-132D01*
G01Y1491450D01*
G37*
G36*
G01X1139101Y1501192D02*
X1141921D01*
G02X1142124Y1500989I0J-203D01*
G01Y1500368D01*
G03X1142174Y1500236I200J0D01*
G02Y1497324I-1664J-1456D01*
G03X1142124Y1497192I150J-132D01*
G01Y1495250D01*
G03X1142174Y1495118I200J0D01*
G02Y1492206I-1664J-1456D01*
G03X1142124Y1492074I150J-132D01*
G01Y1491451D01*
G02X1141921Y1491248I-203J0D01*
G01X1139101D01*
G02X1138898Y1491451I0J203D01*
G01Y1492074D01*
G03X1138848Y1492206I-200J0D01*
G02Y1495118I1664J1456D01*
G03X1138898Y1495250I-150J132D01*
G01Y1497192D01*
G03X1138848Y1497324I-200J0D01*
G02Y1500236I1664J1456D01*
G03X1138898Y1500368I-150J132D01*
G01Y1500989D01*
G02X1139101Y1501192I203J0D01*
G37*
G36*
G01X1159446Y1491450D02*
G02X1159244Y1491248I-202J0D01*
G01X1156424D01*
G02X1156222Y1491451I1J203D01*
G01Y1492072D01*
G03X1156172Y1492204I-200J0D01*
G02Y1495120I1661J1458D01*
G03X1156222Y1495252I-150J132D01*
G01Y1497190D01*
G03X1156172Y1497322I-200J0D01*
G02Y1500238I1661J1458D01*
G03X1156222Y1500370I-150J132D01*
G01Y1500990D01*
G02X1156424Y1501192I202J0D01*
G01X1159244D01*
G02X1159446Y1500989I-1J-203D01*
G01Y1500370D01*
G03X1159496Y1500238I200J0D01*
G02Y1497322I-1661J-1458D01*
G03X1159446Y1497190I150J-132D01*
G01Y1495252D01*
G03X1159496Y1495120I200J0D01*
G02Y1492204I-1661J-1458D01*
G03X1159446Y1492072I150J-132D01*
G01Y1491450D01*
G37*
G36*
G01X1661808D02*
G02X1661606Y1491248I-202J0D01*
G01X1658786D01*
G02X1658584Y1491451I1J203D01*
G01Y1492072D01*
G03X1658534Y1492204I-200J0D01*
G02Y1495120I1661J1458D01*
G03X1658584Y1495252I-150J132D01*
G01Y1497190D01*
G03X1658534Y1497322I-200J0D01*
G02Y1500238I1661J1458D01*
G03X1658584Y1500370I-150J132D01*
G01Y1500990D01*
G02X1658786Y1501192I202J0D01*
G01X1661606D01*
G02X1661808Y1500989I-1J-203D01*
G01Y1500370D01*
G03X1661858Y1500238I200J0D01*
G02Y1497322I-1661J-1458D01*
G03X1661808Y1497190I150J-132D01*
G01Y1495252D01*
G03X1661858Y1495120I200J0D01*
G02Y1492204I-1661J-1458D01*
G03X1661808Y1492072I150J-132D01*
G01Y1491450D01*
G37*
G36*
G01X1676109Y1501192D02*
X1678929D01*
G02X1679132Y1500989I0J-203D01*
G01Y1500368D01*
G03X1679182Y1500236I200J0D01*
G02Y1497324I-1664J-1456D01*
G03X1679132Y1497192I150J-132D01*
G01Y1495250D01*
G03X1679182Y1495118I200J0D01*
G02Y1492206I-1664J-1456D01*
G03X1679132Y1492074I150J-132D01*
G01Y1491451D01*
G02X1678929Y1491248I-203J0D01*
G01X1676109D01*
G02X1675906Y1491451I0J203D01*
G01Y1492074D01*
G03X1675856Y1492206I-200J0D01*
G02Y1495118I1664J1456D01*
G03X1675906Y1495250I-150J132D01*
G01Y1497192D01*
G03X1675856Y1497324I-200J0D01*
G02Y1500236I1664J1456D01*
G03X1675906Y1500368I-150J132D01*
G01Y1500989D01*
G02X1676109Y1501192I203J0D01*
G37*
G36*
G01X108472Y1512216D02*
X111292D01*
G02X111494Y1512014I0J-202D01*
G01Y1511394D01*
G03X111544Y1511262I200J0D01*
G02Y1508346I-1661J-1458D01*
G03X111494Y1508214I150J-132D01*
G01Y1506275D01*
G03X111544Y1506143I200J0D01*
G02Y1503227I-1661J-1458D01*
G03X111494Y1503095I150J-132D01*
G01Y1502476D01*
G02X111292Y1502274I-202J0D01*
G01X108472D01*
G02X108270Y1502476I0J202D01*
G01Y1503095D01*
G03X108220Y1503227I-200J0D01*
G02Y1506143I1661J1458D01*
G03X108270Y1506275I-150J132D01*
G01Y1508214D01*
G03X108220Y1508346I-200J0D01*
G02Y1511262I1661J1458D01*
G03X108270Y1511394I-150J132D01*
G01Y1512014D01*
G02X108472Y1512216I202J0D01*
G37*
G36*
G01X316346D02*
X319166D01*
G02X319368Y1512014I0J-202D01*
G01Y1511394D01*
G03X319418Y1511262I200J0D01*
G02Y1508346I-1661J-1458D01*
G03X319368Y1508214I150J-132D01*
G01Y1506275D01*
G03X319418Y1506143I200J0D01*
G02Y1503227I-1661J-1458D01*
G03X319368Y1503095I150J-132D01*
G01Y1502476D01*
G02X319166Y1502274I-202J0D01*
G01X316346D01*
G02X316144Y1502476I0J202D01*
G01Y1503095D01*
G03X316094Y1503227I-200J0D01*
G02Y1506143I1661J1458D01*
G03X316144Y1506275I-150J132D01*
G01Y1508214D01*
G03X316094Y1508346I-200J0D01*
G02Y1511262I1661J1458D01*
G03X316144Y1511394I-150J132D01*
G01Y1512014D01*
G02X316346Y1512216I202J0D01*
G37*
G36*
G01X333668D02*
X336488D01*
G02X336690Y1512014I0J-202D01*
G01Y1511394D01*
G03X336740Y1511262I200J0D01*
G02Y1508346I-1661J-1458D01*
G03X336690Y1508214I150J-132D01*
G01Y1506275D01*
G03X336740Y1506143I200J0D01*
G02Y1503227I-1661J-1458D01*
G03X336690Y1503095I150J-132D01*
G01Y1502476D01*
G02X336488Y1502274I-202J0D01*
G01X333668D01*
G02X333466Y1502476I0J202D01*
G01Y1503095D01*
G03X333416Y1503227I-200J0D01*
G02Y1506143I1661J1458D01*
G03X333466Y1506275I-150J132D01*
G01Y1508214D01*
G03X333416Y1508346I-200J0D01*
G02Y1511262I1661J1458D01*
G03X333466Y1511394I-150J132D01*
G01Y1512014D01*
G02X333668Y1512216I202J0D01*
G37*
G36*
G01X1130440D02*
X1133260D01*
G02X1133462Y1512014I0J-202D01*
G01Y1511394D01*
G03X1133512Y1511262I200J0D01*
G02Y1508346I-1661J-1458D01*
G03X1133462Y1508214I150J-132D01*
G01Y1506275D01*
G03X1133512Y1506143I200J0D01*
G02Y1503227I-1661J-1458D01*
G03X1133462Y1503095I150J-132D01*
G01Y1502476D01*
G02X1133260Y1502274I-202J0D01*
G01X1130440D01*
G02X1130238Y1502476I0J202D01*
G01Y1503095D01*
G03X1130188Y1503227I-200J0D01*
G02Y1506143I1661J1458D01*
G03X1130238Y1506275I-150J132D01*
G01Y1508214D01*
G03X1130188Y1508346I-200J0D01*
G02Y1511262I1661J1458D01*
G03X1130238Y1511394I-150J132D01*
G01Y1512014D01*
G02X1130440Y1512216I202J0D01*
G37*
G36*
G01X1667448D02*
X1670268D01*
G02X1670470Y1512014I0J-202D01*
G01Y1511394D01*
G03X1670520Y1511262I200J0D01*
G02Y1508346I-1661J-1458D01*
G03X1670470Y1508214I150J-132D01*
G01Y1506275D01*
G03X1670520Y1506143I200J0D01*
G02Y1503227I-1661J-1458D01*
G03X1670470Y1503095I150J-132D01*
G01Y1502476D01*
G02X1670268Y1502274I-202J0D01*
G01X1667448D01*
G02X1667246Y1502476I0J202D01*
G01Y1503095D01*
G03X1667196Y1503227I-200J0D01*
G02Y1506143I1661J1458D01*
G03X1667246Y1506275I-150J132D01*
G01Y1508214D01*
G03X1667196Y1508346I-200J0D01*
G02Y1511262I1661J1458D01*
G03X1667246Y1511394I-150J132D01*
G01Y1512014D01*
G02X1667448Y1512216I202J0D01*
G37*
G36*
G01X628156Y1502274D02*
G02X627954Y1502476I0J202D01*
G01Y1503097D01*
G03X627904Y1503229I-200J0D01*
G02Y1506141I1664J1456D01*
G03X627954Y1506273I-150J132D01*
G01Y1508216D01*
G03X627904Y1508348I-200J0D01*
G02Y1511260I1664J1456D01*
G03X627954Y1511392I-150J132D01*
G01Y1512014D01*
G02X628157Y1512216I203J-1D01*
G01X630978D01*
G02X631180Y1512014I0J-202D01*
G01Y1511392D01*
G03X631230Y1511260I200J0D01*
G02Y1508348I-1664J-1456D01*
G03X631180Y1508216I150J-132D01*
G01Y1506273D01*
G03X631230Y1506141I200J0D01*
G02Y1503229I-1664J-1456D01*
G03X631180Y1503097I150J-132D01*
G01Y1502476D01*
G02X630977Y1502274I-203J1D01*
G01X628156D01*
G37*
G36*
G01X1147762D02*
G02X1147560Y1502476I0J202D01*
G01Y1503097D01*
G03X1147510Y1503229I-200J0D01*
G02Y1506141I1664J1456D01*
G03X1147560Y1506273I-150J132D01*
G01Y1508216D01*
G03X1147510Y1508348I-200J0D01*
G02Y1511260I1664J1456D01*
G03X1147560Y1511392I-150J132D01*
G01Y1512014D01*
G02X1147763Y1512216I203J-1D01*
G01X1150584D01*
G02X1150786Y1512014I0J-202D01*
G01Y1511392D01*
G03X1150836Y1511260I200J0D01*
G02Y1508348I-1664J-1456D01*
G03X1150786Y1508216I150J-132D01*
G01Y1506273D01*
G03X1150836Y1506141I200J0D01*
G02Y1503229I-1664J-1456D01*
G03X1150786Y1503097I150J-132D01*
G01Y1502476D01*
G02X1150583Y1502274I-203J1D01*
G01X1147762D01*
G37*
G36*
G01X1650124D02*
G02X1649922Y1502476I0J202D01*
G01Y1503097D01*
G03X1649872Y1503229I-200J0D01*
G02Y1506141I1664J1456D01*
G03X1649922Y1506273I-150J132D01*
G01Y1508216D01*
G03X1649872Y1508348I-200J0D01*
G02Y1511260I1664J1456D01*
G03X1649922Y1511392I-150J132D01*
G01Y1512014D01*
G02X1650125Y1512216I203J-1D01*
G01X1652946D01*
G02X1653148Y1512014I0J-202D01*
G01Y1511392D01*
G03X1653198Y1511260I200J0D01*
G02Y1508348I-1664J-1456D01*
G03X1653148Y1508216I150J-132D01*
G01Y1506273D01*
G03X1653198Y1506141I200J0D01*
G02Y1503229I-1664J-1456D01*
G03X1653148Y1503097I150J-132D01*
G01Y1502476D01*
G02X1652945Y1502274I-203J1D01*
G01X1650124D01*
G37*
G36*
G01X307684Y1516546D02*
X310504D01*
G02X310706Y1516344I0J-202D01*
G01Y1515724D01*
G03X310756Y1515592I200J0D01*
G02Y1512676I-1661J-1458D01*
G03X310706Y1512544I150J-132D01*
G01Y1510606D01*
G03X310756Y1510474I200J0D01*
G02Y1507558I-1661J-1458D01*
G03X310706Y1507426I150J-132D01*
G01Y1506806D01*
G02X310504Y1506604I-202J0D01*
G01X307684D01*
G02X307482Y1506806I0J202D01*
G01Y1507426D01*
G03X307432Y1507558I-200J0D01*
G02Y1510474I1661J1458D01*
G03X307482Y1510606I-150J132D01*
G01Y1512544D01*
G03X307432Y1512676I-200J0D01*
G02Y1515592I1661J1458D01*
G03X307482Y1515724I-150J132D01*
G01Y1516344D01*
G02X307684Y1516546I202J0D01*
G37*
G36*
G01X342330D02*
X345150D01*
G02X345352Y1516344I0J-202D01*
G01Y1515724D01*
G03X345402Y1515592I200J0D01*
G02Y1512676I-1661J-1458D01*
G03X345352Y1512544I150J-132D01*
G01Y1510606D01*
G03X345402Y1510474I200J0D01*
G02Y1507558I-1661J-1458D01*
G03X345352Y1507426I150J-132D01*
G01Y1506806D01*
G02X345150Y1506604I-202J0D01*
G01X342330D01*
G02X342128Y1506806I0J202D01*
G01Y1507426D01*
G03X342078Y1507558I-200J0D01*
G02Y1510474I1661J1458D01*
G03X342128Y1510606I-150J132D01*
G01Y1512544D01*
G03X342078Y1512676I-200J0D01*
G02Y1515592I1661J1458D01*
G03X342128Y1515724I-150J132D01*
G01Y1516344D01*
G02X342330Y1516546I202J0D01*
G37*
G36*
G01X636818D02*
X639638D01*
G02X639840Y1516344I0J-202D01*
G01Y1515724D01*
G03X639890Y1515592I200J0D01*
G02Y1512676I-1661J-1458D01*
G03X639840Y1512544I150J-132D01*
G01Y1510606D01*
G03X639890Y1510474I200J0D01*
G02Y1507558I-1661J-1458D01*
G03X639840Y1507426I150J-132D01*
G01Y1506806D01*
G02X639638Y1506604I-202J0D01*
G01X636818D01*
G02X636616Y1506806I0J202D01*
G01Y1507426D01*
G03X636566Y1507558I-200J0D01*
G02Y1510474I1661J1458D01*
G03X636616Y1510606I-150J132D01*
G01Y1512544D01*
G03X636566Y1512676I-200J0D01*
G02Y1515592I1661J1458D01*
G03X636616Y1515724I-150J132D01*
G01Y1516344D01*
G02X636818Y1516546I202J0D01*
G37*
G36*
G01X1156424D02*
X1159244D01*
G02X1159446Y1516344I0J-202D01*
G01Y1515724D01*
G03X1159496Y1515592I200J0D01*
G02Y1512676I-1661J-1458D01*
G03X1159446Y1512544I150J-132D01*
G01Y1510606D01*
G03X1159496Y1510474I200J0D01*
G02Y1507558I-1661J-1458D01*
G03X1159446Y1507426I150J-132D01*
G01Y1506806D01*
G02X1159244Y1506604I-202J0D01*
G01X1156424D01*
G02X1156222Y1506806I0J202D01*
G01Y1507426D01*
G03X1156172Y1507558I-200J0D01*
G02Y1510474I1661J1458D01*
G03X1156222Y1510606I-150J132D01*
G01Y1512544D01*
G03X1156172Y1512676I-200J0D01*
G02Y1515592I1661J1458D01*
G03X1156222Y1515724I-150J132D01*
G01Y1516344D01*
G02X1156424Y1516546I202J0D01*
G37*
G36*
G01X1658786D02*
X1661606D01*
G02X1661808Y1516344I0J-202D01*
G01Y1515724D01*
G03X1661858Y1515592I200J0D01*
G02Y1512676I-1661J-1458D01*
G03X1661808Y1512544I150J-132D01*
G01Y1510606D01*
G03X1661858Y1510474I200J0D01*
G02Y1507558I-1661J-1458D01*
G03X1661808Y1507426I150J-132D01*
G01Y1506806D01*
G02X1661606Y1506604I-202J0D01*
G01X1658786D01*
G02X1658584Y1506806I0J202D01*
G01Y1507426D01*
G03X1658534Y1507558I-200J0D01*
G02Y1510474I1661J1458D01*
G03X1658584Y1510606I-150J132D01*
G01Y1512544D01*
G03X1658534Y1512676I-200J0D01*
G02Y1515592I1661J1458D01*
G03X1658584Y1515724I-150J132D01*
G01Y1516344D01*
G02X1658786Y1516546I202J0D01*
G37*
G36*
G01X117132Y1506604D02*
G02X116930Y1506806I0J202D01*
G01Y1507428D01*
G03X116880Y1507560I-200J0D01*
G02Y1510472I1664J1456D01*
G03X116930Y1510604I-150J132D01*
G01Y1512546D01*
G03X116880Y1512678I-200J0D01*
G02Y1515590I1664J1456D01*
G03X116930Y1515722I-150J132D01*
G01Y1516344D01*
G02X117133Y1516546I203J-1D01*
G01X119954D01*
G02X120156Y1516344I0J-202D01*
G01Y1515722D01*
G03X120206Y1515590I200J0D01*
G02Y1512678I-1664J-1456D01*
G03X120156Y1512546I150J-132D01*
G01Y1510604D01*
G03X120206Y1510472I200J0D01*
G02Y1507560I-1664J-1456D01*
G03X120156Y1507428I150J-132D01*
G01Y1506806D01*
G02X119953Y1506604I-203J1D01*
G01X117132D01*
G37*
G36*
G01X325006D02*
G02X324804Y1506806I0J202D01*
G01Y1507428D01*
G03X324754Y1507560I-200J0D01*
G02Y1510472I1664J1456D01*
G03X324804Y1510604I-150J132D01*
G01Y1512546D01*
G03X324754Y1512678I-200J0D01*
G02Y1515590I1664J1456D01*
G03X324804Y1515722I-150J132D01*
G01Y1516344D01*
G02X325007Y1516546I203J-1D01*
G01X327828D01*
G02X328030Y1516344I0J-202D01*
G01Y1515722D01*
G03X328080Y1515590I200J0D01*
G02Y1512678I-1664J-1456D01*
G03X328030Y1512546I150J-132D01*
G01Y1510604D01*
G03X328080Y1510472I200J0D01*
G02Y1507560I-1664J-1456D01*
G03X328030Y1507428I150J-132D01*
G01Y1506806D01*
G02X327827Y1506604I-203J1D01*
G01X325006D01*
G37*
G36*
G01X1139100D02*
G02X1138898Y1506806I0J202D01*
G01Y1507428D01*
G03X1138848Y1507560I-200J0D01*
G02Y1510472I1664J1456D01*
G03X1138898Y1510604I-150J132D01*
G01Y1512546D01*
G03X1138848Y1512678I-200J0D01*
G02Y1515590I1664J1456D01*
G03X1138898Y1515722I-150J132D01*
G01Y1516344D01*
G02X1139101Y1516546I203J-1D01*
G01X1141922D01*
G02X1142124Y1516344I0J-202D01*
G01Y1515722D01*
G03X1142174Y1515590I200J0D01*
G02Y1512678I-1664J-1456D01*
G03X1142124Y1512546I150J-132D01*
G01Y1510604D01*
G03X1142174Y1510472I200J0D01*
G02Y1507560I-1664J-1456D01*
G03X1142124Y1507428I150J-132D01*
G01Y1506806D01*
G02X1141921Y1506604I-203J1D01*
G01X1139100D01*
G37*
G36*
G01X1676108D02*
G02X1675906Y1506806I0J202D01*
G01Y1507428D01*
G03X1675856Y1507560I-200J0D01*
G02Y1510472I1664J1456D01*
G03X1675906Y1510604I-150J132D01*
G01Y1512546D01*
G03X1675856Y1512678I-200J0D01*
G02Y1515590I1664J1456D01*
G03X1675906Y1515722I-150J132D01*
G01Y1516344D01*
G02X1676109Y1516546I203J-1D01*
G01X1678930D01*
G02X1679132Y1516344I0J-202D01*
G01Y1515722D01*
G03X1679182Y1515590I200J0D01*
G02Y1512678I-1664J-1456D01*
G03X1679132Y1512546I150J-132D01*
G01Y1510604D01*
G03X1679182Y1510472I200J0D01*
G02Y1507560I-1664J-1456D01*
G03X1679132Y1507428I150J-132D01*
G01Y1506806D01*
G02X1678929Y1506604I-203J1D01*
G01X1676108D01*
G37*
G36*
G01X454929Y1568516D02*
X457749D01*
G02X457952Y1568313I0J-203D01*
G01Y1567691D01*
G03X458002Y1567559I200J0D01*
G02Y1564647I-1664J-1456D01*
G03X457952Y1564515I150J-132D01*
G01Y1562573D01*
G03X458002Y1562441I200J0D01*
G02Y1559529I-1664J-1456D01*
G03X457952Y1559397I150J-132D01*
G01Y1558775D01*
G02X457749Y1558572I-203J0D01*
G01X454929D01*
G02X454726Y1558775I0J203D01*
G01Y1559397D01*
G03X454676Y1559529I-200J0D01*
G02Y1562441I1664J1456D01*
G03X454726Y1562573I-150J132D01*
G01Y1564515D01*
G03X454676Y1564647I-200J0D01*
G02Y1567559I1664J1456D01*
G03X454726Y1567691I-150J132D01*
G01Y1568313D01*
G02X454929Y1568516I203J0D01*
G37*
G36*
G01X475274Y1558774D02*
G02X475072Y1558572I-202J0D01*
G01X472252D01*
G02X472050Y1558775I1J203D01*
G01Y1559395D01*
G03X472000Y1559527I-200J0D01*
G02Y1562443I1661J1458D01*
G03X472050Y1562575I-150J132D01*
G01Y1564513D01*
G03X472000Y1564645I-200J0D01*
G02Y1567561I1661J1458D01*
G03X472050Y1567693I-150J132D01*
G01Y1568314D01*
G02X472252Y1568516I202J0D01*
G01X475072D01*
G02X475274Y1568313I-1J-203D01*
G01Y1567693D01*
G03X475324Y1567561I200J0D01*
G02Y1564645I-1661J-1458D01*
G03X475274Y1564513I150J-132D01*
G01Y1562575D01*
G03X475324Y1562443I200J0D01*
G02Y1559527I-1661J-1458D01*
G03X475274Y1559395I150J-132D01*
G01Y1558774D01*
G37*
G36*
G01X489575Y1568516D02*
X492395D01*
G02X492598Y1568313I0J-203D01*
G01Y1567691D01*
G03X492648Y1567559I200J0D01*
G02Y1564647I-1664J-1456D01*
G03X492598Y1564515I150J-132D01*
G01Y1562573D01*
G03X492648Y1562441I200J0D01*
G02Y1559529I-1664J-1456D01*
G03X492598Y1559397I150J-132D01*
G01Y1558775D01*
G02X492395Y1558572I-203J0D01*
G01X489575D01*
G02X489372Y1558775I0J203D01*
G01Y1559397D01*
G03X489322Y1559529I-200J0D01*
G02Y1562441I1664J1456D01*
G03X489372Y1562573I-150J132D01*
G01Y1564515D01*
G03X489322Y1564647I-200J0D01*
G02Y1567559I1664J1456D01*
G03X489372Y1567691I-150J132D01*
G01Y1568313D01*
G02X489575Y1568516I203J0D01*
G37*
G36*
G01X506897D02*
X509717D01*
G02X509920Y1568313I0J-203D01*
G01Y1567691D01*
G03X509970Y1567559I200J0D01*
G02Y1564647I-1664J-1456D01*
G03X509920Y1564515I150J-132D01*
G01Y1562573D01*
G03X509970Y1562441I200J0D01*
G02Y1559529I-1664J-1456D01*
G03X509920Y1559397I150J-132D01*
G01Y1558775D01*
G02X509717Y1558572I-203J0D01*
G01X506897D01*
G02X506694Y1558775I0J203D01*
G01Y1559397D01*
G03X506644Y1559529I-200J0D01*
G02Y1562441I1664J1456D01*
G03X506694Y1562573I-150J132D01*
G01Y1564515D01*
G03X506644Y1564647I-200J0D01*
G02Y1567559I1664J1456D01*
G03X506694Y1567691I-150J132D01*
G01Y1568313D01*
G02X506897Y1568516I203J0D01*
G37*
G36*
G01X1497242Y1558774D02*
G02X1497040Y1558572I-202J0D01*
G01X1494220D01*
G02X1494018Y1558775I1J203D01*
G01Y1559395D01*
G03X1493968Y1559527I-200J0D01*
G02Y1562443I1661J1458D01*
G03X1494018Y1562575I-150J132D01*
G01Y1564513D01*
G03X1493968Y1564645I-200J0D01*
G02Y1567561I1661J1458D01*
G03X1494018Y1567693I-150J132D01*
G01Y1568314D01*
G02X1494220Y1568516I202J0D01*
G01X1497040D01*
G02X1497242Y1568313I-1J-203D01*
G01Y1567693D01*
G03X1497292Y1567561I200J0D01*
G02Y1564645I-1661J-1458D01*
G03X1497242Y1564513I150J-132D01*
G01Y1562575D01*
G03X1497292Y1562443I200J0D01*
G02Y1559527I-1661J-1458D01*
G03X1497242Y1559395I150J-132D01*
G01Y1558774D01*
G37*
G36*
G01X1511543Y1568516D02*
X1514363D01*
G02X1514566Y1568313I0J-203D01*
G01Y1567691D01*
G03X1514616Y1567559I200J0D01*
G02Y1564647I-1664J-1456D01*
G03X1514566Y1564515I150J-132D01*
G01Y1562573D01*
G03X1514616Y1562441I200J0D01*
G02Y1559529I-1664J-1456D01*
G03X1514566Y1559397I150J-132D01*
G01Y1558775D01*
G02X1514363Y1558572I-203J0D01*
G01X1511543D01*
G02X1511340Y1558775I0J203D01*
G01Y1559397D01*
G03X1511290Y1559529I-200J0D01*
G02Y1562441I1664J1456D01*
G03X1511340Y1562573I-150J132D01*
G01Y1564515D01*
G03X1511290Y1564647I-200J0D01*
G02Y1567559I1664J1456D01*
G03X1511340Y1567691I-150J132D01*
G01Y1568313D01*
G02X1511543Y1568516I203J0D01*
G37*
G36*
G01X1528865D02*
X1531685D01*
G02X1531888Y1568313I0J-203D01*
G01Y1567691D01*
G03X1531938Y1567559I200J0D01*
G02Y1564647I-1664J-1456D01*
G03X1531888Y1564515I150J-132D01*
G01Y1562573D01*
G03X1531938Y1562441I200J0D01*
G02Y1559529I-1664J-1456D01*
G03X1531888Y1559397I150J-132D01*
G01Y1558775D01*
G02X1531685Y1558572I-203J0D01*
G01X1528865D01*
G02X1528662Y1558775I0J203D01*
G01Y1559397D01*
G03X1528612Y1559529I-200J0D01*
G02Y1562441I1664J1456D01*
G03X1528662Y1562573I-150J132D01*
G01Y1564515D01*
G03X1528612Y1564647I-200J0D01*
G02Y1567559I1664J1456D01*
G03X1528662Y1567691I-150J132D01*
G01Y1568313D01*
G02X1528865Y1568516I203J0D01*
G37*
G36*
G01X463590Y1572846D02*
X466410D01*
G02X466612Y1572644I0J-202D01*
G01Y1572024D01*
G03X466662Y1571892I200J0D01*
G02Y1568976I-1661J-1458D01*
G03X466612Y1568844I150J-132D01*
G01Y1566905D01*
G03X466662Y1566773I200J0D01*
G02Y1563857I-1661J-1458D01*
G03X466612Y1563725I150J-132D01*
G01Y1563106D01*
G02X466410Y1562904I-202J0D01*
G01X463590D01*
G02X463388Y1563106I0J202D01*
G01Y1563725D01*
G03X463338Y1563857I-200J0D01*
G02Y1566773I1661J1458D01*
G03X463388Y1566905I-150J132D01*
G01Y1568844D01*
G03X463338Y1568976I-200J0D01*
G02Y1571892I1661J1458D01*
G03X463388Y1572024I-150J132D01*
G01Y1572644D01*
G02X463590Y1572846I202J0D01*
G37*
G36*
G01X498236D02*
X501056D01*
G02X501258Y1572644I0J-202D01*
G01Y1572024D01*
G03X501308Y1571892I200J0D01*
G02Y1568976I-1661J-1458D01*
G03X501258Y1568844I150J-132D01*
G01Y1566905D01*
G03X501308Y1566773I200J0D01*
G02Y1563857I-1661J-1458D01*
G03X501258Y1563725I150J-132D01*
G01Y1563106D01*
G02X501056Y1562904I-202J0D01*
G01X498236D01*
G02X498034Y1563106I0J202D01*
G01Y1563725D01*
G03X497984Y1563857I-200J0D01*
G02Y1566773I1661J1458D01*
G03X498034Y1566905I-150J132D01*
G01Y1568844D01*
G03X497984Y1568976I-200J0D01*
G02Y1571892I1661J1458D01*
G03X498034Y1572024I-150J132D01*
G01Y1572644D01*
G02X498236Y1572846I202J0D01*
G37*
G36*
G01X1485558D02*
X1488378D01*
G02X1488580Y1572644I0J-202D01*
G01Y1572024D01*
G03X1488630Y1571892I200J0D01*
G02Y1568976I-1661J-1458D01*
G03X1488580Y1568844I150J-132D01*
G01Y1566905D01*
G03X1488630Y1566773I200J0D01*
G02Y1563857I-1661J-1458D01*
G03X1488580Y1563725I150J-132D01*
G01Y1563106D01*
G02X1488378Y1562904I-202J0D01*
G01X1485558D01*
G02X1485356Y1563106I0J202D01*
G01Y1563725D01*
G03X1485306Y1563857I-200J0D01*
G02Y1566773I1661J1458D01*
G03X1485356Y1566905I-150J132D01*
G01Y1568844D01*
G03X1485306Y1568976I-200J0D01*
G02Y1571892I1661J1458D01*
G03X1485356Y1572024I-150J132D01*
G01Y1572644D01*
G02X1485558Y1572846I202J0D01*
G37*
G36*
G01X1520204D02*
X1523024D01*
G02X1523226Y1572644I0J-202D01*
G01Y1572024D01*
G03X1523276Y1571892I200J0D01*
G02Y1568976I-1661J-1458D01*
G03X1523226Y1568844I150J-132D01*
G01Y1566905D01*
G03X1523276Y1566773I200J0D01*
G02Y1563857I-1661J-1458D01*
G03X1523226Y1563725I150J-132D01*
G01Y1563106D01*
G02X1523024Y1562904I-202J0D01*
G01X1520204D01*
G02X1520002Y1563106I0J202D01*
G01Y1563725D01*
G03X1519952Y1563857I-200J0D01*
G02Y1566773I1661J1458D01*
G03X1520002Y1566905I-150J132D01*
G01Y1568844D01*
G03X1519952Y1568976I-200J0D01*
G02Y1571892I1661J1458D01*
G03X1520002Y1572024I-150J132D01*
G01Y1572644D01*
G02X1520204Y1572846I202J0D01*
G37*
G36*
G01X480912Y1562904D02*
G02X480710Y1563106I0J202D01*
G01Y1563727D01*
G03X480660Y1563859I-200J0D01*
G02Y1566771I1664J1456D01*
G03X480710Y1566903I-150J132D01*
G01Y1568846D01*
G03X480660Y1568978I-200J0D01*
G02Y1571890I1664J1456D01*
G03X480710Y1572022I-150J132D01*
G01Y1572644D01*
G02X480913Y1572846I203J-1D01*
G01X483734D01*
G02X483936Y1572644I0J-202D01*
G01Y1572022D01*
G03X483986Y1571890I200J0D01*
G02Y1568978I-1664J-1456D01*
G03X483936Y1568846I150J-132D01*
G01Y1566903D01*
G03X483986Y1566771I200J0D01*
G02Y1563859I-1664J-1456D01*
G03X483936Y1563727I150J-132D01*
G01Y1563106D01*
G02X483733Y1562904I-203J1D01*
G01X480912D01*
G37*
G36*
G01X1502880D02*
G02X1502678Y1563106I0J202D01*
G01Y1563727D01*
G03X1502628Y1563859I-200J0D01*
G02Y1566771I1664J1456D01*
G03X1502678Y1566903I-150J132D01*
G01Y1568846D01*
G03X1502628Y1568978I-200J0D01*
G02Y1571890I1664J1456D01*
G03X1502678Y1572022I-150J132D01*
G01Y1572644D01*
G02X1502881Y1572846I203J-1D01*
G01X1505702D01*
G02X1505904Y1572644I0J-202D01*
G01Y1572022D01*
G03X1505954Y1571890I200J0D01*
G02Y1568978I-1664J-1456D01*
G03X1505904Y1568846I150J-132D01*
G01Y1566903D01*
G03X1505954Y1566771I200J0D01*
G02Y1563859I-1664J-1456D01*
G03X1505904Y1563727I150J-132D01*
G01Y1563106D01*
G02X1505701Y1562904I-203J1D01*
G01X1502880D01*
G37*
G36*
G01X1537526D02*
G02X1537324Y1563106I0J202D01*
G01Y1563727D01*
G03X1537274Y1563859I-200J0D01*
G02Y1566771I1664J1456D01*
G03X1537324Y1566903I-150J132D01*
G01Y1568846D01*
G03X1537274Y1568978I-200J0D01*
G02Y1571890I1664J1456D01*
G03X1537324Y1572022I-150J132D01*
G01Y1572644D01*
G02X1537527Y1572846I203J-1D01*
G01X1540348D01*
G02X1540550Y1572644I0J-202D01*
G01Y1572022D01*
G03X1540600Y1571890I200J0D01*
G02Y1568978I-1664J-1456D01*
G03X1540550Y1568846I150J-132D01*
G01Y1566903D01*
G03X1540600Y1566771I200J0D01*
G02Y1563859I-1664J-1456D01*
G03X1540550Y1563727I150J-132D01*
G01Y1563106D01*
G02X1540347Y1562904I-203J1D01*
G01X1537526D01*
G37*
G36*
G01X454929Y1583870D02*
X457749D01*
G02X457952Y1583667I0J-203D01*
G01Y1583045D01*
G03X458002Y1582913I200J0D01*
G02Y1580001I-1664J-1456D01*
G03X457952Y1579869I150J-132D01*
G01Y1577927D01*
G03X458002Y1577795I200J0D01*
G02Y1574883I-1664J-1456D01*
G03X457952Y1574751I150J-132D01*
G01Y1574129D01*
G02X457749Y1573926I-203J0D01*
G01X454929D01*
G02X454726Y1574129I0J203D01*
G01Y1574751D01*
G03X454676Y1574883I-200J0D01*
G02Y1577795I1664J1456D01*
G03X454726Y1577927I-150J132D01*
G01Y1579869D01*
G03X454676Y1580001I-200J0D01*
G02Y1582913I1664J1456D01*
G03X454726Y1583045I-150J132D01*
G01Y1583667D01*
G02X454929Y1583870I203J0D01*
G37*
G36*
G01X475274Y1574128D02*
G02X475072Y1573926I-202J0D01*
G01X472252D01*
G02X472050Y1574129I1J203D01*
G01Y1574749D01*
G03X472000Y1574881I-200J0D01*
G02Y1577797I1661J1458D01*
G03X472050Y1577929I-150J132D01*
G01Y1579867D01*
G03X472000Y1579999I-200J0D01*
G02Y1582915I1661J1458D01*
G03X472050Y1583047I-150J132D01*
G01Y1583668D01*
G02X472252Y1583870I202J0D01*
G01X475072D01*
G02X475274Y1583667I-1J-203D01*
G01Y1583047D01*
G03X475324Y1582915I200J0D01*
G02Y1579999I-1661J-1458D01*
G03X475274Y1579867I150J-132D01*
G01Y1577929D01*
G03X475324Y1577797I200J0D01*
G02Y1574881I-1661J-1458D01*
G03X475274Y1574749I150J-132D01*
G01Y1574128D01*
G37*
G36*
G01X489575Y1583870D02*
X492395D01*
G02X492598Y1583667I0J-203D01*
G01Y1583045D01*
G03X492648Y1582913I200J0D01*
G02Y1580001I-1664J-1456D01*
G03X492598Y1579869I150J-132D01*
G01Y1577927D01*
G03X492648Y1577795I200J0D01*
G02Y1574883I-1664J-1456D01*
G03X492598Y1574751I150J-132D01*
G01Y1574129D01*
G02X492395Y1573926I-203J0D01*
G01X489575D01*
G02X489372Y1574129I0J203D01*
G01Y1574751D01*
G03X489322Y1574883I-200J0D01*
G02Y1577795I1664J1456D01*
G03X489372Y1577927I-150J132D01*
G01Y1579869D01*
G03X489322Y1580001I-200J0D01*
G02Y1582913I1664J1456D01*
G03X489372Y1583045I-150J132D01*
G01Y1583667D01*
G02X489575Y1583870I203J0D01*
G37*
G36*
G01X506897D02*
X509717D01*
G02X509920Y1583667I0J-203D01*
G01Y1583045D01*
G03X509970Y1582913I200J0D01*
G02Y1580001I-1664J-1456D01*
G03X509920Y1579869I150J-132D01*
G01Y1577927D01*
G03X509970Y1577795I200J0D01*
G02Y1574883I-1664J-1456D01*
G03X509920Y1574751I150J-132D01*
G01Y1574129D01*
G02X509717Y1573926I-203J0D01*
G01X506897D01*
G02X506694Y1574129I0J203D01*
G01Y1574751D01*
G03X506644Y1574883I-200J0D01*
G02Y1577795I1664J1456D01*
G03X506694Y1577927I-150J132D01*
G01Y1579869D01*
G03X506644Y1580001I-200J0D01*
G02Y1582913I1664J1456D01*
G03X506694Y1583045I-150J132D01*
G01Y1583667D01*
G02X506897Y1583870I203J0D01*
G37*
G36*
G01X1497242Y1574128D02*
G02X1497040Y1573926I-202J0D01*
G01X1494220D01*
G02X1494018Y1574129I1J203D01*
G01Y1574749D01*
G03X1493968Y1574881I-200J0D01*
G02Y1577797I1661J1458D01*
G03X1494018Y1577929I-150J132D01*
G01Y1579867D01*
G03X1493968Y1579999I-200J0D01*
G02Y1582915I1661J1458D01*
G03X1494018Y1583047I-150J132D01*
G01Y1583668D01*
G02X1494220Y1583870I202J0D01*
G01X1497040D01*
G02X1497242Y1583667I-1J-203D01*
G01Y1583047D01*
G03X1497292Y1582915I200J0D01*
G02Y1579999I-1661J-1458D01*
G03X1497242Y1579867I150J-132D01*
G01Y1577929D01*
G03X1497292Y1577797I200J0D01*
G02Y1574881I-1661J-1458D01*
G03X1497242Y1574749I150J-132D01*
G01Y1574128D01*
G37*
G36*
G01X1511543Y1583870D02*
X1514363D01*
G02X1514566Y1583667I0J-203D01*
G01Y1583045D01*
G03X1514616Y1582913I200J0D01*
G02Y1580001I-1664J-1456D01*
G03X1514566Y1579869I150J-132D01*
G01Y1577927D01*
G03X1514616Y1577795I200J0D01*
G02Y1574883I-1664J-1456D01*
G03X1514566Y1574751I150J-132D01*
G01Y1574129D01*
G02X1514363Y1573926I-203J0D01*
G01X1511543D01*
G02X1511340Y1574129I0J203D01*
G01Y1574751D01*
G03X1511290Y1574883I-200J0D01*
G02Y1577795I1664J1456D01*
G03X1511340Y1577927I-150J132D01*
G01Y1579869D01*
G03X1511290Y1580001I-200J0D01*
G02Y1582913I1664J1456D01*
G03X1511340Y1583045I-150J132D01*
G01Y1583667D01*
G02X1511543Y1583870I203J0D01*
G37*
G36*
G01X1528865D02*
X1531685D01*
G02X1531888Y1583667I0J-203D01*
G01Y1583045D01*
G03X1531938Y1582913I200J0D01*
G02Y1580001I-1664J-1456D01*
G03X1531888Y1579869I150J-132D01*
G01Y1577927D01*
G03X1531938Y1577795I200J0D01*
G02Y1574883I-1664J-1456D01*
G03X1531888Y1574751I150J-132D01*
G01Y1574129D01*
G02X1531685Y1573926I-203J0D01*
G01X1528865D01*
G02X1528662Y1574129I0J203D01*
G01Y1574751D01*
G03X1528612Y1574883I-200J0D01*
G02Y1577795I1664J1456D01*
G03X1528662Y1577927I-150J132D01*
G01Y1579869D01*
G03X1528612Y1580001I-200J0D01*
G02Y1582913I1664J1456D01*
G03X1528662Y1583045I-150J132D01*
G01Y1583667D01*
G02X1528865Y1583870I203J0D01*
G37*
G36*
G01X463590Y1588200D02*
X466410D01*
G02X466612Y1587998I0J-202D01*
G01Y1587378D01*
G03X466662Y1587246I200J0D01*
G02Y1584330I-1661J-1458D01*
G03X466612Y1584198I150J-132D01*
G01Y1582260D01*
G03X466662Y1582128I200J0D01*
G02Y1579212I-1661J-1458D01*
G03X466612Y1579080I150J-132D01*
G01Y1578460D01*
G02X466410Y1578258I-202J0D01*
G01X463590D01*
G02X463388Y1578460I0J202D01*
G01Y1579080D01*
G03X463338Y1579212I-200J0D01*
G02Y1582128I1661J1458D01*
G03X463388Y1582260I-150J132D01*
G01Y1584198D01*
G03X463338Y1584330I-200J0D01*
G02Y1587246I1661J1458D01*
G03X463388Y1587378I-150J132D01*
G01Y1587998D01*
G02X463590Y1588200I202J0D01*
G37*
G36*
G01X498236D02*
X501056D01*
G02X501258Y1587998I0J-202D01*
G01Y1587378D01*
G03X501308Y1587246I200J0D01*
G02Y1584330I-1661J-1458D01*
G03X501258Y1584198I150J-132D01*
G01Y1582260D01*
G03X501308Y1582128I200J0D01*
G02Y1579212I-1661J-1458D01*
G03X501258Y1579080I150J-132D01*
G01Y1578460D01*
G02X501056Y1578258I-202J0D01*
G01X498236D01*
G02X498034Y1578460I0J202D01*
G01Y1579080D01*
G03X497984Y1579212I-200J0D01*
G02Y1582128I1661J1458D01*
G03X498034Y1582260I-150J132D01*
G01Y1584198D01*
G03X497984Y1584330I-200J0D01*
G02Y1587246I1661J1458D01*
G03X498034Y1587378I-150J132D01*
G01Y1587998D01*
G02X498236Y1588200I202J0D01*
G37*
G36*
G01X1485558D02*
X1488378D01*
G02X1488580Y1587998I0J-202D01*
G01Y1587378D01*
G03X1488630Y1587246I200J0D01*
G02Y1584330I-1661J-1458D01*
G03X1488580Y1584198I150J-132D01*
G01Y1582260D01*
G03X1488630Y1582128I200J0D01*
G02Y1579212I-1661J-1458D01*
G03X1488580Y1579080I150J-132D01*
G01Y1578460D01*
G02X1488378Y1578258I-202J0D01*
G01X1485558D01*
G02X1485356Y1578460I0J202D01*
G01Y1579080D01*
G03X1485306Y1579212I-200J0D01*
G02Y1582128I1661J1458D01*
G03X1485356Y1582260I-150J132D01*
G01Y1584198D01*
G03X1485306Y1584330I-200J0D01*
G02Y1587246I1661J1458D01*
G03X1485356Y1587378I-150J132D01*
G01Y1587998D01*
G02X1485558Y1588200I202J0D01*
G37*
G36*
G01X1520204D02*
X1523024D01*
G02X1523226Y1587998I0J-202D01*
G01Y1587378D01*
G03X1523276Y1587246I200J0D01*
G02Y1584330I-1661J-1458D01*
G03X1523226Y1584198I150J-132D01*
G01Y1582260D01*
G03X1523276Y1582128I200J0D01*
G02Y1579212I-1661J-1458D01*
G03X1523226Y1579080I150J-132D01*
G01Y1578460D01*
G02X1523024Y1578258I-202J0D01*
G01X1520204D01*
G02X1520002Y1578460I0J202D01*
G01Y1579080D01*
G03X1519952Y1579212I-200J0D01*
G02Y1582128I1661J1458D01*
G03X1520002Y1582260I-150J132D01*
G01Y1584198D01*
G03X1519952Y1584330I-200J0D01*
G02Y1587246I1661J1458D01*
G03X1520002Y1587378I-150J132D01*
G01Y1587998D01*
G02X1520204Y1588200I202J0D01*
G37*
G36*
G01X480912Y1578258D02*
G02X480710Y1578460I0J202D01*
G01Y1579082D01*
G03X480660Y1579214I-200J0D01*
G02Y1582126I1664J1456D01*
G03X480710Y1582258I-150J132D01*
G01Y1584200D01*
G03X480660Y1584332I-200J0D01*
G02Y1587244I1664J1456D01*
G03X480710Y1587376I-150J132D01*
G01Y1587998D01*
G02X480913Y1588200I203J-1D01*
G01X483734D01*
G02X483936Y1587998I0J-202D01*
G01Y1587376D01*
G03X483986Y1587244I200J0D01*
G02Y1584332I-1664J-1456D01*
G03X483936Y1584200I150J-132D01*
G01Y1582258D01*
G03X483986Y1582126I200J0D01*
G02Y1579214I-1664J-1456D01*
G03X483936Y1579082I150J-132D01*
G01Y1578460D01*
G02X483733Y1578258I-203J1D01*
G01X480912D01*
G37*
G36*
G01X1502880D02*
G02X1502678Y1578460I0J202D01*
G01Y1579082D01*
G03X1502628Y1579214I-200J0D01*
G02Y1582126I1664J1456D01*
G03X1502678Y1582258I-150J132D01*
G01Y1584200D01*
G03X1502628Y1584332I-200J0D01*
G02Y1587244I1664J1456D01*
G03X1502678Y1587376I-150J132D01*
G01Y1587998D01*
G02X1502881Y1588200I203J-1D01*
G01X1505702D01*
G02X1505904Y1587998I0J-202D01*
G01Y1587376D01*
G03X1505954Y1587244I200J0D01*
G02Y1584332I-1664J-1456D01*
G03X1505904Y1584200I150J-132D01*
G01Y1582258D01*
G03X1505954Y1582126I200J0D01*
G02Y1579214I-1664J-1456D01*
G03X1505904Y1579082I150J-132D01*
G01Y1578460D01*
G02X1505701Y1578258I-203J1D01*
G01X1502880D01*
G37*
G36*
G01X1537526D02*
G02X1537324Y1578460I0J202D01*
G01Y1579082D01*
G03X1537274Y1579214I-200J0D01*
G02Y1582126I1664J1456D01*
G03X1537324Y1582258I-150J132D01*
G01Y1584200D01*
G03X1537274Y1584332I-200J0D01*
G02Y1587244I1664J1456D01*
G03X1537324Y1587376I-150J132D01*
G01Y1587998D01*
G02X1537527Y1588200I203J-1D01*
G01X1540348D01*
G02X1540550Y1587998I0J-202D01*
G01Y1587376D01*
G03X1540600Y1587244I200J0D01*
G02Y1584332I-1664J-1456D01*
G03X1540550Y1584200I150J-132D01*
G01Y1582258D01*
G03X1540600Y1582126I200J0D01*
G02Y1579214I-1664J-1456D01*
G03X1540550Y1579082I150J-132D01*
G01Y1578460D01*
G02X1540347Y1578258I-203J1D01*
G01X1537526D01*
G37*
G36*
G01X454929Y1599224D02*
X457749D01*
G02X457952Y1599021I0J-203D01*
G01Y1598399D01*
G03X458002Y1598267I200J0D01*
G02Y1595355I-1664J-1456D01*
G03X457952Y1595223I150J-132D01*
G01Y1593281D01*
G03X458002Y1593149I200J0D01*
G02Y1590237I-1664J-1456D01*
G03X457952Y1590105I150J-132D01*
G01Y1589483D01*
G02X457749Y1589280I-203J0D01*
G01X454929D01*
G02X454726Y1589483I0J203D01*
G01Y1590105D01*
G03X454676Y1590237I-200J0D01*
G02Y1593149I1664J1456D01*
G03X454726Y1593281I-150J132D01*
G01Y1595223D01*
G03X454676Y1595355I-200J0D01*
G02Y1598267I1664J1456D01*
G03X454726Y1598399I-150J132D01*
G01Y1599021D01*
G02X454929Y1599224I203J0D01*
G37*
G36*
G01X475274Y1589482D02*
G02X475072Y1589280I-202J0D01*
G01X472252D01*
G02X472050Y1589483I1J203D01*
G01Y1590103D01*
G03X472000Y1590235I-200J0D01*
G02Y1593151I1661J1458D01*
G03X472050Y1593283I-150J132D01*
G01Y1595221D01*
G03X472000Y1595353I-200J0D01*
G02Y1598269I1661J1458D01*
G03X472050Y1598401I-150J132D01*
G01Y1599022D01*
G02X472252Y1599224I202J0D01*
G01X475072D01*
G02X475274Y1599021I-1J-203D01*
G01Y1598401D01*
G03X475324Y1598269I200J0D01*
G02Y1595353I-1661J-1458D01*
G03X475274Y1595221I150J-132D01*
G01Y1593283D01*
G03X475324Y1593151I200J0D01*
G02Y1590235I-1661J-1458D01*
G03X475274Y1590103I150J-132D01*
G01Y1589482D01*
G37*
G36*
G01X489575Y1599224D02*
X492395D01*
G02X492598Y1599021I0J-203D01*
G01Y1598399D01*
G03X492648Y1598267I200J0D01*
G02Y1595355I-1664J-1456D01*
G03X492598Y1595223I150J-132D01*
G01Y1593281D01*
G03X492648Y1593149I200J0D01*
G02Y1590237I-1664J-1456D01*
G03X492598Y1590105I150J-132D01*
G01Y1589483D01*
G02X492395Y1589280I-203J0D01*
G01X489575D01*
G02X489372Y1589483I0J203D01*
G01Y1590105D01*
G03X489322Y1590237I-200J0D01*
G02Y1593149I1664J1456D01*
G03X489372Y1593281I-150J132D01*
G01Y1595223D01*
G03X489322Y1595355I-200J0D01*
G02Y1598267I1664J1456D01*
G03X489372Y1598399I-150J132D01*
G01Y1599021D01*
G02X489575Y1599224I203J0D01*
G37*
G36*
G01X506897D02*
X509717D01*
G02X509920Y1599021I0J-203D01*
G01Y1598399D01*
G03X509970Y1598267I200J0D01*
G02Y1595355I-1664J-1456D01*
G03X509920Y1595223I150J-132D01*
G01Y1593281D01*
G03X509970Y1593149I200J0D01*
G02Y1590237I-1664J-1456D01*
G03X509920Y1590105I150J-132D01*
G01Y1589483D01*
G02X509717Y1589280I-203J0D01*
G01X506897D01*
G02X506694Y1589483I0J203D01*
G01Y1590105D01*
G03X506644Y1590237I-200J0D01*
G02Y1593149I1664J1456D01*
G03X506694Y1593281I-150J132D01*
G01Y1595223D01*
G03X506644Y1595355I-200J0D01*
G02Y1598267I1664J1456D01*
G03X506694Y1598399I-150J132D01*
G01Y1599021D01*
G02X506897Y1599224I203J0D01*
G37*
G36*
G01X1497242Y1589482D02*
G02X1497040Y1589280I-202J0D01*
G01X1494220D01*
G02X1494018Y1589483I1J203D01*
G01Y1590103D01*
G03X1493968Y1590235I-200J0D01*
G02Y1593151I1661J1458D01*
G03X1494018Y1593283I-150J132D01*
G01Y1595221D01*
G03X1493968Y1595353I-200J0D01*
G02Y1598269I1661J1458D01*
G03X1494018Y1598401I-150J132D01*
G01Y1599022D01*
G02X1494220Y1599224I202J0D01*
G01X1497040D01*
G02X1497242Y1599021I-1J-203D01*
G01Y1598401D01*
G03X1497292Y1598269I200J0D01*
G02Y1595353I-1661J-1458D01*
G03X1497242Y1595221I150J-132D01*
G01Y1593283D01*
G03X1497292Y1593151I200J0D01*
G02Y1590235I-1661J-1458D01*
G03X1497242Y1590103I150J-132D01*
G01Y1589482D01*
G37*
G36*
G01X1511543Y1599224D02*
X1514363D01*
G02X1514566Y1599021I0J-203D01*
G01Y1598399D01*
G03X1514616Y1598267I200J0D01*
G02Y1595355I-1664J-1456D01*
G03X1514566Y1595223I150J-132D01*
G01Y1593281D01*
G03X1514616Y1593149I200J0D01*
G02Y1590237I-1664J-1456D01*
G03X1514566Y1590105I150J-132D01*
G01Y1589483D01*
G02X1514363Y1589280I-203J0D01*
G01X1511543D01*
G02X1511340Y1589483I0J203D01*
G01Y1590105D01*
G03X1511290Y1590237I-200J0D01*
G02Y1593149I1664J1456D01*
G03X1511340Y1593281I-150J132D01*
G01Y1595223D01*
G03X1511290Y1595355I-200J0D01*
G02Y1598267I1664J1456D01*
G03X1511340Y1598399I-150J132D01*
G01Y1599021D01*
G02X1511543Y1599224I203J0D01*
G37*
G36*
G01X1528865D02*
X1531685D01*
G02X1531888Y1599021I0J-203D01*
G01Y1598399D01*
G03X1531938Y1598267I200J0D01*
G02Y1595355I-1664J-1456D01*
G03X1531888Y1595223I150J-132D01*
G01Y1593281D01*
G03X1531938Y1593149I200J0D01*
G02Y1590237I-1664J-1456D01*
G03X1531888Y1590105I150J-132D01*
G01Y1589483D01*
G02X1531685Y1589280I-203J0D01*
G01X1528865D01*
G02X1528662Y1589483I0J203D01*
G01Y1590105D01*
G03X1528612Y1590237I-200J0D01*
G02Y1593149I1664J1456D01*
G03X1528662Y1593281I-150J132D01*
G01Y1595223D01*
G03X1528612Y1595355I-200J0D01*
G02Y1598267I1664J1456D01*
G03X1528662Y1598399I-150J132D01*
G01Y1599021D01*
G02X1528865Y1599224I203J0D01*
G37*
G36*
G01X463590Y1603554D02*
X466410D01*
G02X466612Y1603352I0J-202D01*
G01Y1602732D01*
G03X466662Y1602600I200J0D01*
G02Y1599684I-1661J-1458D01*
G03X466612Y1599552I150J-132D01*
G01Y1597614D01*
G03X466662Y1597482I200J0D01*
G02Y1594566I-1661J-1458D01*
G03X466612Y1594434I150J-132D01*
G01Y1593814D01*
G02X466410Y1593612I-202J0D01*
G01X463590D01*
G02X463388Y1593814I0J202D01*
G01Y1594434D01*
G03X463338Y1594566I-200J0D01*
G02Y1597482I1661J1458D01*
G03X463388Y1597614I-150J132D01*
G01Y1599552D01*
G03X463338Y1599684I-200J0D01*
G02Y1602600I1661J1458D01*
G03X463388Y1602732I-150J132D01*
G01Y1603352D01*
G02X463590Y1603554I202J0D01*
G37*
G36*
G01X498236D02*
X501056D01*
G02X501258Y1603352I0J-202D01*
G01Y1602732D01*
G03X501308Y1602600I200J0D01*
G02Y1599684I-1661J-1458D01*
G03X501258Y1599552I150J-132D01*
G01Y1597614D01*
G03X501308Y1597482I200J0D01*
G02Y1594566I-1661J-1458D01*
G03X501258Y1594434I150J-132D01*
G01Y1593814D01*
G02X501056Y1593612I-202J0D01*
G01X498236D01*
G02X498034Y1593814I0J202D01*
G01Y1594434D01*
G03X497984Y1594566I-200J0D01*
G02Y1597482I1661J1458D01*
G03X498034Y1597614I-150J132D01*
G01Y1599552D01*
G03X497984Y1599684I-200J0D01*
G02Y1602600I1661J1458D01*
G03X498034Y1602732I-150J132D01*
G01Y1603352D01*
G02X498236Y1603554I202J0D01*
G37*
G36*
G01X1485558D02*
X1488378D01*
G02X1488580Y1603352I0J-202D01*
G01Y1602732D01*
G03X1488630Y1602600I200J0D01*
G02Y1599684I-1661J-1458D01*
G03X1488580Y1599552I150J-132D01*
G01Y1597614D01*
G03X1488630Y1597482I200J0D01*
G02Y1594566I-1661J-1458D01*
G03X1488580Y1594434I150J-132D01*
G01Y1593814D01*
G02X1488378Y1593612I-202J0D01*
G01X1485558D01*
G02X1485356Y1593814I0J202D01*
G01Y1594434D01*
G03X1485306Y1594566I-200J0D01*
G02Y1597482I1661J1458D01*
G03X1485356Y1597614I-150J132D01*
G01Y1599552D01*
G03X1485306Y1599684I-200J0D01*
G02Y1602600I1661J1458D01*
G03X1485356Y1602732I-150J132D01*
G01Y1603352D01*
G02X1485558Y1603554I202J0D01*
G37*
G36*
G01X1520204D02*
X1523024D01*
G02X1523226Y1603352I0J-202D01*
G01Y1602732D01*
G03X1523276Y1602600I200J0D01*
G02Y1599684I-1661J-1458D01*
G03X1523226Y1599552I150J-132D01*
G01Y1597614D01*
G03X1523276Y1597482I200J0D01*
G02Y1594566I-1661J-1458D01*
G03X1523226Y1594434I150J-132D01*
G01Y1593814D01*
G02X1523024Y1593612I-202J0D01*
G01X1520204D01*
G02X1520002Y1593814I0J202D01*
G01Y1594434D01*
G03X1519952Y1594566I-200J0D01*
G02Y1597482I1661J1458D01*
G03X1520002Y1597614I-150J132D01*
G01Y1599552D01*
G03X1519952Y1599684I-200J0D01*
G02Y1602600I1661J1458D01*
G03X1520002Y1602732I-150J132D01*
G01Y1603352D01*
G02X1520204Y1603554I202J0D01*
G37*
G36*
G01X480912Y1593612D02*
G02X480710Y1593814I0J202D01*
G01Y1594436D01*
G03X480660Y1594568I-200J0D01*
G02Y1597480I1664J1456D01*
G03X480710Y1597612I-150J132D01*
G01Y1599554D01*
G03X480660Y1599686I-200J0D01*
G02Y1602598I1664J1456D01*
G03X480710Y1602730I-150J132D01*
G01Y1603352D01*
G02X480913Y1603554I203J-1D01*
G01X483734D01*
G02X483936Y1603352I0J-202D01*
G01Y1602730D01*
G03X483986Y1602598I200J0D01*
G02Y1599686I-1664J-1456D01*
G03X483936Y1599554I150J-132D01*
G01Y1597612D01*
G03X483986Y1597480I200J0D01*
G02Y1594568I-1664J-1456D01*
G03X483936Y1594436I150J-132D01*
G01Y1593814D01*
G02X483733Y1593612I-203J1D01*
G01X480912D01*
G37*
G36*
G01X1502880D02*
G02X1502678Y1593814I0J202D01*
G01Y1594436D01*
G03X1502628Y1594568I-200J0D01*
G02Y1597480I1664J1456D01*
G03X1502678Y1597612I-150J132D01*
G01Y1599554D01*
G03X1502628Y1599686I-200J0D01*
G02Y1602598I1664J1456D01*
G03X1502678Y1602730I-150J132D01*
G01Y1603352D01*
G02X1502881Y1603554I203J-1D01*
G01X1505702D01*
G02X1505904Y1603352I0J-202D01*
G01Y1602730D01*
G03X1505954Y1602598I200J0D01*
G02Y1599686I-1664J-1456D01*
G03X1505904Y1599554I150J-132D01*
G01Y1597612D01*
G03X1505954Y1597480I200J0D01*
G02Y1594568I-1664J-1456D01*
G03X1505904Y1594436I150J-132D01*
G01Y1593814D01*
G02X1505701Y1593612I-203J1D01*
G01X1502880D01*
G37*
G36*
G01X1537526D02*
G02X1537324Y1593814I0J202D01*
G01Y1594436D01*
G03X1537274Y1594568I-200J0D01*
G02Y1597480I1664J1456D01*
G03X1537324Y1597612I-150J132D01*
G01Y1599554D01*
G03X1537274Y1599686I-200J0D01*
G02Y1602598I1664J1456D01*
G03X1537324Y1602730I-150J132D01*
G01Y1603352D01*
G02X1537527Y1603554I203J-1D01*
G01X1540348D01*
G02X1540550Y1603352I0J-202D01*
G01Y1602730D01*
G03X1540600Y1602598I200J0D01*
G02Y1599686I-1664J-1456D01*
G03X1540550Y1599554I150J-132D01*
G01Y1597612D01*
G03X1540600Y1597480I200J0D01*
G02Y1594568I-1664J-1456D01*
G03X1540550Y1594436I150J-132D01*
G01Y1593814D01*
G02X1540347Y1593612I-203J1D01*
G01X1537526D01*
G37*
G36*
G01X472252Y1614578D02*
X475072D01*
G02X475274Y1614376I0J-202D01*
G01Y1613756D01*
G03X475324Y1613624I200J0D01*
G02Y1610708I-1661J-1458D01*
G03X475274Y1610576I150J-132D01*
G01Y1608638D01*
G03X475324Y1608506I200J0D01*
G02Y1605590I-1661J-1458D01*
G03X475274Y1605458I150J-132D01*
G01Y1604838D01*
G02X475072Y1604636I-202J0D01*
G01X472252D01*
G02X472050Y1604838I0J202D01*
G01Y1605458D01*
G03X472000Y1605590I-200J0D01*
G02Y1608506I1661J1458D01*
G03X472050Y1608638I-150J132D01*
G01Y1610576D01*
G03X472000Y1610708I-200J0D01*
G02Y1613624I1661J1458D01*
G03X472050Y1613756I-150J132D01*
G01Y1614376D01*
G02X472252Y1614578I202J0D01*
G37*
G36*
G01X1494220D02*
X1497040D01*
G02X1497242Y1614376I0J-202D01*
G01Y1613756D01*
G03X1497292Y1613624I200J0D01*
G02Y1610708I-1661J-1458D01*
G03X1497242Y1610576I150J-132D01*
G01Y1608638D01*
G03X1497292Y1608506I200J0D01*
G02Y1605590I-1661J-1458D01*
G03X1497242Y1605458I150J-132D01*
G01Y1604838D01*
G02X1497040Y1604636I-202J0D01*
G01X1494220D01*
G02X1494018Y1604838I0J202D01*
G01Y1605458D01*
G03X1493968Y1605590I-200J0D01*
G02Y1608506I1661J1458D01*
G03X1494018Y1608638I-150J132D01*
G01Y1610576D01*
G03X1493968Y1610708I-200J0D01*
G02Y1613624I1661J1458D01*
G03X1494018Y1613756I-150J132D01*
G01Y1614376D01*
G02X1494220Y1614578I202J0D01*
G37*
G36*
G01X454928Y1604636D02*
G02X454726Y1604838I0J202D01*
G01Y1605460D01*
G03X454676Y1605592I-200J0D01*
G02Y1608504I1664J1456D01*
G03X454726Y1608636I-150J132D01*
G01Y1610578D01*
G03X454676Y1610710I-200J0D01*
G02Y1613622I1664J1456D01*
G03X454726Y1613754I-150J132D01*
G01Y1614376D01*
G02X454929Y1614578I203J-1D01*
G01X457750D01*
G02X457952Y1614376I0J-202D01*
G01Y1613754D01*
G03X458002Y1613622I200J0D01*
G02Y1610710I-1664J-1456D01*
G03X457952Y1610578I150J-132D01*
G01Y1608636D01*
G03X458002Y1608504I200J0D01*
G02Y1605592I-1664J-1456D01*
G03X457952Y1605460I150J-132D01*
G01Y1604838D01*
G02X457749Y1604636I-203J1D01*
G01X454928D01*
G37*
G36*
G01X489574D02*
G02X489372Y1604838I0J202D01*
G01Y1605460D01*
G03X489322Y1605592I-200J0D01*
G02Y1608504I1664J1456D01*
G03X489372Y1608636I-150J132D01*
G01Y1610578D01*
G03X489322Y1610710I-200J0D01*
G02Y1613622I1664J1456D01*
G03X489372Y1613754I-150J132D01*
G01Y1614376D01*
G02X489575Y1614578I203J-1D01*
G01X492396D01*
G02X492598Y1614376I0J-202D01*
G01Y1613754D01*
G03X492648Y1613622I200J0D01*
G02Y1610710I-1664J-1456D01*
G03X492598Y1610578I150J-132D01*
G01Y1608636D01*
G03X492648Y1608504I200J0D01*
G02Y1605592I-1664J-1456D01*
G03X492598Y1605460I150J-132D01*
G01Y1604838D01*
G02X492395Y1604636I-203J1D01*
G01X489574D01*
G37*
G36*
G01X506896D02*
G02X506694Y1604838I0J202D01*
G01Y1605460D01*
G03X506644Y1605592I-200J0D01*
G02Y1608504I1664J1456D01*
G03X506694Y1608636I-150J132D01*
G01Y1610578D01*
G03X506644Y1610710I-200J0D01*
G02Y1613622I1664J1456D01*
G03X506694Y1613754I-150J132D01*
G01Y1614376D01*
G02X506897Y1614578I203J-1D01*
G01X509718D01*
G02X509920Y1614376I0J-202D01*
G01Y1613754D01*
G03X509970Y1613622I200J0D01*
G02Y1610710I-1664J-1456D01*
G03X509920Y1610578I150J-132D01*
G01Y1608636D01*
G03X509970Y1608504I200J0D01*
G02Y1605592I-1664J-1456D01*
G03X509920Y1605460I150J-132D01*
G01Y1604838D01*
G02X509717Y1604636I-203J1D01*
G01X506896D01*
G37*
G36*
G01X1511542D02*
G02X1511340Y1604838I0J202D01*
G01Y1605460D01*
G03X1511290Y1605592I-200J0D01*
G02Y1608504I1664J1456D01*
G03X1511340Y1608636I-150J132D01*
G01Y1610578D01*
G03X1511290Y1610710I-200J0D01*
G02Y1613622I1664J1456D01*
G03X1511340Y1613754I-150J132D01*
G01Y1614376D01*
G02X1511543Y1614578I203J-1D01*
G01X1514364D01*
G02X1514566Y1614376I0J-202D01*
G01Y1613754D01*
G03X1514616Y1613622I200J0D01*
G02Y1610710I-1664J-1456D01*
G03X1514566Y1610578I150J-132D01*
G01Y1608636D01*
G03X1514616Y1608504I200J0D01*
G02Y1605592I-1664J-1456D01*
G03X1514566Y1605460I150J-132D01*
G01Y1604838D01*
G02X1514363Y1604636I-203J1D01*
G01X1511542D01*
G37*
G36*
G01X1528864D02*
G02X1528662Y1604838I0J202D01*
G01Y1605460D01*
G03X1528612Y1605592I-200J0D01*
G02Y1608504I1664J1456D01*
G03X1528662Y1608636I-150J132D01*
G01Y1610578D01*
G03X1528612Y1610710I-200J0D01*
G02Y1613622I1664J1456D01*
G03X1528662Y1613754I-150J132D01*
G01Y1614376D01*
G02X1528865Y1614578I203J-1D01*
G01X1531686D01*
G02X1531888Y1614376I0J-202D01*
G01Y1613754D01*
G03X1531938Y1613622I200J0D01*
G02Y1610710I-1664J-1456D01*
G03X1531888Y1610578I150J-132D01*
G01Y1608636D01*
G03X1531938Y1608504I200J0D01*
G02Y1605592I-1664J-1456D01*
G03X1531888Y1605460I150J-132D01*
G01Y1604838D01*
G02X1531685Y1604636I-203J1D01*
G01X1528864D01*
G37*
G36*
G01X463590Y1618908D02*
X466410D01*
G02X466612Y1618706I0J-202D01*
G01Y1618086D01*
G03X466662Y1617954I200J0D01*
G02Y1615038I-1661J-1458D01*
G03X466612Y1614906I150J-132D01*
G01Y1612968D01*
G03X466662Y1612836I200J0D01*
G02Y1609920I-1661J-1458D01*
G03X466612Y1609788I150J-132D01*
G01Y1609168D01*
G02X466410Y1608966I-202J0D01*
G01X463590D01*
G02X463388Y1609168I0J202D01*
G01Y1609788D01*
G03X463338Y1609920I-200J0D01*
G02Y1612836I1661J1458D01*
G03X463388Y1612968I-150J132D01*
G01Y1614906D01*
G03X463338Y1615038I-200J0D01*
G02Y1617954I1661J1458D01*
G03X463388Y1618086I-150J132D01*
G01Y1618706D01*
G02X463590Y1618908I202J0D01*
G37*
G36*
G01X498236D02*
X501056D01*
G02X501258Y1618706I0J-202D01*
G01Y1618086D01*
G03X501308Y1617954I200J0D01*
G02Y1615038I-1661J-1458D01*
G03X501258Y1614906I150J-132D01*
G01Y1612968D01*
G03X501308Y1612836I200J0D01*
G02Y1609920I-1661J-1458D01*
G03X501258Y1609788I150J-132D01*
G01Y1609168D01*
G02X501056Y1608966I-202J0D01*
G01X498236D01*
G02X498034Y1609168I0J202D01*
G01Y1609788D01*
G03X497984Y1609920I-200J0D01*
G02Y1612836I1661J1458D01*
G03X498034Y1612968I-150J132D01*
G01Y1614906D01*
G03X497984Y1615038I-200J0D01*
G02Y1617954I1661J1458D01*
G03X498034Y1618086I-150J132D01*
G01Y1618706D01*
G02X498236Y1618908I202J0D01*
G37*
G36*
G01X1485558D02*
X1488378D01*
G02X1488580Y1618706I0J-202D01*
G01Y1618086D01*
G03X1488630Y1617954I200J0D01*
G02Y1615038I-1661J-1458D01*
G03X1488580Y1614906I150J-132D01*
G01Y1612968D01*
G03X1488630Y1612836I200J0D01*
G02Y1609920I-1661J-1458D01*
G03X1488580Y1609788I150J-132D01*
G01Y1609168D01*
G02X1488378Y1608966I-202J0D01*
G01X1485558D01*
G02X1485356Y1609168I0J202D01*
G01Y1609788D01*
G03X1485306Y1609920I-200J0D01*
G02Y1612836I1661J1458D01*
G03X1485356Y1612968I-150J132D01*
G01Y1614906D01*
G03X1485306Y1615038I-200J0D01*
G02Y1617954I1661J1458D01*
G03X1485356Y1618086I-150J132D01*
G01Y1618706D01*
G02X1485558Y1618908I202J0D01*
G37*
G36*
G01X1520204D02*
X1523024D01*
G02X1523226Y1618706I0J-202D01*
G01Y1618086D01*
G03X1523276Y1617954I200J0D01*
G02Y1615038I-1661J-1458D01*
G03X1523226Y1614906I150J-132D01*
G01Y1612968D01*
G03X1523276Y1612836I200J0D01*
G02Y1609920I-1661J-1458D01*
G03X1523226Y1609788I150J-132D01*
G01Y1609168D01*
G02X1523024Y1608966I-202J0D01*
G01X1520204D01*
G02X1520002Y1609168I0J202D01*
G01Y1609788D01*
G03X1519952Y1609920I-200J0D01*
G02Y1612836I1661J1458D01*
G03X1520002Y1612968I-150J132D01*
G01Y1614906D01*
G03X1519952Y1615038I-200J0D01*
G02Y1617954I1661J1458D01*
G03X1520002Y1618086I-150J132D01*
G01Y1618706D01*
G02X1520204Y1618908I202J0D01*
G37*
G36*
G01X480912Y1608966D02*
G02X480710Y1609168I0J202D01*
G01Y1609790D01*
G03X480660Y1609922I-200J0D01*
G02Y1612834I1664J1456D01*
G03X480710Y1612966I-150J132D01*
G01Y1614908D01*
G03X480660Y1615040I-200J0D01*
G02Y1617952I1664J1456D01*
G03X480710Y1618084I-150J132D01*
G01Y1618706D01*
G02X480913Y1618908I203J-1D01*
G01X483734D01*
G02X483936Y1618706I0J-202D01*
G01Y1618084D01*
G03X483986Y1617952I200J0D01*
G02Y1615040I-1664J-1456D01*
G03X483936Y1614908I150J-132D01*
G01Y1612966D01*
G03X483986Y1612834I200J0D01*
G02Y1609922I-1664J-1456D01*
G03X483936Y1609790I150J-132D01*
G01Y1609168D01*
G02X483733Y1608966I-203J1D01*
G01X480912D01*
G37*
G36*
G01X1502880D02*
G02X1502678Y1609168I0J202D01*
G01Y1609790D01*
G03X1502628Y1609922I-200J0D01*
G02Y1612834I1664J1456D01*
G03X1502678Y1612966I-150J132D01*
G01Y1614908D01*
G03X1502628Y1615040I-200J0D01*
G02Y1617952I1664J1456D01*
G03X1502678Y1618084I-150J132D01*
G01Y1618706D01*
G02X1502881Y1618908I203J-1D01*
G01X1505702D01*
G02X1505904Y1618706I0J-202D01*
G01Y1618084D01*
G03X1505954Y1617952I200J0D01*
G02Y1615040I-1664J-1456D01*
G03X1505904Y1614908I150J-132D01*
G01Y1612966D01*
G03X1505954Y1612834I200J0D01*
G02Y1609922I-1664J-1456D01*
G03X1505904Y1609790I150J-132D01*
G01Y1609168D01*
G02X1505701Y1608966I-203J1D01*
G01X1502880D01*
G37*
G36*
G01X1537526D02*
G02X1537324Y1609168I0J202D01*
G01Y1609790D01*
G03X1537274Y1609922I-200J0D01*
G02Y1612834I1664J1456D01*
G03X1537324Y1612966I-150J132D01*
G01Y1614908D01*
G03X1537274Y1615040I-200J0D01*
G02Y1617952I1664J1456D01*
G03X1537324Y1618084I-150J132D01*
G01Y1618706D01*
G02X1537527Y1618908I203J-1D01*
G01X1540348D01*
G02X1540550Y1618706I0J-202D01*
G01Y1618084D01*
G03X1540600Y1617952I200J0D01*
G02Y1615040I-1664J-1456D01*
G03X1540550Y1614908I150J-132D01*
G01Y1612966D01*
G03X1540600Y1612834I200J0D01*
G02Y1609922I-1664J-1456D01*
G03X1540550Y1609790I150J-132D01*
G01Y1609168D01*
G02X1540347Y1608966I-203J1D01*
G01X1537526D01*
G37*
G36*
G01X125795Y1466154D02*
X128615D01*
G02X128818Y1465951I0J-203D01*
G01Y1465329D01*
G03X128868Y1465197I200J0D01*
G02Y1462285I-1664J-1456D01*
G03X128818Y1462153I150J-132D01*
G01Y1460210D01*
G03X128868Y1460078I200J0D01*
G02Y1457166I-1664J-1456D01*
G03X128818Y1457034I150J-132D01*
G01Y1456413D01*
G02X128615Y1456210I-203J0D01*
G01X125795D01*
G02X125592Y1456413I0J203D01*
G01Y1457034D01*
G03X125542Y1457166I-200J0D01*
G02Y1460078I1664J1456D01*
G03X125592Y1460210I-150J132D01*
G01Y1462153D01*
G03X125542Y1462285I-200J0D01*
G02Y1465197I1664J1456D01*
G03X125592Y1465329I-150J132D01*
G01Y1465951D01*
G02X125795Y1466154I203J0D01*
G37*
G36*
G01X143118D02*
X145938D01*
G02X146140Y1465951I-1J-203D01*
G01Y1465331D01*
G03X146190Y1465199I200J0D01*
G02Y1462283I-1661J-1458D01*
G03X146140Y1462151I150J-132D01*
G01Y1460212D01*
G03X146190Y1460080I200J0D01*
G02Y1457164I-1661J-1458D01*
G03X146140Y1457032I150J-132D01*
G01Y1456413D01*
G02X145938Y1456210I-202J-1D01*
G01X143118D01*
G02X142916Y1456413I1J203D01*
G01Y1457032D01*
G03X142866Y1457164I-200J0D01*
G02Y1460080I1661J1458D01*
G03X142916Y1460212I-150J132D01*
G01Y1462151D01*
G03X142866Y1462283I-200J0D01*
G02Y1465199I1661J1458D01*
G03X142916Y1465331I-150J132D01*
G01Y1465951D01*
G02X143118Y1466154I202J1D01*
G37*
G36*
G01X160440D02*
X163260D01*
G02X163462Y1465951I-1J-203D01*
G01Y1465331D01*
G03X163512Y1465199I200J0D01*
G02Y1462283I-1661J-1458D01*
G03X163462Y1462151I150J-132D01*
G01Y1460212D01*
G03X163512Y1460080I200J0D01*
G02Y1457164I-1661J-1458D01*
G03X163462Y1457032I150J-132D01*
G01Y1456413D01*
G02X163260Y1456210I-202J-1D01*
G01X160440D01*
G02X160238Y1456413I1J203D01*
G01Y1457032D01*
G03X160188Y1457164I-200J0D01*
G02Y1460080I1661J1458D01*
G03X160238Y1460212I-150J132D01*
G01Y1462151D01*
G03X160188Y1462283I-200J0D01*
G02Y1465199I1661J1458D01*
G03X160238Y1465331I-150J132D01*
G01Y1465951D01*
G02X160440Y1466154I202J1D01*
G37*
G36*
G01X177763D02*
X180583D01*
G02X180786Y1465951I0J-203D01*
G01Y1465329D01*
G03X180836Y1465197I200J0D01*
G02Y1462285I-1664J-1456D01*
G03X180786Y1462153I150J-132D01*
G01Y1460210D01*
G03X180836Y1460078I200J0D01*
G02Y1457166I-1664J-1456D01*
G03X180786Y1457034I150J-132D01*
G01Y1456413D01*
G02X180583Y1456210I-203J0D01*
G01X177763D01*
G02X177560Y1456413I0J203D01*
G01Y1457034D01*
G03X177510Y1457166I-200J0D01*
G02Y1460078I1664J1456D01*
G03X177560Y1460210I-150J132D01*
G01Y1462153D01*
G03X177510Y1462285I-200J0D01*
G02Y1465197I1664J1456D01*
G03X177560Y1465329I-150J132D01*
G01Y1465951D01*
G02X177763Y1466154I203J0D01*
G37*
G36*
G01X281700D02*
X284520D01*
G02X284722Y1465951I-1J-203D01*
G01Y1465331D01*
G03X284772Y1465199I200J0D01*
G02Y1462283I-1661J-1458D01*
G03X284722Y1462151I150J-132D01*
G01Y1460212D01*
G03X284772Y1460080I200J0D01*
G02Y1457164I-1661J-1458D01*
G03X284722Y1457032I150J-132D01*
G01Y1456413D01*
G02X284520Y1456210I-202J-1D01*
G01X281700D01*
G02X281498Y1456413I1J203D01*
G01Y1457032D01*
G03X281448Y1457164I-200J0D01*
G02Y1460080I1661J1458D01*
G03X281498Y1460212I-150J132D01*
G01Y1462151D01*
G03X281448Y1462283I-200J0D01*
G02Y1465199I1661J1458D01*
G03X281498Y1465331I-150J132D01*
G01Y1465951D01*
G02X281700Y1466154I202J1D01*
G37*
G36*
G01X299023D02*
X301843D01*
G02X302046Y1465951I0J-203D01*
G01Y1465329D01*
G03X302096Y1465197I200J0D01*
G02Y1462285I-1664J-1456D01*
G03X302046Y1462153I150J-132D01*
G01Y1460210D01*
G03X302096Y1460078I200J0D01*
G02Y1457166I-1664J-1456D01*
G03X302046Y1457034I150J-132D01*
G01Y1456413D01*
G02X301843Y1456210I-203J0D01*
G01X299023D01*
G02X298820Y1456413I0J203D01*
G01Y1457034D01*
G03X298770Y1457166I-200J0D01*
G02Y1460078I1664J1456D01*
G03X298820Y1460210I-150J132D01*
G01Y1462153D01*
G03X298770Y1462285I-200J0D01*
G02Y1465197I1664J1456D01*
G03X298820Y1465329I-150J132D01*
G01Y1465951D01*
G02X299023Y1466154I203J0D01*
G37*
G36*
G01X454929D02*
X457749D01*
G02X457952Y1465951I0J-203D01*
G01Y1465329D01*
G03X458002Y1465197I200J0D01*
G02Y1462285I-1664J-1456D01*
G03X457952Y1462153I150J-132D01*
G01Y1460210D01*
G03X458002Y1460078I200J0D01*
G02Y1457166I-1664J-1456D01*
G03X457952Y1457034I150J-132D01*
G01Y1456413D01*
G02X457749Y1456210I-203J0D01*
G01X454929D01*
G02X454726Y1456413I0J203D01*
G01Y1457034D01*
G03X454676Y1457166I-200J0D01*
G02Y1460078I1664J1456D01*
G03X454726Y1460210I-150J132D01*
G01Y1462153D01*
G03X454676Y1462285I-200J0D01*
G02Y1465197I1664J1456D01*
G03X454726Y1465329I-150J132D01*
G01Y1465951D01*
G02X454929Y1466154I203J0D01*
G37*
G36*
G01X472252D02*
X475072D01*
G02X475274Y1465951I-1J-203D01*
G01Y1465331D01*
G03X475324Y1465199I200J0D01*
G02Y1462283I-1661J-1458D01*
G03X475274Y1462151I150J-132D01*
G01Y1460212D01*
G03X475324Y1460080I200J0D01*
G02Y1457164I-1661J-1458D01*
G03X475274Y1457032I150J-132D01*
G01Y1456413D01*
G02X475072Y1456210I-202J-1D01*
G01X472252D01*
G02X472050Y1456413I1J203D01*
G01Y1457032D01*
G03X472000Y1457164I-200J0D01*
G02Y1460080I1661J1458D01*
G03X472050Y1460212I-150J132D01*
G01Y1462151D01*
G03X472000Y1462283I-200J0D01*
G02Y1465199I1661J1458D01*
G03X472050Y1465331I-150J132D01*
G01Y1465951D01*
G02X472252Y1466154I202J1D01*
G37*
G36*
G01X489575D02*
X492395D01*
G02X492598Y1465951I0J-203D01*
G01Y1465329D01*
G03X492648Y1465197I200J0D01*
G02Y1462285I-1664J-1456D01*
G03X492598Y1462153I150J-132D01*
G01Y1460210D01*
G03X492648Y1460078I200J0D01*
G02Y1457166I-1664J-1456D01*
G03X492598Y1457034I150J-132D01*
G01Y1456413D01*
G02X492395Y1456210I-203J0D01*
G01X489575D01*
G02X489372Y1456413I0J203D01*
G01Y1457034D01*
G03X489322Y1457166I-200J0D01*
G02Y1460078I1664J1456D01*
G03X489372Y1460210I-150J132D01*
G01Y1462153D01*
G03X489322Y1462285I-200J0D01*
G02Y1465197I1664J1456D01*
G03X489372Y1465329I-150J132D01*
G01Y1465951D01*
G02X489575Y1466154I203J0D01*
G37*
G36*
G01X506897D02*
X509717D01*
G02X509920Y1465951I0J-203D01*
G01Y1465329D01*
G03X509970Y1465197I200J0D01*
G02Y1462285I-1664J-1456D01*
G03X509920Y1462153I150J-132D01*
G01Y1460210D01*
G03X509970Y1460078I200J0D01*
G02Y1457166I-1664J-1456D01*
G03X509920Y1457034I150J-132D01*
G01Y1456413D01*
G02X509717Y1456210I-203J0D01*
G01X506897D01*
G02X506694Y1456413I0J203D01*
G01Y1457034D01*
G03X506644Y1457166I-200J0D01*
G02Y1460078I1664J1456D01*
G03X506694Y1460210I-150J132D01*
G01Y1462153D01*
G03X506644Y1462285I-200J0D01*
G02Y1465197I1664J1456D01*
G03X506694Y1465329I-150J132D01*
G01Y1465951D01*
G02X506897Y1466154I203J0D01*
G37*
G36*
G01X645480D02*
X648300D01*
G02X648502Y1465951I-1J-203D01*
G01Y1465331D01*
G03X648552Y1465199I200J0D01*
G02Y1462283I-1661J-1458D01*
G03X648502Y1462151I150J-132D01*
G01Y1460212D01*
G03X648552Y1460080I200J0D01*
G02Y1457164I-1661J-1458D01*
G03X648502Y1457032I150J-132D01*
G01Y1456413D01*
G02X648300Y1456210I-202J-1D01*
G01X645480D01*
G02X645278Y1456413I1J203D01*
G01Y1457032D01*
G03X645228Y1457164I-200J0D01*
G02Y1460080I1661J1458D01*
G03X645278Y1460212I-150J132D01*
G01Y1462151D01*
G03X645228Y1462283I-200J0D01*
G02Y1465199I1661J1458D01*
G03X645278Y1465331I-150J132D01*
G01Y1465951D01*
G02X645480Y1466154I202J1D01*
G37*
G36*
G01X662803D02*
X665623D01*
G02X665826Y1465951I0J-203D01*
G01Y1465329D01*
G03X665876Y1465197I200J0D01*
G02Y1462285I-1664J-1456D01*
G03X665826Y1462153I150J-132D01*
G01Y1460210D01*
G03X665876Y1460078I200J0D01*
G02Y1457166I-1664J-1456D01*
G03X665826Y1457034I150J-132D01*
G01Y1456413D01*
G02X665623Y1456210I-203J0D01*
G01X662803D01*
G02X662600Y1456413I0J203D01*
G01Y1457034D01*
G03X662550Y1457166I-200J0D01*
G02Y1460078I1664J1456D01*
G03X662600Y1460210I-150J132D01*
G01Y1462153D01*
G03X662550Y1462285I-200J0D01*
G02Y1465197I1664J1456D01*
G03X662600Y1465329I-150J132D01*
G01Y1465951D01*
G02X662803Y1466154I203J0D01*
G37*
G36*
G01X680125D02*
X682945D01*
G02X683148Y1465951I0J-203D01*
G01Y1465329D01*
G03X683198Y1465197I200J0D01*
G02Y1462285I-1664J-1456D01*
G03X683148Y1462153I150J-132D01*
G01Y1460210D01*
G03X683198Y1460078I200J0D01*
G02Y1457166I-1664J-1456D01*
G03X683148Y1457034I150J-132D01*
G01Y1456413D01*
G02X682945Y1456210I-203J0D01*
G01X680125D01*
G02X679922Y1456413I0J203D01*
G01Y1457034D01*
G03X679872Y1457166I-200J0D01*
G02Y1460078I1664J1456D01*
G03X679922Y1460210I-150J132D01*
G01Y1462153D01*
G03X679872Y1462285I-200J0D01*
G02Y1465197I1664J1456D01*
G03X679922Y1465329I-150J132D01*
G01Y1465951D01*
G02X680125Y1466154I203J0D01*
G37*
G36*
G01X1165086D02*
X1167906D01*
G02X1168108Y1465951I-1J-203D01*
G01Y1465331D01*
G03X1168158Y1465199I200J0D01*
G02Y1462283I-1661J-1458D01*
G03X1168108Y1462151I150J-132D01*
G01Y1460212D01*
G03X1168158Y1460080I200J0D01*
G02Y1457164I-1661J-1458D01*
G03X1168108Y1457032I150J-132D01*
G01Y1456413D01*
G02X1167906Y1456210I-202J-1D01*
G01X1165086D01*
G02X1164884Y1456413I1J203D01*
G01Y1457032D01*
G03X1164834Y1457164I-200J0D01*
G02Y1460080I1661J1458D01*
G03X1164884Y1460212I-150J132D01*
G01Y1462151D01*
G03X1164834Y1462283I-200J0D01*
G02Y1465199I1661J1458D01*
G03X1164884Y1465331I-150J132D01*
G01Y1465951D01*
G02X1165086Y1466154I202J1D01*
G37*
G36*
G01X1182408D02*
X1185228D01*
G02X1185430Y1465951I-1J-203D01*
G01Y1465331D01*
G03X1185480Y1465199I200J0D01*
G02Y1462283I-1661J-1458D01*
G03X1185430Y1462151I150J-132D01*
G01Y1460212D01*
G03X1185480Y1460080I200J0D01*
G02Y1457164I-1661J-1458D01*
G03X1185430Y1457032I150J-132D01*
G01Y1456413D01*
G02X1185228Y1456210I-202J-1D01*
G01X1182408D01*
G02X1182206Y1456413I1J203D01*
G01Y1457032D01*
G03X1182156Y1457164I-200J0D01*
G02Y1460080I1661J1458D01*
G03X1182206Y1460212I-150J132D01*
G01Y1462151D01*
G03X1182156Y1462283I-200J0D01*
G02Y1465199I1661J1458D01*
G03X1182206Y1465331I-150J132D01*
G01Y1465951D01*
G02X1182408Y1466154I202J1D01*
G37*
G36*
G01X1303669D02*
X1306489D01*
G02X1306692Y1465951I0J-203D01*
G01Y1465329D01*
G03X1306742Y1465197I200J0D01*
G02Y1462285I-1664J-1456D01*
G03X1306692Y1462153I150J-132D01*
G01Y1460210D01*
G03X1306742Y1460078I200J0D01*
G02Y1457166I-1664J-1456D01*
G03X1306692Y1457034I150J-132D01*
G01Y1456413D01*
G02X1306489Y1456210I-203J0D01*
G01X1303669D01*
G02X1303466Y1456413I0J203D01*
G01Y1457034D01*
G03X1303416Y1457166I-200J0D01*
G02Y1460078I1664J1456D01*
G03X1303466Y1460210I-150J132D01*
G01Y1462153D01*
G03X1303416Y1462285I-200J0D01*
G02Y1465197I1664J1456D01*
G03X1303466Y1465329I-150J132D01*
G01Y1465951D01*
G02X1303669Y1466154I203J0D01*
G37*
G36*
G01X1320992D02*
X1323812D01*
G02X1324014Y1465951I-1J-203D01*
G01Y1465331D01*
G03X1324064Y1465199I200J0D01*
G02Y1462283I-1661J-1458D01*
G03X1324014Y1462151I150J-132D01*
G01Y1460212D01*
G03X1324064Y1460080I200J0D01*
G02Y1457164I-1661J-1458D01*
G03X1324014Y1457032I150J-132D01*
G01Y1456413D01*
G02X1323812Y1456210I-202J-1D01*
G01X1320992D01*
G02X1320790Y1456413I1J203D01*
G01Y1457032D01*
G03X1320740Y1457164I-200J0D01*
G02Y1460080I1661J1458D01*
G03X1320790Y1460212I-150J132D01*
G01Y1462151D01*
G03X1320740Y1462283I-200J0D01*
G02Y1465199I1661J1458D01*
G03X1320790Y1465331I-150J132D01*
G01Y1465951D01*
G02X1320992Y1466154I202J1D01*
G37*
G36*
G01X1338315D02*
X1341135D01*
G02X1341338Y1465951I0J-203D01*
G01Y1465329D01*
G03X1341388Y1465197I200J0D01*
G02Y1462285I-1664J-1456D01*
G03X1341338Y1462153I150J-132D01*
G01Y1460210D01*
G03X1341388Y1460078I200J0D01*
G02Y1457166I-1664J-1456D01*
G03X1341338Y1457034I150J-132D01*
G01Y1456413D01*
G02X1341135Y1456210I-203J0D01*
G01X1338315D01*
G02X1338112Y1456413I0J203D01*
G01Y1457034D01*
G03X1338062Y1457166I-200J0D01*
G02Y1460078I1664J1456D01*
G03X1338112Y1460210I-150J132D01*
G01Y1462153D01*
G03X1338062Y1462285I-200J0D01*
G02Y1465197I1664J1456D01*
G03X1338112Y1465329I-150J132D01*
G01Y1465951D01*
G02X1338315Y1466154I203J0D01*
G37*
G36*
G01X1355637D02*
X1358457D01*
G02X1358660Y1465951I0J-203D01*
G01Y1465329D01*
G03X1358710Y1465197I200J0D01*
G02Y1462285I-1664J-1456D01*
G03X1358660Y1462153I150J-132D01*
G01Y1460210D01*
G03X1358710Y1460078I200J0D01*
G02Y1457166I-1664J-1456D01*
G03X1358660Y1457034I150J-132D01*
G01Y1456413D01*
G02X1358457Y1456210I-203J0D01*
G01X1355637D01*
G02X1355434Y1456413I0J203D01*
G01Y1457034D01*
G03X1355384Y1457166I-200J0D01*
G02Y1460078I1664J1456D01*
G03X1355434Y1460210I-150J132D01*
G01Y1462153D01*
G03X1355384Y1462285I-200J0D01*
G02Y1465197I1664J1456D01*
G03X1355434Y1465329I-150J132D01*
G01Y1465951D01*
G02X1355637Y1466154I203J0D01*
G37*
G36*
G01X1476897D02*
X1479717D01*
G02X1479920Y1465951I0J-203D01*
G01Y1465329D01*
G03X1479970Y1465197I200J0D01*
G02Y1462285I-1664J-1456D01*
G03X1479920Y1462153I150J-132D01*
G01Y1460210D01*
G03X1479970Y1460078I200J0D01*
G02Y1457166I-1664J-1456D01*
G03X1479920Y1457034I150J-132D01*
G01Y1456413D01*
G02X1479717Y1456210I-203J0D01*
G01X1476897D01*
G02X1476694Y1456413I0J203D01*
G01Y1457034D01*
G03X1476644Y1457166I-200J0D01*
G02Y1460078I1664J1456D01*
G03X1476694Y1460210I-150J132D01*
G01Y1462153D01*
G03X1476644Y1462285I-200J0D01*
G02Y1465197I1664J1456D01*
G03X1476694Y1465329I-150J132D01*
G01Y1465951D01*
G02X1476897Y1466154I203J0D01*
G37*
G36*
G01X1494220D02*
X1497040D01*
G02X1497242Y1465951I-1J-203D01*
G01Y1465331D01*
G03X1497292Y1465199I200J0D01*
G02Y1462283I-1661J-1458D01*
G03X1497242Y1462151I150J-132D01*
G01Y1460212D01*
G03X1497292Y1460080I200J0D01*
G02Y1457164I-1661J-1458D01*
G03X1497242Y1457032I150J-132D01*
G01Y1456413D01*
G02X1497040Y1456210I-202J-1D01*
G01X1494220D01*
G02X1494018Y1456413I1J203D01*
G01Y1457032D01*
G03X1493968Y1457164I-200J0D01*
G02Y1460080I1661J1458D01*
G03X1494018Y1460212I-150J132D01*
G01Y1462151D01*
G03X1493968Y1462283I-200J0D01*
G02Y1465199I1661J1458D01*
G03X1494018Y1465331I-150J132D01*
G01Y1465951D01*
G02X1494220Y1466154I202J1D01*
G37*
G36*
G01X1511543D02*
X1514363D01*
G02X1514566Y1465951I0J-203D01*
G01Y1465329D01*
G03X1514616Y1465197I200J0D01*
G02Y1462285I-1664J-1456D01*
G03X1514566Y1462153I150J-132D01*
G01Y1460210D01*
G03X1514616Y1460078I200J0D01*
G02Y1457166I-1664J-1456D01*
G03X1514566Y1457034I150J-132D01*
G01Y1456413D01*
G02X1514363Y1456210I-203J0D01*
G01X1511543D01*
G02X1511340Y1456413I0J203D01*
G01Y1457034D01*
G03X1511290Y1457166I-200J0D01*
G02Y1460078I1664J1456D01*
G03X1511340Y1460210I-150J132D01*
G01Y1462153D01*
G03X1511290Y1462285I-200J0D01*
G02Y1465197I1664J1456D01*
G03X1511340Y1465329I-150J132D01*
G01Y1465951D01*
G02X1511543Y1466154I203J0D01*
G37*
G36*
G01X1528865D02*
X1531685D01*
G02X1531888Y1465951I0J-203D01*
G01Y1465329D01*
G03X1531938Y1465197I200J0D01*
G02Y1462285I-1664J-1456D01*
G03X1531888Y1462153I150J-132D01*
G01Y1460210D01*
G03X1531938Y1460078I200J0D01*
G02Y1457166I-1664J-1456D01*
G03X1531888Y1457034I150J-132D01*
G01Y1456413D01*
G02X1531685Y1456210I-203J0D01*
G01X1528865D01*
G02X1528662Y1456413I0J203D01*
G01Y1457034D01*
G03X1528612Y1457166I-200J0D01*
G02Y1460078I1664J1456D01*
G03X1528662Y1460210I-150J132D01*
G01Y1462153D01*
G03X1528612Y1462285I-200J0D01*
G02Y1465197I1664J1456D01*
G03X1528662Y1465329I-150J132D01*
G01Y1465951D01*
G02X1528865Y1466154I203J0D01*
G37*
G36*
G01X1684771D02*
X1687591D01*
G02X1687794Y1465951I0J-203D01*
G01Y1465329D01*
G03X1687844Y1465197I200J0D01*
G02Y1462285I-1664J-1456D01*
G03X1687794Y1462153I150J-132D01*
G01Y1460210D01*
G03X1687844Y1460078I200J0D01*
G02Y1457166I-1664J-1456D01*
G03X1687794Y1457034I150J-132D01*
G01Y1456413D01*
G02X1687591Y1456210I-203J0D01*
G01X1684771D01*
G02X1684568Y1456413I0J203D01*
G01Y1457034D01*
G03X1684518Y1457166I-200J0D01*
G02Y1460078I1664J1456D01*
G03X1684568Y1460210I-150J132D01*
G01Y1462153D01*
G03X1684518Y1462285I-200J0D01*
G02Y1465197I1664J1456D01*
G03X1684568Y1465329I-150J132D01*
G01Y1465951D01*
G02X1684771Y1466154I203J0D01*
G37*
G36*
G01X1702093D02*
X1704913D01*
G02X1705116Y1465951I0J-203D01*
G01Y1465329D01*
G03X1705166Y1465197I200J0D01*
G02Y1462285I-1664J-1456D01*
G03X1705116Y1462153I150J-132D01*
G01Y1460210D01*
G03X1705166Y1460078I200J0D01*
G02Y1457166I-1664J-1456D01*
G03X1705116Y1457034I150J-132D01*
G01Y1456413D01*
G02X1704913Y1456210I-203J0D01*
G01X1702093D01*
G02X1701890Y1456413I0J203D01*
G01Y1457034D01*
G03X1701840Y1457166I-200J0D01*
G02Y1460078I1664J1456D01*
G03X1701890Y1460210I-150J132D01*
G01Y1462153D01*
G03X1701840Y1462285I-200J0D01*
G02Y1465197I1664J1456D01*
G03X1701890Y1465329I-150J132D01*
G01Y1465951D01*
G02X1702093Y1466154I203J0D01*
G37*
G36*
G01X134456Y1470484D02*
X137276D01*
G02X137478Y1470281I-1J-203D01*
G01Y1469661D01*
G03X137528Y1469529I200J0D01*
G02Y1466613I-1661J-1458D01*
G03X137478Y1466481I150J-132D01*
G01Y1464543D01*
G03X137528Y1464411I200J0D01*
G02Y1461495I-1661J-1458D01*
G03X137478Y1461363I150J-132D01*
G01Y1460743D01*
G02X137276Y1460540I-202J-1D01*
G01X134456D01*
G02X134254Y1460743I1J203D01*
G01Y1461363D01*
G03X134204Y1461495I-200J0D01*
G02Y1464411I1661J1458D01*
G03X134254Y1464543I-150J132D01*
G01Y1466481D01*
G03X134204Y1466613I-200J0D01*
G02Y1469529I1661J1458D01*
G03X134254Y1469661I-150J132D01*
G01Y1470281D01*
G02X134456Y1470484I202J1D01*
G37*
G36*
G01X151779D02*
X154599D01*
G02X154802Y1470281I0J-203D01*
G01Y1469659D01*
G03X154852Y1469527I200J0D01*
G02Y1466615I-1664J-1456D01*
G03X154802Y1466483I150J-132D01*
G01Y1464541D01*
G03X154852Y1464409I200J0D01*
G02Y1461497I-1664J-1456D01*
G03X154802Y1461365I150J-132D01*
G01Y1460743D01*
G02X154599Y1460540I-203J0D01*
G01X151779D01*
G02X151576Y1460743I0J203D01*
G01Y1461365D01*
G03X151526Y1461497I-200J0D01*
G02Y1464409I1664J1456D01*
G03X151576Y1464541I-150J132D01*
G01Y1466483D01*
G03X151526Y1466615I-200J0D01*
G02Y1469527I1664J1456D01*
G03X151576Y1469659I-150J132D01*
G01Y1470281D01*
G02X151779Y1470484I203J0D01*
G37*
G36*
G01X169102D02*
X171922D01*
G02X172124Y1470281I-1J-203D01*
G01Y1469661D01*
G03X172174Y1469529I200J0D01*
G02Y1466613I-1661J-1458D01*
G03X172124Y1466481I150J-132D01*
G01Y1464543D01*
G03X172174Y1464411I200J0D01*
G02Y1461495I-1661J-1458D01*
G03X172124Y1461363I150J-132D01*
G01Y1460743D01*
G02X171922Y1460540I-202J-1D01*
G01X169102D01*
G02X168900Y1460743I1J203D01*
G01Y1461363D01*
G03X168850Y1461495I-200J0D01*
G02Y1464411I1661J1458D01*
G03X168900Y1464543I-150J132D01*
G01Y1466481D01*
G03X168850Y1466613I-200J0D01*
G02Y1469529I1661J1458D01*
G03X168900Y1469661I-150J132D01*
G01Y1470281D01*
G02X169102Y1470484I202J1D01*
G37*
G36*
G01X186425D02*
X189245D01*
G02X189448Y1470281I0J-203D01*
G01Y1469659D01*
G03X189498Y1469527I200J0D01*
G02Y1466615I-1664J-1456D01*
G03X189448Y1466483I150J-132D01*
G01Y1464541D01*
G03X189498Y1464409I200J0D01*
G02Y1461497I-1664J-1456D01*
G03X189448Y1461365I150J-132D01*
G01Y1460743D01*
G02X189245Y1460540I-203J0D01*
G01X186425D01*
G02X186222Y1460743I0J203D01*
G01Y1461365D01*
G03X186172Y1461497I-200J0D01*
G02Y1464409I1664J1456D01*
G03X186222Y1464541I-150J132D01*
G01Y1466483D01*
G03X186172Y1466615I-200J0D01*
G02Y1469527I1664J1456D01*
G03X186222Y1469659I-150J132D01*
G01Y1470281D01*
G02X186425Y1470484I203J0D01*
G37*
G36*
G01X290361D02*
X293181D01*
G02X293384Y1470281I0J-203D01*
G01Y1469659D01*
G03X293434Y1469527I200J0D01*
G02Y1466615I-1664J-1456D01*
G03X293384Y1466483I150J-132D01*
G01Y1464541D01*
G03X293434Y1464409I200J0D01*
G02Y1461497I-1664J-1456D01*
G03X293384Y1461365I150J-132D01*
G01Y1460743D01*
G02X293181Y1460540I-203J0D01*
G01X290361D01*
G02X290158Y1460743I0J203D01*
G01Y1461365D01*
G03X290108Y1461497I-200J0D01*
G02Y1464409I1664J1456D01*
G03X290158Y1464541I-150J132D01*
G01Y1466483D01*
G03X290108Y1466615I-200J0D01*
G02Y1469527I1664J1456D01*
G03X290158Y1469659I-150J132D01*
G01Y1470281D01*
G02X290361Y1470484I203J0D01*
G37*
G36*
G01X463590D02*
X466410D01*
G02X466612Y1470281I-1J-203D01*
G01Y1469661D01*
G03X466662Y1469529I200J0D01*
G02Y1466613I-1661J-1458D01*
G03X466612Y1466481I150J-132D01*
G01Y1464543D01*
G03X466662Y1464411I200J0D01*
G02Y1461495I-1661J-1458D01*
G03X466612Y1461363I150J-132D01*
G01Y1460743D01*
G02X466410Y1460540I-202J-1D01*
G01X463590D01*
G02X463388Y1460743I1J203D01*
G01Y1461363D01*
G03X463338Y1461495I-200J0D01*
G02Y1464411I1661J1458D01*
G03X463388Y1464543I-150J132D01*
G01Y1466481D01*
G03X463338Y1466613I-200J0D01*
G02Y1469529I1661J1458D01*
G03X463388Y1469661I-150J132D01*
G01Y1470281D01*
G02X463590Y1470484I202J1D01*
G37*
G36*
G01X480913D02*
X483733D01*
G02X483936Y1470281I0J-203D01*
G01Y1469659D01*
G03X483986Y1469527I200J0D01*
G02Y1466615I-1664J-1456D01*
G03X483936Y1466483I150J-132D01*
G01Y1464541D01*
G03X483986Y1464409I200J0D01*
G02Y1461497I-1664J-1456D01*
G03X483936Y1461365I150J-132D01*
G01Y1460743D01*
G02X483733Y1460540I-203J0D01*
G01X480913D01*
G02X480710Y1460743I0J203D01*
G01Y1461365D01*
G03X480660Y1461497I-200J0D01*
G02Y1464409I1664J1456D01*
G03X480710Y1464541I-150J132D01*
G01Y1466483D01*
G03X480660Y1466615I-200J0D01*
G02Y1469527I1664J1456D01*
G03X480710Y1469659I-150J132D01*
G01Y1470281D01*
G02X480913Y1470484I203J0D01*
G37*
G36*
G01X498236D02*
X501056D01*
G02X501258Y1470281I-1J-203D01*
G01Y1469661D01*
G03X501308Y1469529I200J0D01*
G02Y1466613I-1661J-1458D01*
G03X501258Y1466481I150J-132D01*
G01Y1464543D01*
G03X501308Y1464411I200J0D01*
G02Y1461495I-1661J-1458D01*
G03X501258Y1461363I150J-132D01*
G01Y1460743D01*
G02X501056Y1460540I-202J-1D01*
G01X498236D01*
G02X498034Y1460743I1J203D01*
G01Y1461363D01*
G03X497984Y1461495I-200J0D01*
G02Y1464411I1661J1458D01*
G03X498034Y1464543I-150J132D01*
G01Y1466481D01*
G03X497984Y1466613I-200J0D01*
G02Y1469529I1661J1458D01*
G03X498034Y1469661I-150J132D01*
G01Y1470281D01*
G02X498236Y1470484I202J1D01*
G37*
G36*
G01X515559D02*
X518379D01*
G02X518582Y1470281I0J-203D01*
G01Y1469659D01*
G03X518632Y1469527I200J0D01*
G02Y1466615I-1664J-1456D01*
G03X518582Y1466483I150J-132D01*
G01Y1464541D01*
G03X518632Y1464409I200J0D01*
G02Y1461497I-1664J-1456D01*
G03X518582Y1461365I150J-132D01*
G01Y1460743D01*
G02X518379Y1460540I-203J0D01*
G01X515559D01*
G02X515356Y1460743I0J203D01*
G01Y1461365D01*
G03X515306Y1461497I-200J0D01*
G02Y1464409I1664J1456D01*
G03X515356Y1464541I-150J132D01*
G01Y1466483D01*
G03X515306Y1466615I-200J0D01*
G02Y1469527I1664J1456D01*
G03X515356Y1469659I-150J132D01*
G01Y1470281D01*
G02X515559Y1470484I203J0D01*
G37*
G36*
G01X654141D02*
X656961D01*
G02X657164Y1470281I0J-203D01*
G01Y1469659D01*
G03X657214Y1469527I200J0D01*
G02Y1466615I-1664J-1456D01*
G03X657164Y1466483I150J-132D01*
G01Y1464541D01*
G03X657214Y1464409I200J0D01*
G02Y1461497I-1664J-1456D01*
G03X657164Y1461365I150J-132D01*
G01Y1460743D01*
G02X656961Y1460540I-203J0D01*
G01X654141D01*
G02X653938Y1460743I0J203D01*
G01Y1461365D01*
G03X653888Y1461497I-200J0D01*
G02Y1464409I1664J1456D01*
G03X653938Y1464541I-150J132D01*
G01Y1466483D01*
G03X653888Y1466615I-200J0D01*
G02Y1469527I1664J1456D01*
G03X653938Y1469659I-150J132D01*
G01Y1470281D01*
G02X654141Y1470484I203J0D01*
G37*
G36*
G01X671464D02*
X674284D01*
G02X674486Y1470281I-1J-203D01*
G01Y1469661D01*
G03X674536Y1469529I200J0D01*
G02Y1466613I-1661J-1458D01*
G03X674486Y1466481I150J-132D01*
G01Y1464543D01*
G03X674536Y1464411I200J0D01*
G02Y1461495I-1661J-1458D01*
G03X674486Y1461363I150J-132D01*
G01Y1460743D01*
G02X674284Y1460540I-202J-1D01*
G01X671464D01*
G02X671262Y1460743I1J203D01*
G01Y1461363D01*
G03X671212Y1461495I-200J0D01*
G02Y1464411I1661J1458D01*
G03X671262Y1464543I-150J132D01*
G01Y1466481D01*
G03X671212Y1466613I-200J0D01*
G02Y1469529I1661J1458D01*
G03X671262Y1469661I-150J132D01*
G01Y1470281D01*
G02X671464Y1470484I202J1D01*
G37*
G36*
G01X688787D02*
X691607D01*
G02X691810Y1470281I0J-203D01*
G01Y1469659D01*
G03X691860Y1469527I200J0D01*
G02Y1466615I-1664J-1456D01*
G03X691810Y1466483I150J-132D01*
G01Y1464541D01*
G03X691860Y1464409I200J0D01*
G02Y1461497I-1664J-1456D01*
G03X691810Y1461365I150J-132D01*
G01Y1460743D01*
G02X691607Y1460540I-203J0D01*
G01X688787D01*
G02X688584Y1460743I0J203D01*
G01Y1461365D01*
G03X688534Y1461497I-200J0D01*
G02Y1464409I1664J1456D01*
G03X688584Y1464541I-150J132D01*
G01Y1466483D01*
G03X688534Y1466615I-200J0D01*
G02Y1469527I1664J1456D01*
G03X688584Y1469659I-150J132D01*
G01Y1470281D01*
G02X688787Y1470484I203J0D01*
G37*
G36*
G01X1173747D02*
X1176567D01*
G02X1176770Y1470281I0J-203D01*
G01Y1469659D01*
G03X1176820Y1469527I200J0D01*
G02Y1466615I-1664J-1456D01*
G03X1176770Y1466483I150J-132D01*
G01Y1464541D01*
G03X1176820Y1464409I200J0D01*
G02Y1461497I-1664J-1456D01*
G03X1176770Y1461365I150J-132D01*
G01Y1460743D01*
G02X1176567Y1460540I-203J0D01*
G01X1173747D01*
G02X1173544Y1460743I0J203D01*
G01Y1461365D01*
G03X1173494Y1461497I-200J0D01*
G02Y1464409I1664J1456D01*
G03X1173544Y1464541I-150J132D01*
G01Y1466483D01*
G03X1173494Y1466615I-200J0D01*
G02Y1469527I1664J1456D01*
G03X1173544Y1469659I-150J132D01*
G01Y1470281D01*
G02X1173747Y1470484I203J0D01*
G37*
G36*
G01X1191070D02*
X1193890D01*
G02X1194092Y1470281I-1J-203D01*
G01Y1469661D01*
G03X1194142Y1469529I200J0D01*
G02Y1466613I-1661J-1458D01*
G03X1194092Y1466481I150J-132D01*
G01Y1464543D01*
G03X1194142Y1464411I200J0D01*
G02Y1461495I-1661J-1458D01*
G03X1194092Y1461363I150J-132D01*
G01Y1460743D01*
G02X1193890Y1460540I-202J-1D01*
G01X1191070D01*
G02X1190868Y1460743I1J203D01*
G01Y1461363D01*
G03X1190818Y1461495I-200J0D01*
G02Y1464411I1661J1458D01*
G03X1190868Y1464543I-150J132D01*
G01Y1466481D01*
G03X1190818Y1466613I-200J0D01*
G02Y1469529I1661J1458D01*
G03X1190868Y1469661I-150J132D01*
G01Y1470281D01*
G02X1191070Y1470484I202J1D01*
G37*
G36*
G01X1312330D02*
X1315150D01*
G02X1315352Y1470281I-1J-203D01*
G01Y1469661D01*
G03X1315402Y1469529I200J0D01*
G02Y1466613I-1661J-1458D01*
G03X1315352Y1466481I150J-132D01*
G01Y1464543D01*
G03X1315402Y1464411I200J0D01*
G02Y1461495I-1661J-1458D01*
G03X1315352Y1461363I150J-132D01*
G01Y1460743D01*
G02X1315150Y1460540I-202J-1D01*
G01X1312330D01*
G02X1312128Y1460743I1J203D01*
G01Y1461363D01*
G03X1312078Y1461495I-200J0D01*
G02Y1464411I1661J1458D01*
G03X1312128Y1464543I-150J132D01*
G01Y1466481D01*
G03X1312078Y1466613I-200J0D01*
G02Y1469529I1661J1458D01*
G03X1312128Y1469661I-150J132D01*
G01Y1470281D01*
G02X1312330Y1470484I202J1D01*
G37*
G36*
G01X1329653D02*
X1332473D01*
G02X1332676Y1470281I0J-203D01*
G01Y1469659D01*
G03X1332726Y1469527I200J0D01*
G02Y1466615I-1664J-1456D01*
G03X1332676Y1466483I150J-132D01*
G01Y1464541D01*
G03X1332726Y1464409I200J0D01*
G02Y1461497I-1664J-1456D01*
G03X1332676Y1461365I150J-132D01*
G01Y1460743D01*
G02X1332473Y1460540I-203J0D01*
G01X1329653D01*
G02X1329450Y1460743I0J203D01*
G01Y1461365D01*
G03X1329400Y1461497I-200J0D01*
G02Y1464409I1664J1456D01*
G03X1329450Y1464541I-150J132D01*
G01Y1466483D01*
G03X1329400Y1466615I-200J0D01*
G02Y1469527I1664J1456D01*
G03X1329450Y1469659I-150J132D01*
G01Y1470281D01*
G02X1329653Y1470484I203J0D01*
G37*
G36*
G01X1346976D02*
X1349796D01*
G02X1349998Y1470281I-1J-203D01*
G01Y1469661D01*
G03X1350048Y1469529I200J0D01*
G02Y1466613I-1661J-1458D01*
G03X1349998Y1466481I150J-132D01*
G01Y1464543D01*
G03X1350048Y1464411I200J0D01*
G02Y1461495I-1661J-1458D01*
G03X1349998Y1461363I150J-132D01*
G01Y1460743D01*
G02X1349796Y1460540I-202J-1D01*
G01X1346976D01*
G02X1346774Y1460743I1J203D01*
G01Y1461363D01*
G03X1346724Y1461495I-200J0D01*
G02Y1464411I1661J1458D01*
G03X1346774Y1464543I-150J132D01*
G01Y1466481D01*
G03X1346724Y1466613I-200J0D01*
G02Y1469529I1661J1458D01*
G03X1346774Y1469661I-150J132D01*
G01Y1470281D01*
G02X1346976Y1470484I202J1D01*
G37*
G36*
G01X1364299D02*
X1367119D01*
G02X1367322Y1470281I0J-203D01*
G01Y1469659D01*
G03X1367372Y1469527I200J0D01*
G02Y1466615I-1664J-1456D01*
G03X1367322Y1466483I150J-132D01*
G01Y1464541D01*
G03X1367372Y1464409I200J0D01*
G02Y1461497I-1664J-1456D01*
G03X1367322Y1461365I150J-132D01*
G01Y1460743D01*
G02X1367119Y1460540I-203J0D01*
G01X1364299D01*
G02X1364096Y1460743I0J203D01*
G01Y1461365D01*
G03X1364046Y1461497I-200J0D01*
G02Y1464409I1664J1456D01*
G03X1364096Y1464541I-150J132D01*
G01Y1466483D01*
G03X1364046Y1466615I-200J0D01*
G02Y1469527I1664J1456D01*
G03X1364096Y1469659I-150J132D01*
G01Y1470281D01*
G02X1364299Y1470484I203J0D01*
G37*
G36*
G01X1485558D02*
X1488378D01*
G02X1488580Y1470281I-1J-203D01*
G01Y1469661D01*
G03X1488630Y1469529I200J0D01*
G02Y1466613I-1661J-1458D01*
G03X1488580Y1466481I150J-132D01*
G01Y1464543D01*
G03X1488630Y1464411I200J0D01*
G02Y1461495I-1661J-1458D01*
G03X1488580Y1461363I150J-132D01*
G01Y1460743D01*
G02X1488378Y1460540I-202J-1D01*
G01X1485558D01*
G02X1485356Y1460743I1J203D01*
G01Y1461363D01*
G03X1485306Y1461495I-200J0D01*
G02Y1464411I1661J1458D01*
G03X1485356Y1464543I-150J132D01*
G01Y1466481D01*
G03X1485306Y1466613I-200J0D01*
G02Y1469529I1661J1458D01*
G03X1485356Y1469661I-150J132D01*
G01Y1470281D01*
G02X1485558Y1470484I202J1D01*
G37*
G36*
G01X1502881D02*
X1505701D01*
G02X1505904Y1470281I0J-203D01*
G01Y1469659D01*
G03X1505954Y1469527I200J0D01*
G02Y1466615I-1664J-1456D01*
G03X1505904Y1466483I150J-132D01*
G01Y1464541D01*
G03X1505954Y1464409I200J0D01*
G02Y1461497I-1664J-1456D01*
G03X1505904Y1461365I150J-132D01*
G01Y1460743D01*
G02X1505701Y1460540I-203J0D01*
G01X1502881D01*
G02X1502678Y1460743I0J203D01*
G01Y1461365D01*
G03X1502628Y1461497I-200J0D01*
G02Y1464409I1664J1456D01*
G03X1502678Y1464541I-150J132D01*
G01Y1466483D01*
G03X1502628Y1466615I-200J0D01*
G02Y1469527I1664J1456D01*
G03X1502678Y1469659I-150J132D01*
G01Y1470281D01*
G02X1502881Y1470484I203J0D01*
G37*
G36*
G01X1520204D02*
X1523024D01*
G02X1523226Y1470281I-1J-203D01*
G01Y1469661D01*
G03X1523276Y1469529I200J0D01*
G02Y1466613I-1661J-1458D01*
G03X1523226Y1466481I150J-132D01*
G01Y1464543D01*
G03X1523276Y1464411I200J0D01*
G02Y1461495I-1661J-1458D01*
G03X1523226Y1461363I150J-132D01*
G01Y1460743D01*
G02X1523024Y1460540I-202J-1D01*
G01X1520204D01*
G02X1520002Y1460743I1J203D01*
G01Y1461363D01*
G03X1519952Y1461495I-200J0D01*
G02Y1464411I1661J1458D01*
G03X1520002Y1464543I-150J132D01*
G01Y1466481D01*
G03X1519952Y1466613I-200J0D01*
G02Y1469529I1661J1458D01*
G03X1520002Y1469661I-150J132D01*
G01Y1470281D01*
G02X1520204Y1470484I202J1D01*
G37*
G36*
G01X1537527D02*
X1540347D01*
G02X1540550Y1470281I0J-203D01*
G01Y1469659D01*
G03X1540600Y1469527I200J0D01*
G02Y1466615I-1664J-1456D01*
G03X1540550Y1466483I150J-132D01*
G01Y1464541D01*
G03X1540600Y1464409I200J0D01*
G02Y1461497I-1664J-1456D01*
G03X1540550Y1461365I150J-132D01*
G01Y1460743D01*
G02X1540347Y1460540I-203J0D01*
G01X1537527D01*
G02X1537324Y1460743I0J203D01*
G01Y1461365D01*
G03X1537274Y1461497I-200J0D01*
G02Y1464409I1664J1456D01*
G03X1537324Y1464541I-150J132D01*
G01Y1466483D01*
G03X1537274Y1466615I-200J0D01*
G02Y1469527I1664J1456D01*
G03X1537324Y1469659I-150J132D01*
G01Y1470281D01*
G02X1537527Y1470484I203J0D01*
G37*
G36*
G01X1693432D02*
X1696252D01*
G02X1696454Y1470281I-1J-203D01*
G01Y1469661D01*
G03X1696504Y1469529I200J0D01*
G02Y1466613I-1661J-1458D01*
G03X1696454Y1466481I150J-132D01*
G01Y1464543D01*
G03X1696504Y1464411I200J0D01*
G02Y1461495I-1661J-1458D01*
G03X1696454Y1461363I150J-132D01*
G01Y1460743D01*
G02X1696252Y1460540I-202J-1D01*
G01X1693432D01*
G02X1693230Y1460743I1J203D01*
G01Y1461363D01*
G03X1693180Y1461495I-200J0D01*
G02Y1464411I1661J1458D01*
G03X1693230Y1464543I-150J132D01*
G01Y1466481D01*
G03X1693180Y1466613I-200J0D01*
G02Y1469529I1661J1458D01*
G03X1693230Y1469661I-150J132D01*
G01Y1470281D01*
G02X1693432Y1470484I202J1D01*
G37*
G36*
G01X1710755D02*
X1713575D01*
G02X1713778Y1470281I0J-203D01*
G01Y1469659D01*
G03X1713828Y1469527I200J0D01*
G02Y1466615I-1664J-1456D01*
G03X1713778Y1466483I150J-132D01*
G01Y1464541D01*
G03X1713828Y1464409I200J0D01*
G02Y1461497I-1664J-1456D01*
G03X1713778Y1461365I150J-132D01*
G01Y1460743D01*
G02X1713575Y1460540I-203J0D01*
G01X1710755D01*
G02X1710552Y1460743I0J203D01*
G01Y1461365D01*
G03X1710502Y1461497I-200J0D01*
G02Y1464409I1664J1456D01*
G03X1710552Y1464541I-150J132D01*
G01Y1466483D01*
G03X1710502Y1466615I-200J0D01*
G02Y1469527I1664J1456D01*
G03X1710552Y1469659I-150J132D01*
G01Y1470281D01*
G02X1710755Y1470484I203J0D01*
G37*
G36*
G01X125795Y1481508D02*
X128615D01*
G02X128818Y1481305I0J-203D01*
G01Y1480683D01*
G03X128868Y1480551I200J0D01*
G02Y1477639I-1664J-1456D01*
G03X128818Y1477507I150J-132D01*
G01Y1475565D01*
G03X128868Y1475433I200J0D01*
G02Y1472521I-1664J-1456D01*
G03X128818Y1472389I150J-132D01*
G01Y1471767D01*
G02X128615Y1471564I-203J0D01*
G01X125795D01*
G02X125592Y1471767I0J203D01*
G01Y1472389D01*
G03X125542Y1472521I-200J0D01*
G02Y1475433I1664J1456D01*
G03X125592Y1475565I-150J132D01*
G01Y1477507D01*
G03X125542Y1477639I-200J0D01*
G02Y1480551I1664J1456D01*
G03X125592Y1480683I-150J132D01*
G01Y1481305D01*
G02X125795Y1481508I203J0D01*
G37*
G36*
G01X143118D02*
X145938D01*
G02X146140Y1481305I-1J-203D01*
G01Y1480685D01*
G03X146190Y1480553I200J0D01*
G02Y1477637I-1661J-1458D01*
G03X146140Y1477505I150J-132D01*
G01Y1475567D01*
G03X146190Y1475435I200J0D01*
G02Y1472519I-1661J-1458D01*
G03X146140Y1472387I150J-132D01*
G01Y1471767D01*
G02X145938Y1471564I-202J-1D01*
G01X143118D01*
G02X142916Y1471767I1J203D01*
G01Y1472387D01*
G03X142866Y1472519I-200J0D01*
G02Y1475435I1661J1458D01*
G03X142916Y1475567I-150J132D01*
G01Y1477505D01*
G03X142866Y1477637I-200J0D01*
G02Y1480553I1661J1458D01*
G03X142916Y1480685I-150J132D01*
G01Y1481305D01*
G02X143118Y1481508I202J1D01*
G37*
G36*
G01X160440D02*
X163260D01*
G02X163462Y1481305I-1J-203D01*
G01Y1480685D01*
G03X163512Y1480553I200J0D01*
G02Y1477637I-1661J-1458D01*
G03X163462Y1477505I150J-132D01*
G01Y1475567D01*
G03X163512Y1475435I200J0D01*
G02Y1472519I-1661J-1458D01*
G03X163462Y1472387I150J-132D01*
G01Y1471767D01*
G02X163260Y1471564I-202J-1D01*
G01X160440D01*
G02X160238Y1471767I1J203D01*
G01Y1472387D01*
G03X160188Y1472519I-200J0D01*
G02Y1475435I1661J1458D01*
G03X160238Y1475567I-150J132D01*
G01Y1477505D01*
G03X160188Y1477637I-200J0D01*
G02Y1480553I1661J1458D01*
G03X160238Y1480685I-150J132D01*
G01Y1481305D01*
G02X160440Y1481508I202J1D01*
G37*
G36*
G01X177763D02*
X180583D01*
G02X180786Y1481305I0J-203D01*
G01Y1480683D01*
G03X180836Y1480551I200J0D01*
G02Y1477639I-1664J-1456D01*
G03X180786Y1477507I150J-132D01*
G01Y1475565D01*
G03X180836Y1475433I200J0D01*
G02Y1472521I-1664J-1456D01*
G03X180786Y1472389I150J-132D01*
G01Y1471767D01*
G02X180583Y1471564I-203J0D01*
G01X177763D01*
G02X177560Y1471767I0J203D01*
G01Y1472389D01*
G03X177510Y1472521I-200J0D01*
G02Y1475433I1664J1456D01*
G03X177560Y1475565I-150J132D01*
G01Y1477507D01*
G03X177510Y1477639I-200J0D01*
G02Y1480551I1664J1456D01*
G03X177560Y1480683I-150J132D01*
G01Y1481305D01*
G02X177763Y1481508I203J0D01*
G37*
G36*
G01X281700D02*
X284520D01*
G02X284722Y1481305I-1J-203D01*
G01Y1480685D01*
G03X284772Y1480553I200J0D01*
G02Y1477637I-1661J-1458D01*
G03X284722Y1477505I150J-132D01*
G01Y1475567D01*
G03X284772Y1475435I200J0D01*
G02Y1472519I-1661J-1458D01*
G03X284722Y1472387I150J-132D01*
G01Y1471767D01*
G02X284520Y1471564I-202J-1D01*
G01X281700D01*
G02X281498Y1471767I1J203D01*
G01Y1472387D01*
G03X281448Y1472519I-200J0D01*
G02Y1475435I1661J1458D01*
G03X281498Y1475567I-150J132D01*
G01Y1477505D01*
G03X281448Y1477637I-200J0D01*
G02Y1480553I1661J1458D01*
G03X281498Y1480685I-150J132D01*
G01Y1481305D01*
G02X281700Y1481508I202J1D01*
G37*
G36*
G01X299023D02*
X301843D01*
G02X302046Y1481305I0J-203D01*
G01Y1480683D01*
G03X302096Y1480551I200J0D01*
G02Y1477639I-1664J-1456D01*
G03X302046Y1477507I150J-132D01*
G01Y1475565D01*
G03X302096Y1475433I200J0D01*
G02Y1472521I-1664J-1456D01*
G03X302046Y1472389I150J-132D01*
G01Y1471767D01*
G02X301843Y1471564I-203J0D01*
G01X299023D01*
G02X298820Y1471767I0J203D01*
G01Y1472389D01*
G03X298770Y1472521I-200J0D01*
G02Y1475433I1664J1456D01*
G03X298820Y1475565I-150J132D01*
G01Y1477507D01*
G03X298770Y1477639I-200J0D01*
G02Y1480551I1664J1456D01*
G03X298820Y1480683I-150J132D01*
G01Y1481305D01*
G02X299023Y1481508I203J0D01*
G37*
G36*
G01X454929D02*
X457749D01*
G02X457952Y1481305I0J-203D01*
G01Y1480683D01*
G03X458002Y1480551I200J0D01*
G02Y1477639I-1664J-1456D01*
G03X457952Y1477507I150J-132D01*
G01Y1475565D01*
G03X458002Y1475433I200J0D01*
G02Y1472521I-1664J-1456D01*
G03X457952Y1472389I150J-132D01*
G01Y1471767D01*
G02X457749Y1471564I-203J0D01*
G01X454929D01*
G02X454726Y1471767I0J203D01*
G01Y1472389D01*
G03X454676Y1472521I-200J0D01*
G02Y1475433I1664J1456D01*
G03X454726Y1475565I-150J132D01*
G01Y1477507D01*
G03X454676Y1477639I-200J0D01*
G02Y1480551I1664J1456D01*
G03X454726Y1480683I-150J132D01*
G01Y1481305D01*
G02X454929Y1481508I203J0D01*
G37*
G36*
G01X472252D02*
X475072D01*
G02X475274Y1481305I-1J-203D01*
G01Y1480685D01*
G03X475324Y1480553I200J0D01*
G02Y1477637I-1661J-1458D01*
G03X475274Y1477505I150J-132D01*
G01Y1475567D01*
G03X475324Y1475435I200J0D01*
G02Y1472519I-1661J-1458D01*
G03X475274Y1472387I150J-132D01*
G01Y1471767D01*
G02X475072Y1471564I-202J-1D01*
G01X472252D01*
G02X472050Y1471767I1J203D01*
G01Y1472387D01*
G03X472000Y1472519I-200J0D01*
G02Y1475435I1661J1458D01*
G03X472050Y1475567I-150J132D01*
G01Y1477505D01*
G03X472000Y1477637I-200J0D01*
G02Y1480553I1661J1458D01*
G03X472050Y1480685I-150J132D01*
G01Y1481305D01*
G02X472252Y1481508I202J1D01*
G37*
G36*
G01X489575D02*
X492395D01*
G02X492598Y1481305I0J-203D01*
G01Y1480683D01*
G03X492648Y1480551I200J0D01*
G02Y1477639I-1664J-1456D01*
G03X492598Y1477507I150J-132D01*
G01Y1475565D01*
G03X492648Y1475433I200J0D01*
G02Y1472521I-1664J-1456D01*
G03X492598Y1472389I150J-132D01*
G01Y1471767D01*
G02X492395Y1471564I-203J0D01*
G01X489575D01*
G02X489372Y1471767I0J203D01*
G01Y1472389D01*
G03X489322Y1472521I-200J0D01*
G02Y1475433I1664J1456D01*
G03X489372Y1475565I-150J132D01*
G01Y1477507D01*
G03X489322Y1477639I-200J0D01*
G02Y1480551I1664J1456D01*
G03X489372Y1480683I-150J132D01*
G01Y1481305D01*
G02X489575Y1481508I203J0D01*
G37*
G36*
G01X506897D02*
X509717D01*
G02X509920Y1481305I0J-203D01*
G01Y1480683D01*
G03X509970Y1480551I200J0D01*
G02Y1477639I-1664J-1456D01*
G03X509920Y1477507I150J-132D01*
G01Y1475565D01*
G03X509970Y1475433I200J0D01*
G02Y1472521I-1664J-1456D01*
G03X509920Y1472389I150J-132D01*
G01Y1471767D01*
G02X509717Y1471564I-203J0D01*
G01X506897D01*
G02X506694Y1471767I0J203D01*
G01Y1472389D01*
G03X506644Y1472521I-200J0D01*
G02Y1475433I1664J1456D01*
G03X506694Y1475565I-150J132D01*
G01Y1477507D01*
G03X506644Y1477639I-200J0D01*
G02Y1480551I1664J1456D01*
G03X506694Y1480683I-150J132D01*
G01Y1481305D01*
G02X506897Y1481508I203J0D01*
G37*
G36*
G01X645480D02*
X648300D01*
G02X648502Y1481305I-1J-203D01*
G01Y1480685D01*
G03X648552Y1480553I200J0D01*
G02Y1477637I-1661J-1458D01*
G03X648502Y1477505I150J-132D01*
G01Y1475567D01*
G03X648552Y1475435I200J0D01*
G02Y1472519I-1661J-1458D01*
G03X648502Y1472387I150J-132D01*
G01Y1471767D01*
G02X648300Y1471564I-202J-1D01*
G01X645480D01*
G02X645278Y1471767I1J203D01*
G01Y1472387D01*
G03X645228Y1472519I-200J0D01*
G02Y1475435I1661J1458D01*
G03X645278Y1475567I-150J132D01*
G01Y1477505D01*
G03X645228Y1477637I-200J0D01*
G02Y1480553I1661J1458D01*
G03X645278Y1480685I-150J132D01*
G01Y1481305D01*
G02X645480Y1481508I202J1D01*
G37*
G36*
G01X662803D02*
X665623D01*
G02X665826Y1481305I0J-203D01*
G01Y1480683D01*
G03X665876Y1480551I200J0D01*
G02Y1477639I-1664J-1456D01*
G03X665826Y1477507I150J-132D01*
G01Y1475565D01*
G03X665876Y1475433I200J0D01*
G02Y1472521I-1664J-1456D01*
G03X665826Y1472389I150J-132D01*
G01Y1471767D01*
G02X665623Y1471564I-203J0D01*
G01X662803D01*
G02X662600Y1471767I0J203D01*
G01Y1472389D01*
G03X662550Y1472521I-200J0D01*
G02Y1475433I1664J1456D01*
G03X662600Y1475565I-150J132D01*
G01Y1477507D01*
G03X662550Y1477639I-200J0D01*
G02Y1480551I1664J1456D01*
G03X662600Y1480683I-150J132D01*
G01Y1481305D01*
G02X662803Y1481508I203J0D01*
G37*
G36*
G01X680125D02*
X682945D01*
G02X683148Y1481305I0J-203D01*
G01Y1480683D01*
G03X683198Y1480551I200J0D01*
G02Y1477639I-1664J-1456D01*
G03X683148Y1477507I150J-132D01*
G01Y1475565D01*
G03X683198Y1475433I200J0D01*
G02Y1472521I-1664J-1456D01*
G03X683148Y1472389I150J-132D01*
G01Y1471767D01*
G02X682945Y1471564I-203J0D01*
G01X680125D01*
G02X679922Y1471767I0J203D01*
G01Y1472389D01*
G03X679872Y1472521I-200J0D01*
G02Y1475433I1664J1456D01*
G03X679922Y1475565I-150J132D01*
G01Y1477507D01*
G03X679872Y1477639I-200J0D01*
G02Y1480551I1664J1456D01*
G03X679922Y1480683I-150J132D01*
G01Y1481305D01*
G02X680125Y1481508I203J0D01*
G37*
G36*
G01X1165086D02*
X1167906D01*
G02X1168108Y1481305I-1J-203D01*
G01Y1480685D01*
G03X1168158Y1480553I200J0D01*
G02Y1477637I-1661J-1458D01*
G03X1168108Y1477505I150J-132D01*
G01Y1475567D01*
G03X1168158Y1475435I200J0D01*
G02Y1472519I-1661J-1458D01*
G03X1168108Y1472387I150J-132D01*
G01Y1471767D01*
G02X1167906Y1471564I-202J-1D01*
G01X1165086D01*
G02X1164884Y1471767I1J203D01*
G01Y1472387D01*
G03X1164834Y1472519I-200J0D01*
G02Y1475435I1661J1458D01*
G03X1164884Y1475567I-150J132D01*
G01Y1477505D01*
G03X1164834Y1477637I-200J0D01*
G02Y1480553I1661J1458D01*
G03X1164884Y1480685I-150J132D01*
G01Y1481305D01*
G02X1165086Y1481508I202J1D01*
G37*
G36*
G01X1182408D02*
X1185228D01*
G02X1185430Y1481305I-1J-203D01*
G01Y1480685D01*
G03X1185480Y1480553I200J0D01*
G02Y1477637I-1661J-1458D01*
G03X1185430Y1477505I150J-132D01*
G01Y1475567D01*
G03X1185480Y1475435I200J0D01*
G02Y1472519I-1661J-1458D01*
G03X1185430Y1472387I150J-132D01*
G01Y1471767D01*
G02X1185228Y1471564I-202J-1D01*
G01X1182408D01*
G02X1182206Y1471767I1J203D01*
G01Y1472387D01*
G03X1182156Y1472519I-200J0D01*
G02Y1475435I1661J1458D01*
G03X1182206Y1475567I-150J132D01*
G01Y1477505D01*
G03X1182156Y1477637I-200J0D01*
G02Y1480553I1661J1458D01*
G03X1182206Y1480685I-150J132D01*
G01Y1481305D01*
G02X1182408Y1481508I202J1D01*
G37*
G36*
G01X1303669D02*
X1306489D01*
G02X1306692Y1481305I0J-203D01*
G01Y1480683D01*
G03X1306742Y1480551I200J0D01*
G02Y1477639I-1664J-1456D01*
G03X1306692Y1477507I150J-132D01*
G01Y1475565D01*
G03X1306742Y1475433I200J0D01*
G02Y1472521I-1664J-1456D01*
G03X1306692Y1472389I150J-132D01*
G01Y1471767D01*
G02X1306489Y1471564I-203J0D01*
G01X1303669D01*
G02X1303466Y1471767I0J203D01*
G01Y1472389D01*
G03X1303416Y1472521I-200J0D01*
G02Y1475433I1664J1456D01*
G03X1303466Y1475565I-150J132D01*
G01Y1477507D01*
G03X1303416Y1477639I-200J0D01*
G02Y1480551I1664J1456D01*
G03X1303466Y1480683I-150J132D01*
G01Y1481305D01*
G02X1303669Y1481508I203J0D01*
G37*
G36*
G01X1320992D02*
X1323812D01*
G02X1324014Y1481305I-1J-203D01*
G01Y1480685D01*
G03X1324064Y1480553I200J0D01*
G02Y1477637I-1661J-1458D01*
G03X1324014Y1477505I150J-132D01*
G01Y1475567D01*
G03X1324064Y1475435I200J0D01*
G02Y1472519I-1661J-1458D01*
G03X1324014Y1472387I150J-132D01*
G01Y1471767D01*
G02X1323812Y1471564I-202J-1D01*
G01X1320992D01*
G02X1320790Y1471767I1J203D01*
G01Y1472387D01*
G03X1320740Y1472519I-200J0D01*
G02Y1475435I1661J1458D01*
G03X1320790Y1475567I-150J132D01*
G01Y1477505D01*
G03X1320740Y1477637I-200J0D01*
G02Y1480553I1661J1458D01*
G03X1320790Y1480685I-150J132D01*
G01Y1481305D01*
G02X1320992Y1481508I202J1D01*
G37*
G36*
G01X1338315D02*
X1341135D01*
G02X1341338Y1481305I0J-203D01*
G01Y1480683D01*
G03X1341388Y1480551I200J0D01*
G02Y1477639I-1664J-1456D01*
G03X1341338Y1477507I150J-132D01*
G01Y1475565D01*
G03X1341388Y1475433I200J0D01*
G02Y1472521I-1664J-1456D01*
G03X1341338Y1472389I150J-132D01*
G01Y1471767D01*
G02X1341135Y1471564I-203J0D01*
G01X1338315D01*
G02X1338112Y1471767I0J203D01*
G01Y1472389D01*
G03X1338062Y1472521I-200J0D01*
G02Y1475433I1664J1456D01*
G03X1338112Y1475565I-150J132D01*
G01Y1477507D01*
G03X1338062Y1477639I-200J0D01*
G02Y1480551I1664J1456D01*
G03X1338112Y1480683I-150J132D01*
G01Y1481305D01*
G02X1338315Y1481508I203J0D01*
G37*
G36*
G01X1355637D02*
X1358457D01*
G02X1358660Y1481305I0J-203D01*
G01Y1480683D01*
G03X1358710Y1480551I200J0D01*
G02Y1477639I-1664J-1456D01*
G03X1358660Y1477507I150J-132D01*
G01Y1475565D01*
G03X1358710Y1475433I200J0D01*
G02Y1472521I-1664J-1456D01*
G03X1358660Y1472389I150J-132D01*
G01Y1471767D01*
G02X1358457Y1471564I-203J0D01*
G01X1355637D01*
G02X1355434Y1471767I0J203D01*
G01Y1472389D01*
G03X1355384Y1472521I-200J0D01*
G02Y1475433I1664J1456D01*
G03X1355434Y1475565I-150J132D01*
G01Y1477507D01*
G03X1355384Y1477639I-200J0D01*
G02Y1480551I1664J1456D01*
G03X1355434Y1480683I-150J132D01*
G01Y1481305D01*
G02X1355637Y1481508I203J0D01*
G37*
G36*
G01X1476897D02*
X1479717D01*
G02X1479920Y1481305I0J-203D01*
G01Y1480683D01*
G03X1479970Y1480551I200J0D01*
G02Y1477639I-1664J-1456D01*
G03X1479920Y1477507I150J-132D01*
G01Y1475565D01*
G03X1479970Y1475433I200J0D01*
G02Y1472521I-1664J-1456D01*
G03X1479920Y1472389I150J-132D01*
G01Y1471767D01*
G02X1479717Y1471564I-203J0D01*
G01X1476897D01*
G02X1476694Y1471767I0J203D01*
G01Y1472389D01*
G03X1476644Y1472521I-200J0D01*
G02Y1475433I1664J1456D01*
G03X1476694Y1475565I-150J132D01*
G01Y1477507D01*
G03X1476644Y1477639I-200J0D01*
G02Y1480551I1664J1456D01*
G03X1476694Y1480683I-150J132D01*
G01Y1481305D01*
G02X1476897Y1481508I203J0D01*
G37*
G36*
G01X1494220D02*
X1497040D01*
G02X1497242Y1481305I-1J-203D01*
G01Y1480685D01*
G03X1497292Y1480553I200J0D01*
G02Y1477637I-1661J-1458D01*
G03X1497242Y1477505I150J-132D01*
G01Y1475567D01*
G03X1497292Y1475435I200J0D01*
G02Y1472519I-1661J-1458D01*
G03X1497242Y1472387I150J-132D01*
G01Y1471767D01*
G02X1497040Y1471564I-202J-1D01*
G01X1494220D01*
G02X1494018Y1471767I1J203D01*
G01Y1472387D01*
G03X1493968Y1472519I-200J0D01*
G02Y1475435I1661J1458D01*
G03X1494018Y1475567I-150J132D01*
G01Y1477505D01*
G03X1493968Y1477637I-200J0D01*
G02Y1480553I1661J1458D01*
G03X1494018Y1480685I-150J132D01*
G01Y1481305D01*
G02X1494220Y1481508I202J1D01*
G37*
G36*
G01X1511543D02*
X1514363D01*
G02X1514566Y1481305I0J-203D01*
G01Y1480683D01*
G03X1514616Y1480551I200J0D01*
G02Y1477639I-1664J-1456D01*
G03X1514566Y1477507I150J-132D01*
G01Y1475565D01*
G03X1514616Y1475433I200J0D01*
G02Y1472521I-1664J-1456D01*
G03X1514566Y1472389I150J-132D01*
G01Y1471767D01*
G02X1514363Y1471564I-203J0D01*
G01X1511543D01*
G02X1511340Y1471767I0J203D01*
G01Y1472389D01*
G03X1511290Y1472521I-200J0D01*
G02Y1475433I1664J1456D01*
G03X1511340Y1475565I-150J132D01*
G01Y1477507D01*
G03X1511290Y1477639I-200J0D01*
G02Y1480551I1664J1456D01*
G03X1511340Y1480683I-150J132D01*
G01Y1481305D01*
G02X1511543Y1481508I203J0D01*
G37*
G36*
G01X1528865D02*
X1531685D01*
G02X1531888Y1481305I0J-203D01*
G01Y1480683D01*
G03X1531938Y1480551I200J0D01*
G02Y1477639I-1664J-1456D01*
G03X1531888Y1477507I150J-132D01*
G01Y1475565D01*
G03X1531938Y1475433I200J0D01*
G02Y1472521I-1664J-1456D01*
G03X1531888Y1472389I150J-132D01*
G01Y1471767D01*
G02X1531685Y1471564I-203J0D01*
G01X1528865D01*
G02X1528662Y1471767I0J203D01*
G01Y1472389D01*
G03X1528612Y1472521I-200J0D01*
G02Y1475433I1664J1456D01*
G03X1528662Y1475565I-150J132D01*
G01Y1477507D01*
G03X1528612Y1477639I-200J0D01*
G02Y1480551I1664J1456D01*
G03X1528662Y1480683I-150J132D01*
G01Y1481305D01*
G02X1528865Y1481508I203J0D01*
G37*
G36*
G01X1684771D02*
X1687591D01*
G02X1687794Y1481305I0J-203D01*
G01Y1480683D01*
G03X1687844Y1480551I200J0D01*
G02Y1477639I-1664J-1456D01*
G03X1687794Y1477507I150J-132D01*
G01Y1475565D01*
G03X1687844Y1475433I200J0D01*
G02Y1472521I-1664J-1456D01*
G03X1687794Y1472389I150J-132D01*
G01Y1471767D01*
G02X1687591Y1471564I-203J0D01*
G01X1684771D01*
G02X1684568Y1471767I0J203D01*
G01Y1472389D01*
G03X1684518Y1472521I-200J0D01*
G02Y1475433I1664J1456D01*
G03X1684568Y1475565I-150J132D01*
G01Y1477507D01*
G03X1684518Y1477639I-200J0D01*
G02Y1480551I1664J1456D01*
G03X1684568Y1480683I-150J132D01*
G01Y1481305D01*
G02X1684771Y1481508I203J0D01*
G37*
G36*
G01X1702093D02*
X1704913D01*
G02X1705116Y1481305I0J-203D01*
G01Y1480683D01*
G03X1705166Y1480551I200J0D01*
G02Y1477639I-1664J-1456D01*
G03X1705116Y1477507I150J-132D01*
G01Y1475565D01*
G03X1705166Y1475433I200J0D01*
G02Y1472521I-1664J-1456D01*
G03X1705116Y1472389I150J-132D01*
G01Y1471767D01*
G02X1704913Y1471564I-203J0D01*
G01X1702093D01*
G02X1701890Y1471767I0J203D01*
G01Y1472389D01*
G03X1701840Y1472521I-200J0D01*
G02Y1475433I1664J1456D01*
G03X1701890Y1475565I-150J132D01*
G01Y1477507D01*
G03X1701840Y1477639I-200J0D01*
G02Y1480551I1664J1456D01*
G03X1701890Y1480683I-150J132D01*
G01Y1481305D01*
G02X1702093Y1481508I203J0D01*
G37*
G36*
G01X134456Y1485838D02*
X137276D01*
G02X137478Y1485635I-1J-203D01*
G01Y1485016D01*
G03X137528Y1484884I200J0D01*
G02Y1481968I-1661J-1458D01*
G03X137478Y1481836I150J-132D01*
G01Y1479898D01*
G03X137528Y1479766I200J0D01*
G02Y1476850I-1661J-1458D01*
G03X137478Y1476718I150J-132D01*
G01Y1476097D01*
G02X137276Y1475894I-202J-1D01*
G01X134456D01*
G02X134254Y1476097I1J203D01*
G01Y1476718D01*
G03X134204Y1476850I-200J0D01*
G02Y1479766I1661J1458D01*
G03X134254Y1479898I-150J132D01*
G01Y1481836D01*
G03X134204Y1481968I-200J0D01*
G02Y1484884I1661J1458D01*
G03X134254Y1485016I-150J132D01*
G01Y1485635D01*
G02X134456Y1485838I202J1D01*
G37*
G36*
G01X151779D02*
X154599D01*
G02X154802Y1485635I0J-203D01*
G01Y1485014D01*
G03X154852Y1484882I200J0D01*
G02Y1481970I-1664J-1456D01*
G03X154802Y1481838I150J-132D01*
G01Y1479896D01*
G03X154852Y1479764I200J0D01*
G02Y1476852I-1664J-1456D01*
G03X154802Y1476720I150J-132D01*
G01Y1476097D01*
G02X154599Y1475894I-203J0D01*
G01X151779D01*
G02X151576Y1476097I0J203D01*
G01Y1476720D01*
G03X151526Y1476852I-200J0D01*
G02Y1479764I1664J1456D01*
G03X151576Y1479896I-150J132D01*
G01Y1481838D01*
G03X151526Y1481970I-200J0D01*
G02Y1484882I1664J1456D01*
G03X151576Y1485014I-150J132D01*
G01Y1485635D01*
G02X151779Y1485838I203J0D01*
G37*
G36*
G01X169102D02*
X171922D01*
G02X172124Y1485635I-1J-203D01*
G01Y1485016D01*
G03X172174Y1484884I200J0D01*
G02Y1481968I-1661J-1458D01*
G03X172124Y1481836I150J-132D01*
G01Y1479898D01*
G03X172174Y1479766I200J0D01*
G02Y1476850I-1661J-1458D01*
G03X172124Y1476718I150J-132D01*
G01Y1476097D01*
G02X171922Y1475894I-202J-1D01*
G01X169102D01*
G02X168900Y1476097I1J203D01*
G01Y1476718D01*
G03X168850Y1476850I-200J0D01*
G02Y1479766I1661J1458D01*
G03X168900Y1479898I-150J132D01*
G01Y1481836D01*
G03X168850Y1481968I-200J0D01*
G02Y1484884I1661J1458D01*
G03X168900Y1485016I-150J132D01*
G01Y1485635D01*
G02X169102Y1485838I202J1D01*
G37*
G36*
G01X290361D02*
X293181D01*
G02X293384Y1485635I0J-203D01*
G01Y1485014D01*
G03X293434Y1484882I200J0D01*
G02Y1481970I-1664J-1456D01*
G03X293384Y1481838I150J-132D01*
G01Y1479896D01*
G03X293434Y1479764I200J0D01*
G02Y1476852I-1664J-1456D01*
G03X293384Y1476720I150J-132D01*
G01Y1476097D01*
G02X293181Y1475894I-203J0D01*
G01X290361D01*
G02X290158Y1476097I0J203D01*
G01Y1476720D01*
G03X290108Y1476852I-200J0D01*
G02Y1479764I1664J1456D01*
G03X290158Y1479896I-150J132D01*
G01Y1481838D01*
G03X290108Y1481970I-200J0D01*
G02Y1484882I1664J1456D01*
G03X290158Y1485014I-150J132D01*
G01Y1485635D01*
G02X290361Y1485838I203J0D01*
G37*
G36*
G01X463590D02*
X466410D01*
G02X466612Y1485635I-1J-203D01*
G01Y1485016D01*
G03X466662Y1484884I200J0D01*
G02Y1481968I-1661J-1458D01*
G03X466612Y1481836I150J-132D01*
G01Y1479898D01*
G03X466662Y1479766I200J0D01*
G02Y1476850I-1661J-1458D01*
G03X466612Y1476718I150J-132D01*
G01Y1476097D01*
G02X466410Y1475894I-202J-1D01*
G01X463590D01*
G02X463388Y1476097I1J203D01*
G01Y1476718D01*
G03X463338Y1476850I-200J0D01*
G02Y1479766I1661J1458D01*
G03X463388Y1479898I-150J132D01*
G01Y1481836D01*
G03X463338Y1481968I-200J0D01*
G02Y1484884I1661J1458D01*
G03X463388Y1485016I-150J132D01*
G01Y1485635D01*
G02X463590Y1485838I202J1D01*
G37*
G36*
G01X480913D02*
X483733D01*
G02X483936Y1485635I0J-203D01*
G01Y1485014D01*
G03X483986Y1484882I200J0D01*
G02Y1481970I-1664J-1456D01*
G03X483936Y1481838I150J-132D01*
G01Y1479896D01*
G03X483986Y1479764I200J0D01*
G02Y1476852I-1664J-1456D01*
G03X483936Y1476720I150J-132D01*
G01Y1476097D01*
G02X483733Y1475894I-203J0D01*
G01X480913D01*
G02X480710Y1476097I0J203D01*
G01Y1476720D01*
G03X480660Y1476852I-200J0D01*
G02Y1479764I1664J1456D01*
G03X480710Y1479896I-150J132D01*
G01Y1481838D01*
G03X480660Y1481970I-200J0D01*
G02Y1484882I1664J1456D01*
G03X480710Y1485014I-150J132D01*
G01Y1485635D01*
G02X480913Y1485838I203J0D01*
G37*
G36*
G01X498236D02*
X501056D01*
G02X501258Y1485635I-1J-203D01*
G01Y1485016D01*
G03X501308Y1484884I200J0D01*
G02Y1481968I-1661J-1458D01*
G03X501258Y1481836I150J-132D01*
G01Y1479898D01*
G03X501308Y1479766I200J0D01*
G02Y1476850I-1661J-1458D01*
G03X501258Y1476718I150J-132D01*
G01Y1476097D01*
G02X501056Y1475894I-202J-1D01*
G01X498236D01*
G02X498034Y1476097I1J203D01*
G01Y1476718D01*
G03X497984Y1476850I-200J0D01*
G02Y1479766I1661J1458D01*
G03X498034Y1479898I-150J132D01*
G01Y1481836D01*
G03X497984Y1481968I-200J0D01*
G02Y1484884I1661J1458D01*
G03X498034Y1485016I-150J132D01*
G01Y1485635D01*
G02X498236Y1485838I202J1D01*
G37*
G36*
G01X515559D02*
X518379D01*
G02X518582Y1485635I0J-203D01*
G01Y1485014D01*
G03X518632Y1484882I200J0D01*
G02Y1481970I-1664J-1456D01*
G03X518582Y1481838I150J-132D01*
G01Y1479896D01*
G03X518632Y1479764I200J0D01*
G02Y1476852I-1664J-1456D01*
G03X518582Y1476720I150J-132D01*
G01Y1476097D01*
G02X518379Y1475894I-203J0D01*
G01X515559D01*
G02X515356Y1476097I0J203D01*
G01Y1476720D01*
G03X515306Y1476852I-200J0D01*
G02Y1479764I1664J1456D01*
G03X515356Y1479896I-150J132D01*
G01Y1481838D01*
G03X515306Y1481970I-200J0D01*
G02Y1484882I1664J1456D01*
G03X515356Y1485014I-150J132D01*
G01Y1485635D01*
G02X515559Y1485838I203J0D01*
G37*
G36*
G01X654141D02*
X656961D01*
G02X657164Y1485635I0J-203D01*
G01Y1485014D01*
G03X657214Y1484882I200J0D01*
G02Y1481970I-1664J-1456D01*
G03X657164Y1481838I150J-132D01*
G01Y1479896D01*
G03X657214Y1479764I200J0D01*
G02Y1476852I-1664J-1456D01*
G03X657164Y1476720I150J-132D01*
G01Y1476097D01*
G02X656961Y1475894I-203J0D01*
G01X654141D01*
G02X653938Y1476097I0J203D01*
G01Y1476720D01*
G03X653888Y1476852I-200J0D01*
G02Y1479764I1664J1456D01*
G03X653938Y1479896I-150J132D01*
G01Y1481838D01*
G03X653888Y1481970I-200J0D01*
G02Y1484882I1664J1456D01*
G03X653938Y1485014I-150J132D01*
G01Y1485635D01*
G02X654141Y1485838I203J0D01*
G37*
G36*
G01X671464D02*
X674284D01*
G02X674486Y1485635I-1J-203D01*
G01Y1485016D01*
G03X674536Y1484884I200J0D01*
G02Y1481968I-1661J-1458D01*
G03X674486Y1481836I150J-132D01*
G01Y1479898D01*
G03X674536Y1479766I200J0D01*
G02Y1476850I-1661J-1458D01*
G03X674486Y1476718I150J-132D01*
G01Y1476097D01*
G02X674284Y1475894I-202J-1D01*
G01X671464D01*
G02X671262Y1476097I1J203D01*
G01Y1476718D01*
G03X671212Y1476850I-200J0D01*
G02Y1479766I1661J1458D01*
G03X671262Y1479898I-150J132D01*
G01Y1481836D01*
G03X671212Y1481968I-200J0D01*
G02Y1484884I1661J1458D01*
G03X671262Y1485016I-150J132D01*
G01Y1485635D01*
G02X671464Y1485838I202J1D01*
G37*
G36*
G01X688787D02*
X691607D01*
G02X691810Y1485635I0J-203D01*
G01Y1485014D01*
G03X691860Y1484882I200J0D01*
G02Y1481970I-1664J-1456D01*
G03X691810Y1481838I150J-132D01*
G01Y1479896D01*
G03X691860Y1479764I200J0D01*
G02Y1476852I-1664J-1456D01*
G03X691810Y1476720I150J-132D01*
G01Y1476097D01*
G02X691607Y1475894I-203J0D01*
G01X688787D01*
G02X688584Y1476097I0J203D01*
G01Y1476720D01*
G03X688534Y1476852I-200J0D01*
G02Y1479764I1664J1456D01*
G03X688584Y1479896I-150J132D01*
G01Y1481838D01*
G03X688534Y1481970I-200J0D01*
G02Y1484882I1664J1456D01*
G03X688584Y1485014I-150J132D01*
G01Y1485635D01*
G02X688787Y1485838I203J0D01*
G37*
G36*
G01X1173747D02*
X1176567D01*
G02X1176770Y1485635I0J-203D01*
G01Y1485014D01*
G03X1176820Y1484882I200J0D01*
G02Y1481970I-1664J-1456D01*
G03X1176770Y1481838I150J-132D01*
G01Y1479896D01*
G03X1176820Y1479764I200J0D01*
G02Y1476852I-1664J-1456D01*
G03X1176770Y1476720I150J-132D01*
G01Y1476097D01*
G02X1176567Y1475894I-203J0D01*
G01X1173747D01*
G02X1173544Y1476097I0J203D01*
G01Y1476720D01*
G03X1173494Y1476852I-200J0D01*
G02Y1479764I1664J1456D01*
G03X1173544Y1479896I-150J132D01*
G01Y1481838D01*
G03X1173494Y1481970I-200J0D01*
G02Y1484882I1664J1456D01*
G03X1173544Y1485014I-150J132D01*
G01Y1485635D01*
G02X1173747Y1485838I203J0D01*
G37*
G36*
G01X1191070D02*
X1193890D01*
G02X1194092Y1485635I-1J-203D01*
G01Y1485016D01*
G03X1194142Y1484884I200J0D01*
G02Y1481968I-1661J-1458D01*
G03X1194092Y1481836I150J-132D01*
G01Y1479898D01*
G03X1194142Y1479766I200J0D01*
G02Y1476850I-1661J-1458D01*
G03X1194092Y1476718I150J-132D01*
G01Y1476097D01*
G02X1193890Y1475894I-202J-1D01*
G01X1191070D01*
G02X1190868Y1476097I1J203D01*
G01Y1476718D01*
G03X1190818Y1476850I-200J0D01*
G02Y1479766I1661J1458D01*
G03X1190868Y1479898I-150J132D01*
G01Y1481836D01*
G03X1190818Y1481968I-200J0D01*
G02Y1484884I1661J1458D01*
G03X1190868Y1485016I-150J132D01*
G01Y1485635D01*
G02X1191070Y1485838I202J1D01*
G37*
G36*
G01X1312330D02*
X1315150D01*
G02X1315352Y1485635I-1J-203D01*
G01Y1485016D01*
G03X1315402Y1484884I200J0D01*
G02Y1481968I-1661J-1458D01*
G03X1315352Y1481836I150J-132D01*
G01Y1479898D01*
G03X1315402Y1479766I200J0D01*
G02Y1476850I-1661J-1458D01*
G03X1315352Y1476718I150J-132D01*
G01Y1476097D01*
G02X1315150Y1475894I-202J-1D01*
G01X1312330D01*
G02X1312128Y1476097I1J203D01*
G01Y1476718D01*
G03X1312078Y1476850I-200J0D01*
G02Y1479766I1661J1458D01*
G03X1312128Y1479898I-150J132D01*
G01Y1481836D01*
G03X1312078Y1481968I-200J0D01*
G02Y1484884I1661J1458D01*
G03X1312128Y1485016I-150J132D01*
G01Y1485635D01*
G02X1312330Y1485838I202J1D01*
G37*
G36*
G01X1329653D02*
X1332473D01*
G02X1332676Y1485635I0J-203D01*
G01Y1485014D01*
G03X1332726Y1484882I200J0D01*
G02Y1481970I-1664J-1456D01*
G03X1332676Y1481838I150J-132D01*
G01Y1479896D01*
G03X1332726Y1479764I200J0D01*
G02Y1476852I-1664J-1456D01*
G03X1332676Y1476720I150J-132D01*
G01Y1476097D01*
G02X1332473Y1475894I-203J0D01*
G01X1329653D01*
G02X1329450Y1476097I0J203D01*
G01Y1476720D01*
G03X1329400Y1476852I-200J0D01*
G02Y1479764I1664J1456D01*
G03X1329450Y1479896I-150J132D01*
G01Y1481838D01*
G03X1329400Y1481970I-200J0D01*
G02Y1484882I1664J1456D01*
G03X1329450Y1485014I-150J132D01*
G01Y1485635D01*
G02X1329653Y1485838I203J0D01*
G37*
G36*
G01X1346976D02*
X1349796D01*
G02X1349998Y1485635I-1J-203D01*
G01Y1485016D01*
G03X1350048Y1484884I200J0D01*
G02Y1481968I-1661J-1458D01*
G03X1349998Y1481836I150J-132D01*
G01Y1479898D01*
G03X1350048Y1479766I200J0D01*
G02Y1476850I-1661J-1458D01*
G03X1349998Y1476718I150J-132D01*
G01Y1476097D01*
G02X1349796Y1475894I-202J-1D01*
G01X1346976D01*
G02X1346774Y1476097I1J203D01*
G01Y1476718D01*
G03X1346724Y1476850I-200J0D01*
G02Y1479766I1661J1458D01*
G03X1346774Y1479898I-150J132D01*
G01Y1481836D01*
G03X1346724Y1481968I-200J0D01*
G02Y1484884I1661J1458D01*
G03X1346774Y1485016I-150J132D01*
G01Y1485635D01*
G02X1346976Y1485838I202J1D01*
G37*
G36*
G01X1364299D02*
X1367119D01*
G02X1367322Y1485635I0J-203D01*
G01Y1485014D01*
G03X1367372Y1484882I200J0D01*
G02Y1481970I-1664J-1456D01*
G03X1367322Y1481838I150J-132D01*
G01Y1479896D01*
G03X1367372Y1479764I200J0D01*
G02Y1476852I-1664J-1456D01*
G03X1367322Y1476720I150J-132D01*
G01Y1476097D01*
G02X1367119Y1475894I-203J0D01*
G01X1364299D01*
G02X1364096Y1476097I0J203D01*
G01Y1476720D01*
G03X1364046Y1476852I-200J0D01*
G02Y1479764I1664J1456D01*
G03X1364096Y1479896I-150J132D01*
G01Y1481838D01*
G03X1364046Y1481970I-200J0D01*
G02Y1484882I1664J1456D01*
G03X1364096Y1485014I-150J132D01*
G01Y1485635D01*
G02X1364299Y1485838I203J0D01*
G37*
G36*
G01X1485558D02*
X1488378D01*
G02X1488580Y1485635I-1J-203D01*
G01Y1485016D01*
G03X1488630Y1484884I200J0D01*
G02Y1481968I-1661J-1458D01*
G03X1488580Y1481836I150J-132D01*
G01Y1479898D01*
G03X1488630Y1479766I200J0D01*
G02Y1476850I-1661J-1458D01*
G03X1488580Y1476718I150J-132D01*
G01Y1476097D01*
G02X1488378Y1475894I-202J-1D01*
G01X1485558D01*
G02X1485356Y1476097I1J203D01*
G01Y1476718D01*
G03X1485306Y1476850I-200J0D01*
G02Y1479766I1661J1458D01*
G03X1485356Y1479898I-150J132D01*
G01Y1481836D01*
G03X1485306Y1481968I-200J0D01*
G02Y1484884I1661J1458D01*
G03X1485356Y1485016I-150J132D01*
G01Y1485635D01*
G02X1485558Y1485838I202J1D01*
G37*
G36*
G01X1502881D02*
X1505701D01*
G02X1505904Y1485635I0J-203D01*
G01Y1485014D01*
G03X1505954Y1484882I200J0D01*
G02Y1481970I-1664J-1456D01*
G03X1505904Y1481838I150J-132D01*
G01Y1479896D01*
G03X1505954Y1479764I200J0D01*
G02Y1476852I-1664J-1456D01*
G03X1505904Y1476720I150J-132D01*
G01Y1476097D01*
G02X1505701Y1475894I-203J0D01*
G01X1502881D01*
G02X1502678Y1476097I0J203D01*
G01Y1476720D01*
G03X1502628Y1476852I-200J0D01*
G02Y1479764I1664J1456D01*
G03X1502678Y1479896I-150J132D01*
G01Y1481838D01*
G03X1502628Y1481970I-200J0D01*
G02Y1484882I1664J1456D01*
G03X1502678Y1485014I-150J132D01*
G01Y1485635D01*
G02X1502881Y1485838I203J0D01*
G37*
G36*
G01X1520204D02*
X1523024D01*
G02X1523226Y1485635I-1J-203D01*
G01Y1485016D01*
G03X1523276Y1484884I200J0D01*
G02Y1481968I-1661J-1458D01*
G03X1523226Y1481836I150J-132D01*
G01Y1479898D01*
G03X1523276Y1479766I200J0D01*
G02Y1476850I-1661J-1458D01*
G03X1523226Y1476718I150J-132D01*
G01Y1476097D01*
G02X1523024Y1475894I-202J-1D01*
G01X1520204D01*
G02X1520002Y1476097I1J203D01*
G01Y1476718D01*
G03X1519952Y1476850I-200J0D01*
G02Y1479766I1661J1458D01*
G03X1520002Y1479898I-150J132D01*
G01Y1481836D01*
G03X1519952Y1481968I-200J0D01*
G02Y1484884I1661J1458D01*
G03X1520002Y1485016I-150J132D01*
G01Y1485635D01*
G02X1520204Y1485838I202J1D01*
G37*
G36*
G01X1537527D02*
X1540347D01*
G02X1540550Y1485635I0J-203D01*
G01Y1485014D01*
G03X1540600Y1484882I200J0D01*
G02Y1481970I-1664J-1456D01*
G03X1540550Y1481838I150J-132D01*
G01Y1479896D01*
G03X1540600Y1479764I200J0D01*
G02Y1476852I-1664J-1456D01*
G03X1540550Y1476720I150J-132D01*
G01Y1476097D01*
G02X1540347Y1475894I-203J0D01*
G01X1537527D01*
G02X1537324Y1476097I0J203D01*
G01Y1476720D01*
G03X1537274Y1476852I-200J0D01*
G02Y1479764I1664J1456D01*
G03X1537324Y1479896I-150J132D01*
G01Y1481838D01*
G03X1537274Y1481970I-200J0D01*
G02Y1484882I1664J1456D01*
G03X1537324Y1485014I-150J132D01*
G01Y1485635D01*
G02X1537527Y1485838I203J0D01*
G37*
G36*
G01X1693432D02*
X1696252D01*
G02X1696454Y1485635I-1J-203D01*
G01Y1485016D01*
G03X1696504Y1484884I200J0D01*
G02Y1481968I-1661J-1458D01*
G03X1696454Y1481836I150J-132D01*
G01Y1479898D01*
G03X1696504Y1479766I200J0D01*
G02Y1476850I-1661J-1458D01*
G03X1696454Y1476718I150J-132D01*
G01Y1476097D01*
G02X1696252Y1475894I-202J-1D01*
G01X1693432D01*
G02X1693230Y1476097I1J203D01*
G01Y1476718D01*
G03X1693180Y1476850I-200J0D01*
G02Y1479766I1661J1458D01*
G03X1693230Y1479898I-150J132D01*
G01Y1481836D01*
G03X1693180Y1481968I-200J0D01*
G02Y1484884I1661J1458D01*
G03X1693230Y1485016I-150J132D01*
G01Y1485635D01*
G02X1693432Y1485838I202J1D01*
G37*
G36*
G01X1710755D02*
X1713575D01*
G02X1713778Y1485635I0J-203D01*
G01Y1485014D01*
G03X1713828Y1484882I200J0D01*
G02Y1481970I-1664J-1456D01*
G03X1713778Y1481838I150J-132D01*
G01Y1479896D01*
G03X1713828Y1479764I200J0D01*
G02Y1476852I-1664J-1456D01*
G03X1713778Y1476720I150J-132D01*
G01Y1476097D01*
G02X1713575Y1475894I-203J0D01*
G01X1710755D01*
G02X1710552Y1476097I0J203D01*
G01Y1476720D01*
G03X1710502Y1476852I-200J0D01*
G02Y1479764I1664J1456D01*
G03X1710552Y1479896I-150J132D01*
G01Y1481838D01*
G03X1710502Y1481970I-200J0D01*
G02Y1484882I1664J1456D01*
G03X1710552Y1485014I-150J132D01*
G01Y1485635D01*
G02X1710755Y1485838I203J0D01*
G37*
G36*
G01X186425D02*
X189245D01*
G02X189448Y1485636I1J-202D01*
G01Y1485014D01*
G03X189498Y1484882I200J0D01*
G02Y1481970I-1664J-1456D01*
G03X189448Y1481838I150J-132D01*
G01Y1479896D01*
G03X189498Y1479764I200J0D01*
G02Y1476852I-1664J-1456D01*
G03X189448Y1476720I150J-132D01*
G01Y1476098D01*
G02X189245Y1475896I-203J1D01*
G01X186425D01*
G02X186222Y1476098I-1J202D01*
G01Y1476720D01*
G03X186172Y1476852I-200J0D01*
G02Y1479764I1664J1456D01*
G03X186222Y1479896I-150J132D01*
G01Y1481838D01*
G03X186172Y1481970I-200J0D01*
G02Y1484882I1664J1456D01*
G03X186222Y1485014I-150J132D01*
G01Y1485636D01*
G02X186425Y1485838I203J-1D01*
G37*
G36*
G01X125795Y1496862D02*
X128615D01*
G02X128818Y1496659I0J-203D01*
G01Y1496037D01*
G03X128868Y1495905I200J0D01*
G02Y1492993I-1664J-1456D01*
G03X128818Y1492861I150J-132D01*
G01Y1490919D01*
G03X128868Y1490787I200J0D01*
G02Y1487875I-1664J-1456D01*
G03X128818Y1487743I150J-132D01*
G01Y1487121D01*
G02X128615Y1486918I-203J0D01*
G01X125795D01*
G02X125592Y1487121I0J203D01*
G01Y1487743D01*
G03X125542Y1487875I-200J0D01*
G02Y1490787I1664J1456D01*
G03X125592Y1490919I-150J132D01*
G01Y1492861D01*
G03X125542Y1492993I-200J0D01*
G02Y1495905I1664J1456D01*
G03X125592Y1496037I-150J132D01*
G01Y1496659D01*
G02X125795Y1496862I203J0D01*
G37*
G36*
G01X143118D02*
X145938D01*
G02X146140Y1496659I-1J-203D01*
G01Y1496039D01*
G03X146190Y1495907I200J0D01*
G02Y1492991I-1661J-1458D01*
G03X146140Y1492859I150J-132D01*
G01Y1490921D01*
G03X146190Y1490789I200J0D01*
G02Y1487873I-1661J-1458D01*
G03X146140Y1487741I150J-132D01*
G01Y1487121D01*
G02X145938Y1486918I-202J-1D01*
G01X143118D01*
G02X142916Y1487121I1J203D01*
G01Y1487741D01*
G03X142866Y1487873I-200J0D01*
G02Y1490789I1661J1458D01*
G03X142916Y1490921I-150J132D01*
G01Y1492859D01*
G03X142866Y1492991I-200J0D01*
G02Y1495907I1661J1458D01*
G03X142916Y1496039I-150J132D01*
G01Y1496659D01*
G02X143118Y1496862I202J1D01*
G37*
G36*
G01X160440D02*
X163260D01*
G02X163462Y1496659I-1J-203D01*
G01Y1496039D01*
G03X163512Y1495907I200J0D01*
G02Y1492991I-1661J-1458D01*
G03X163462Y1492859I150J-132D01*
G01Y1490921D01*
G03X163512Y1490789I200J0D01*
G02Y1487873I-1661J-1458D01*
G03X163462Y1487741I150J-132D01*
G01Y1487121D01*
G02X163260Y1486918I-202J-1D01*
G01X160440D01*
G02X160238Y1487121I1J203D01*
G01Y1487741D01*
G03X160188Y1487873I-200J0D01*
G02Y1490789I1661J1458D01*
G03X160238Y1490921I-150J132D01*
G01Y1492859D01*
G03X160188Y1492991I-200J0D01*
G02Y1495907I1661J1458D01*
G03X160238Y1496039I-150J132D01*
G01Y1496659D01*
G02X160440Y1496862I202J1D01*
G37*
G36*
G01X281700D02*
X284520D01*
G02X284722Y1496659I-1J-203D01*
G01Y1496039D01*
G03X284772Y1495907I200J0D01*
G02Y1492991I-1661J-1458D01*
G03X284722Y1492859I150J-132D01*
G01Y1490921D01*
G03X284772Y1490789I200J0D01*
G02Y1487873I-1661J-1458D01*
G03X284722Y1487741I150J-132D01*
G01Y1487121D01*
G02X284520Y1486918I-202J-1D01*
G01X281700D01*
G02X281498Y1487121I1J203D01*
G01Y1487741D01*
G03X281448Y1487873I-200J0D01*
G02Y1490789I1661J1458D01*
G03X281498Y1490921I-150J132D01*
G01Y1492859D01*
G03X281448Y1492991I-200J0D01*
G02Y1495907I1661J1458D01*
G03X281498Y1496039I-150J132D01*
G01Y1496659D01*
G02X281700Y1496862I202J1D01*
G37*
G36*
G01X299023D02*
X301843D01*
G02X302046Y1496659I0J-203D01*
G01Y1496037D01*
G03X302096Y1495905I200J0D01*
G02Y1492993I-1664J-1456D01*
G03X302046Y1492861I150J-132D01*
G01Y1490919D01*
G03X302096Y1490787I200J0D01*
G02Y1487875I-1664J-1456D01*
G03X302046Y1487743I150J-132D01*
G01Y1487121D01*
G02X301843Y1486918I-203J0D01*
G01X299023D01*
G02X298820Y1487121I0J203D01*
G01Y1487743D01*
G03X298770Y1487875I-200J0D01*
G02Y1490787I1664J1456D01*
G03X298820Y1490919I-150J132D01*
G01Y1492861D01*
G03X298770Y1492993I-200J0D01*
G02Y1495905I1664J1456D01*
G03X298820Y1496037I-150J132D01*
G01Y1496659D01*
G02X299023Y1496862I203J0D01*
G37*
G36*
G01X454929D02*
X457749D01*
G02X457952Y1496659I0J-203D01*
G01Y1496037D01*
G03X458002Y1495905I200J0D01*
G02Y1492993I-1664J-1456D01*
G03X457952Y1492861I150J-132D01*
G01Y1490919D01*
G03X458002Y1490787I200J0D01*
G02Y1487875I-1664J-1456D01*
G03X457952Y1487743I150J-132D01*
G01Y1487121D01*
G02X457749Y1486918I-203J0D01*
G01X454929D01*
G02X454726Y1487121I0J203D01*
G01Y1487743D01*
G03X454676Y1487875I-200J0D01*
G02Y1490787I1664J1456D01*
G03X454726Y1490919I-150J132D01*
G01Y1492861D01*
G03X454676Y1492993I-200J0D01*
G02Y1495905I1664J1456D01*
G03X454726Y1496037I-150J132D01*
G01Y1496659D01*
G02X454929Y1496862I203J0D01*
G37*
G36*
G01X472252D02*
X475072D01*
G02X475274Y1496659I-1J-203D01*
G01Y1496039D01*
G03X475324Y1495907I200J0D01*
G02Y1492991I-1661J-1458D01*
G03X475274Y1492859I150J-132D01*
G01Y1490921D01*
G03X475324Y1490789I200J0D01*
G02Y1487873I-1661J-1458D01*
G03X475274Y1487741I150J-132D01*
G01Y1487121D01*
G02X475072Y1486918I-202J-1D01*
G01X472252D01*
G02X472050Y1487121I1J203D01*
G01Y1487741D01*
G03X472000Y1487873I-200J0D01*
G02Y1490789I1661J1458D01*
G03X472050Y1490921I-150J132D01*
G01Y1492859D01*
G03X472000Y1492991I-200J0D01*
G02Y1495907I1661J1458D01*
G03X472050Y1496039I-150J132D01*
G01Y1496659D01*
G02X472252Y1496862I202J1D01*
G37*
G36*
G01X489575D02*
X492395D01*
G02X492598Y1496659I0J-203D01*
G01Y1496037D01*
G03X492648Y1495905I200J0D01*
G02Y1492993I-1664J-1456D01*
G03X492598Y1492861I150J-132D01*
G01Y1490919D01*
G03X492648Y1490787I200J0D01*
G02Y1487875I-1664J-1456D01*
G03X492598Y1487743I150J-132D01*
G01Y1487121D01*
G02X492395Y1486918I-203J0D01*
G01X489575D01*
G02X489372Y1487121I0J203D01*
G01Y1487743D01*
G03X489322Y1487875I-200J0D01*
G02Y1490787I1664J1456D01*
G03X489372Y1490919I-150J132D01*
G01Y1492861D01*
G03X489322Y1492993I-200J0D01*
G02Y1495905I1664J1456D01*
G03X489372Y1496037I-150J132D01*
G01Y1496659D01*
G02X489575Y1496862I203J0D01*
G37*
G36*
G01X506897D02*
X509717D01*
G02X509920Y1496659I0J-203D01*
G01Y1496037D01*
G03X509970Y1495905I200J0D01*
G02Y1492993I-1664J-1456D01*
G03X509920Y1492861I150J-132D01*
G01Y1490919D01*
G03X509970Y1490787I200J0D01*
G02Y1487875I-1664J-1456D01*
G03X509920Y1487743I150J-132D01*
G01Y1487121D01*
G02X509717Y1486918I-203J0D01*
G01X506897D01*
G02X506694Y1487121I0J203D01*
G01Y1487743D01*
G03X506644Y1487875I-200J0D01*
G02Y1490787I1664J1456D01*
G03X506694Y1490919I-150J132D01*
G01Y1492861D01*
G03X506644Y1492993I-200J0D01*
G02Y1495905I1664J1456D01*
G03X506694Y1496037I-150J132D01*
G01Y1496659D01*
G02X506897Y1496862I203J0D01*
G37*
G36*
G01X645480D02*
X648300D01*
G02X648502Y1496659I-1J-203D01*
G01Y1496039D01*
G03X648552Y1495907I200J0D01*
G02Y1492991I-1661J-1458D01*
G03X648502Y1492859I150J-132D01*
G01Y1490921D01*
G03X648552Y1490789I200J0D01*
G02Y1487873I-1661J-1458D01*
G03X648502Y1487741I150J-132D01*
G01Y1487121D01*
G02X648300Y1486918I-202J-1D01*
G01X645480D01*
G02X645278Y1487121I1J203D01*
G01Y1487741D01*
G03X645228Y1487873I-200J0D01*
G02Y1490789I1661J1458D01*
G03X645278Y1490921I-150J132D01*
G01Y1492859D01*
G03X645228Y1492991I-200J0D01*
G02Y1495907I1661J1458D01*
G03X645278Y1496039I-150J132D01*
G01Y1496659D01*
G02X645480Y1496862I202J1D01*
G37*
G36*
G01X662803D02*
X665623D01*
G02X665826Y1496659I0J-203D01*
G01Y1496037D01*
G03X665876Y1495905I200J0D01*
G02Y1492993I-1664J-1456D01*
G03X665826Y1492861I150J-132D01*
G01Y1490919D01*
G03X665876Y1490787I200J0D01*
G02Y1487875I-1664J-1456D01*
G03X665826Y1487743I150J-132D01*
G01Y1487121D01*
G02X665623Y1486918I-203J0D01*
G01X662803D01*
G02X662600Y1487121I0J203D01*
G01Y1487743D01*
G03X662550Y1487875I-200J0D01*
G02Y1490787I1664J1456D01*
G03X662600Y1490919I-150J132D01*
G01Y1492861D01*
G03X662550Y1492993I-200J0D01*
G02Y1495905I1664J1456D01*
G03X662600Y1496037I-150J132D01*
G01Y1496659D01*
G02X662803Y1496862I203J0D01*
G37*
G36*
G01X680125D02*
X682945D01*
G02X683148Y1496659I0J-203D01*
G01Y1496037D01*
G03X683198Y1495905I200J0D01*
G02Y1492993I-1664J-1456D01*
G03X683148Y1492861I150J-132D01*
G01Y1490919D01*
G03X683198Y1490787I200J0D01*
G02Y1487875I-1664J-1456D01*
G03X683148Y1487743I150J-132D01*
G01Y1487121D01*
G02X682945Y1486918I-203J0D01*
G01X680125D01*
G02X679922Y1487121I0J203D01*
G01Y1487743D01*
G03X679872Y1487875I-200J0D01*
G02Y1490787I1664J1456D01*
G03X679922Y1490919I-150J132D01*
G01Y1492861D01*
G03X679872Y1492993I-200J0D01*
G02Y1495905I1664J1456D01*
G03X679922Y1496037I-150J132D01*
G01Y1496659D01*
G02X680125Y1496862I203J0D01*
G37*
G36*
G01X1165086D02*
X1167906D01*
G02X1168108Y1496659I-1J-203D01*
G01Y1496039D01*
G03X1168158Y1495907I200J0D01*
G02Y1492991I-1661J-1458D01*
G03X1168108Y1492859I150J-132D01*
G01Y1490921D01*
G03X1168158Y1490789I200J0D01*
G02Y1487873I-1661J-1458D01*
G03X1168108Y1487741I150J-132D01*
G01Y1487121D01*
G02X1167906Y1486918I-202J-1D01*
G01X1165086D01*
G02X1164884Y1487121I1J203D01*
G01Y1487741D01*
G03X1164834Y1487873I-200J0D01*
G02Y1490789I1661J1458D01*
G03X1164884Y1490921I-150J132D01*
G01Y1492859D01*
G03X1164834Y1492991I-200J0D01*
G02Y1495907I1661J1458D01*
G03X1164884Y1496039I-150J132D01*
G01Y1496659D01*
G02X1165086Y1496862I202J1D01*
G37*
G36*
G01X1182408D02*
X1185228D01*
G02X1185430Y1496659I-1J-203D01*
G01Y1496039D01*
G03X1185480Y1495907I200J0D01*
G02Y1492991I-1661J-1458D01*
G03X1185430Y1492859I150J-132D01*
G01Y1490921D01*
G03X1185480Y1490789I200J0D01*
G02Y1487873I-1661J-1458D01*
G03X1185430Y1487741I150J-132D01*
G01Y1487121D01*
G02X1185228Y1486918I-202J-1D01*
G01X1182408D01*
G02X1182206Y1487121I1J203D01*
G01Y1487741D01*
G03X1182156Y1487873I-200J0D01*
G02Y1490789I1661J1458D01*
G03X1182206Y1490921I-150J132D01*
G01Y1492859D01*
G03X1182156Y1492991I-200J0D01*
G02Y1495907I1661J1458D01*
G03X1182206Y1496039I-150J132D01*
G01Y1496659D01*
G02X1182408Y1496862I202J1D01*
G37*
G36*
G01X1303669D02*
X1306489D01*
G02X1306692Y1496659I0J-203D01*
G01Y1496037D01*
G03X1306742Y1495905I200J0D01*
G02Y1492993I-1664J-1456D01*
G03X1306692Y1492861I150J-132D01*
G01Y1490919D01*
G03X1306742Y1490787I200J0D01*
G02Y1487875I-1664J-1456D01*
G03X1306692Y1487743I150J-132D01*
G01Y1487121D01*
G02X1306489Y1486918I-203J0D01*
G01X1303669D01*
G02X1303466Y1487121I0J203D01*
G01Y1487743D01*
G03X1303416Y1487875I-200J0D01*
G02Y1490787I1664J1456D01*
G03X1303466Y1490919I-150J132D01*
G01Y1492861D01*
G03X1303416Y1492993I-200J0D01*
G02Y1495905I1664J1456D01*
G03X1303466Y1496037I-150J132D01*
G01Y1496659D01*
G02X1303669Y1496862I203J0D01*
G37*
G36*
G01X1320992D02*
X1323812D01*
G02X1324014Y1496659I-1J-203D01*
G01Y1496039D01*
G03X1324064Y1495907I200J0D01*
G02Y1492991I-1661J-1458D01*
G03X1324014Y1492859I150J-132D01*
G01Y1490921D01*
G03X1324064Y1490789I200J0D01*
G02Y1487873I-1661J-1458D01*
G03X1324014Y1487741I150J-132D01*
G01Y1487121D01*
G02X1323812Y1486918I-202J-1D01*
G01X1320992D01*
G02X1320790Y1487121I1J203D01*
G01Y1487741D01*
G03X1320740Y1487873I-200J0D01*
G02Y1490789I1661J1458D01*
G03X1320790Y1490921I-150J132D01*
G01Y1492859D01*
G03X1320740Y1492991I-200J0D01*
G02Y1495907I1661J1458D01*
G03X1320790Y1496039I-150J132D01*
G01Y1496659D01*
G02X1320992Y1496862I202J1D01*
G37*
G36*
G01X1338315D02*
X1341135D01*
G02X1341338Y1496659I0J-203D01*
G01Y1496037D01*
G03X1341388Y1495905I200J0D01*
G02Y1492993I-1664J-1456D01*
G03X1341338Y1492861I150J-132D01*
G01Y1490919D01*
G03X1341388Y1490787I200J0D01*
G02Y1487875I-1664J-1456D01*
G03X1341338Y1487743I150J-132D01*
G01Y1487121D01*
G02X1341135Y1486918I-203J0D01*
G01X1338315D01*
G02X1338112Y1487121I0J203D01*
G01Y1487743D01*
G03X1338062Y1487875I-200J0D01*
G02Y1490787I1664J1456D01*
G03X1338112Y1490919I-150J132D01*
G01Y1492861D01*
G03X1338062Y1492993I-200J0D01*
G02Y1495905I1664J1456D01*
G03X1338112Y1496037I-150J132D01*
G01Y1496659D01*
G02X1338315Y1496862I203J0D01*
G37*
G36*
G01X1355637D02*
X1358457D01*
G02X1358660Y1496659I0J-203D01*
G01Y1496037D01*
G03X1358710Y1495905I200J0D01*
G02Y1492993I-1664J-1456D01*
G03X1358660Y1492861I150J-132D01*
G01Y1490919D01*
G03X1358710Y1490787I200J0D01*
G02Y1487875I-1664J-1456D01*
G03X1358660Y1487743I150J-132D01*
G01Y1487121D01*
G02X1358457Y1486918I-203J0D01*
G01X1355637D01*
G02X1355434Y1487121I0J203D01*
G01Y1487743D01*
G03X1355384Y1487875I-200J0D01*
G02Y1490787I1664J1456D01*
G03X1355434Y1490919I-150J132D01*
G01Y1492861D01*
G03X1355384Y1492993I-200J0D01*
G02Y1495905I1664J1456D01*
G03X1355434Y1496037I-150J132D01*
G01Y1496659D01*
G02X1355637Y1496862I203J0D01*
G37*
G36*
G01X1476897D02*
X1479717D01*
G02X1479920Y1496659I0J-203D01*
G01Y1496037D01*
G03X1479970Y1495905I200J0D01*
G02Y1492993I-1664J-1456D01*
G03X1479920Y1492861I150J-132D01*
G01Y1490919D01*
G03X1479970Y1490787I200J0D01*
G02Y1487875I-1664J-1456D01*
G03X1479920Y1487743I150J-132D01*
G01Y1487121D01*
G02X1479717Y1486918I-203J0D01*
G01X1476897D01*
G02X1476694Y1487121I0J203D01*
G01Y1487743D01*
G03X1476644Y1487875I-200J0D01*
G02Y1490787I1664J1456D01*
G03X1476694Y1490919I-150J132D01*
G01Y1492861D01*
G03X1476644Y1492993I-200J0D01*
G02Y1495905I1664J1456D01*
G03X1476694Y1496037I-150J132D01*
G01Y1496659D01*
G02X1476897Y1496862I203J0D01*
G37*
G36*
G01X1494220D02*
X1497040D01*
G02X1497242Y1496659I-1J-203D01*
G01Y1496039D01*
G03X1497292Y1495907I200J0D01*
G02Y1492991I-1661J-1458D01*
G03X1497242Y1492859I150J-132D01*
G01Y1490921D01*
G03X1497292Y1490789I200J0D01*
G02Y1487873I-1661J-1458D01*
G03X1497242Y1487741I150J-132D01*
G01Y1487121D01*
G02X1497040Y1486918I-202J-1D01*
G01X1494220D01*
G02X1494018Y1487121I1J203D01*
G01Y1487741D01*
G03X1493968Y1487873I-200J0D01*
G02Y1490789I1661J1458D01*
G03X1494018Y1490921I-150J132D01*
G01Y1492859D01*
G03X1493968Y1492991I-200J0D01*
G02Y1495907I1661J1458D01*
G03X1494018Y1496039I-150J132D01*
G01Y1496659D01*
G02X1494220Y1496862I202J1D01*
G37*
G36*
G01X1511543D02*
X1514363D01*
G02X1514566Y1496659I0J-203D01*
G01Y1496037D01*
G03X1514616Y1495905I200J0D01*
G02Y1492993I-1664J-1456D01*
G03X1514566Y1492861I150J-132D01*
G01Y1490919D01*
G03X1514616Y1490787I200J0D01*
G02Y1487875I-1664J-1456D01*
G03X1514566Y1487743I150J-132D01*
G01Y1487121D01*
G02X1514363Y1486918I-203J0D01*
G01X1511543D01*
G02X1511340Y1487121I0J203D01*
G01Y1487743D01*
G03X1511290Y1487875I-200J0D01*
G02Y1490787I1664J1456D01*
G03X1511340Y1490919I-150J132D01*
G01Y1492861D01*
G03X1511290Y1492993I-200J0D01*
G02Y1495905I1664J1456D01*
G03X1511340Y1496037I-150J132D01*
G01Y1496659D01*
G02X1511543Y1496862I203J0D01*
G37*
G36*
G01X1528865D02*
X1531685D01*
G02X1531888Y1496659I0J-203D01*
G01Y1496037D01*
G03X1531938Y1495905I200J0D01*
G02Y1492993I-1664J-1456D01*
G03X1531888Y1492861I150J-132D01*
G01Y1490919D01*
G03X1531938Y1490787I200J0D01*
G02Y1487875I-1664J-1456D01*
G03X1531888Y1487743I150J-132D01*
G01Y1487121D01*
G02X1531685Y1486918I-203J0D01*
G01X1528865D01*
G02X1528662Y1487121I0J203D01*
G01Y1487743D01*
G03X1528612Y1487875I-200J0D01*
G02Y1490787I1664J1456D01*
G03X1528662Y1490919I-150J132D01*
G01Y1492861D01*
G03X1528612Y1492993I-200J0D01*
G02Y1495905I1664J1456D01*
G03X1528662Y1496037I-150J132D01*
G01Y1496659D01*
G02X1528865Y1496862I203J0D01*
G37*
G36*
G01X1684771D02*
X1687591D01*
G02X1687794Y1496659I0J-203D01*
G01Y1496037D01*
G03X1687844Y1495905I200J0D01*
G02Y1492993I-1664J-1456D01*
G03X1687794Y1492861I150J-132D01*
G01Y1490919D01*
G03X1687844Y1490787I200J0D01*
G02Y1487875I-1664J-1456D01*
G03X1687794Y1487743I150J-132D01*
G01Y1487121D01*
G02X1687591Y1486918I-203J0D01*
G01X1684771D01*
G02X1684568Y1487121I0J203D01*
G01Y1487743D01*
G03X1684518Y1487875I-200J0D01*
G02Y1490787I1664J1456D01*
G03X1684568Y1490919I-150J132D01*
G01Y1492861D01*
G03X1684518Y1492993I-200J0D01*
G02Y1495905I1664J1456D01*
G03X1684568Y1496037I-150J132D01*
G01Y1496659D01*
G02X1684771Y1496862I203J0D01*
G37*
G36*
G01X1702093D02*
X1704913D01*
G02X1705116Y1496659I0J-203D01*
G01Y1496037D01*
G03X1705166Y1495905I200J0D01*
G02Y1492993I-1664J-1456D01*
G03X1705116Y1492861I150J-132D01*
G01Y1490919D01*
G03X1705166Y1490787I200J0D01*
G02Y1487875I-1664J-1456D01*
G03X1705116Y1487743I150J-132D01*
G01Y1487121D01*
G02X1704913Y1486918I-203J0D01*
G01X1702093D01*
G02X1701890Y1487121I0J203D01*
G01Y1487743D01*
G03X1701840Y1487875I-200J0D01*
G02Y1490787I1664J1456D01*
G03X1701890Y1490919I-150J132D01*
G01Y1492861D01*
G03X1701840Y1492993I-200J0D01*
G02Y1495905I1664J1456D01*
G03X1701890Y1496037I-150J132D01*
G01Y1496659D01*
G02X1702093Y1496862I203J0D01*
G37*
G36*
G01X134456Y1501192D02*
X137276D01*
G02X137478Y1500989I-1J-203D01*
G01Y1500370D01*
G03X137528Y1500238I200J0D01*
G02Y1497322I-1661J-1458D01*
G03X137478Y1497190I150J-132D01*
G01Y1495252D01*
G03X137528Y1495120I200J0D01*
G02Y1492204I-1661J-1458D01*
G03X137478Y1492072I150J-132D01*
G01Y1491451D01*
G02X137276Y1491248I-202J-1D01*
G01X134456D01*
G02X134254Y1491451I1J203D01*
G01Y1492072D01*
G03X134204Y1492204I-200J0D01*
G02Y1495120I1661J1458D01*
G03X134254Y1495252I-150J132D01*
G01Y1497190D01*
G03X134204Y1497322I-200J0D01*
G02Y1500238I1661J1458D01*
G03X134254Y1500370I-150J132D01*
G01Y1500989D01*
G02X134456Y1501192I202J1D01*
G37*
G36*
G01X151779D02*
X154599D01*
G02X154802Y1500989I0J-203D01*
G01Y1500368D01*
G03X154852Y1500236I200J0D01*
G02Y1497324I-1664J-1456D01*
G03X154802Y1497192I150J-132D01*
G01Y1495250D01*
G03X154852Y1495118I200J0D01*
G02Y1492206I-1664J-1456D01*
G03X154802Y1492074I150J-132D01*
G01Y1491451D01*
G02X154599Y1491248I-203J0D01*
G01X151779D01*
G02X151576Y1491451I0J203D01*
G01Y1492074D01*
G03X151526Y1492206I-200J0D01*
G02Y1495118I1664J1456D01*
G03X151576Y1495250I-150J132D01*
G01Y1497192D01*
G03X151526Y1497324I-200J0D01*
G02Y1500236I1664J1456D01*
G03X151576Y1500368I-150J132D01*
G01Y1500989D01*
G02X151779Y1501192I203J0D01*
G37*
G36*
G01X169102D02*
X171922D01*
G02X172124Y1500989I-1J-203D01*
G01Y1500370D01*
G03X172174Y1500238I200J0D01*
G02Y1497322I-1661J-1458D01*
G03X172124Y1497190I150J-132D01*
G01Y1495252D01*
G03X172174Y1495120I200J0D01*
G02Y1492204I-1661J-1458D01*
G03X172124Y1492072I150J-132D01*
G01Y1491451D01*
G02X171922Y1491248I-202J-1D01*
G01X169102D01*
G02X168900Y1491451I1J203D01*
G01Y1492072D01*
G03X168850Y1492204I-200J0D01*
G02Y1495120I1661J1458D01*
G03X168900Y1495252I-150J132D01*
G01Y1497190D01*
G03X168850Y1497322I-200J0D01*
G02Y1500238I1661J1458D01*
G03X168900Y1500370I-150J132D01*
G01Y1500989D01*
G02X169102Y1501192I202J1D01*
G37*
G36*
G01X290361D02*
X293181D01*
G02X293384Y1500989I0J-203D01*
G01Y1500368D01*
G03X293434Y1500236I200J0D01*
G02Y1497324I-1664J-1456D01*
G03X293384Y1497192I150J-132D01*
G01Y1495250D01*
G03X293434Y1495118I200J0D01*
G02Y1492206I-1664J-1456D01*
G03X293384Y1492074I150J-132D01*
G01Y1491451D01*
G02X293181Y1491248I-203J0D01*
G01X290361D01*
G02X290158Y1491451I0J203D01*
G01Y1492074D01*
G03X290108Y1492206I-200J0D01*
G02Y1495118I1664J1456D01*
G03X290158Y1495250I-150J132D01*
G01Y1497192D01*
G03X290108Y1497324I-200J0D01*
G02Y1500236I1664J1456D01*
G03X290158Y1500368I-150J132D01*
G01Y1500989D01*
G02X290361Y1501192I203J0D01*
G37*
G36*
G01X463590D02*
X466410D01*
G02X466612Y1500989I-1J-203D01*
G01Y1500370D01*
G03X466662Y1500238I200J0D01*
G02Y1497322I-1661J-1458D01*
G03X466612Y1497190I150J-132D01*
G01Y1495252D01*
G03X466662Y1495120I200J0D01*
G02Y1492204I-1661J-1458D01*
G03X466612Y1492072I150J-132D01*
G01Y1491451D01*
G02X466410Y1491248I-202J-1D01*
G01X463590D01*
G02X463388Y1491451I1J203D01*
G01Y1492072D01*
G03X463338Y1492204I-200J0D01*
G02Y1495120I1661J1458D01*
G03X463388Y1495252I-150J132D01*
G01Y1497190D01*
G03X463338Y1497322I-200J0D01*
G02Y1500238I1661J1458D01*
G03X463388Y1500370I-150J132D01*
G01Y1500989D01*
G02X463590Y1501192I202J1D01*
G37*
G36*
G01X480913D02*
X483733D01*
G02X483936Y1500989I0J-203D01*
G01Y1500368D01*
G03X483986Y1500236I200J0D01*
G02Y1497324I-1664J-1456D01*
G03X483936Y1497192I150J-132D01*
G01Y1495250D01*
G03X483986Y1495118I200J0D01*
G02Y1492206I-1664J-1456D01*
G03X483936Y1492074I150J-132D01*
G01Y1491451D01*
G02X483733Y1491248I-203J0D01*
G01X480913D01*
G02X480710Y1491451I0J203D01*
G01Y1492074D01*
G03X480660Y1492206I-200J0D01*
G02Y1495118I1664J1456D01*
G03X480710Y1495250I-150J132D01*
G01Y1497192D01*
G03X480660Y1497324I-200J0D01*
G02Y1500236I1664J1456D01*
G03X480710Y1500368I-150J132D01*
G01Y1500989D01*
G02X480913Y1501192I203J0D01*
G37*
G36*
G01X498236D02*
X501056D01*
G02X501258Y1500989I-1J-203D01*
G01Y1500370D01*
G03X501308Y1500238I200J0D01*
G02Y1497322I-1661J-1458D01*
G03X501258Y1497190I150J-132D01*
G01Y1495252D01*
G03X501308Y1495120I200J0D01*
G02Y1492204I-1661J-1458D01*
G03X501258Y1492072I150J-132D01*
G01Y1491451D01*
G02X501056Y1491248I-202J-1D01*
G01X498236D01*
G02X498034Y1491451I1J203D01*
G01Y1492072D01*
G03X497984Y1492204I-200J0D01*
G02Y1495120I1661J1458D01*
G03X498034Y1495252I-150J132D01*
G01Y1497190D01*
G03X497984Y1497322I-200J0D01*
G02Y1500238I1661J1458D01*
G03X498034Y1500370I-150J132D01*
G01Y1500989D01*
G02X498236Y1501192I202J1D01*
G37*
G36*
G01X515559D02*
X518379D01*
G02X518582Y1500989I0J-203D01*
G01Y1500368D01*
G03X518632Y1500236I200J0D01*
G02Y1497324I-1664J-1456D01*
G03X518582Y1497192I150J-132D01*
G01Y1495250D01*
G03X518632Y1495118I200J0D01*
G02Y1492206I-1664J-1456D01*
G03X518582Y1492074I150J-132D01*
G01Y1491451D01*
G02X518379Y1491248I-203J0D01*
G01X515559D01*
G02X515356Y1491451I0J203D01*
G01Y1492074D01*
G03X515306Y1492206I-200J0D01*
G02Y1495118I1664J1456D01*
G03X515356Y1495250I-150J132D01*
G01Y1497192D01*
G03X515306Y1497324I-200J0D01*
G02Y1500236I1664J1456D01*
G03X515356Y1500368I-150J132D01*
G01Y1500989D01*
G02X515559Y1501192I203J0D01*
G37*
G36*
G01X654141D02*
X656961D01*
G02X657164Y1500989I0J-203D01*
G01Y1500368D01*
G03X657214Y1500236I200J0D01*
G02Y1497324I-1664J-1456D01*
G03X657164Y1497192I150J-132D01*
G01Y1495250D01*
G03X657214Y1495118I200J0D01*
G02Y1492206I-1664J-1456D01*
G03X657164Y1492074I150J-132D01*
G01Y1491451D01*
G02X656961Y1491248I-203J0D01*
G01X654141D01*
G02X653938Y1491451I0J203D01*
G01Y1492074D01*
G03X653888Y1492206I-200J0D01*
G02Y1495118I1664J1456D01*
G03X653938Y1495250I-150J132D01*
G01Y1497192D01*
G03X653888Y1497324I-200J0D01*
G02Y1500236I1664J1456D01*
G03X653938Y1500368I-150J132D01*
G01Y1500989D01*
G02X654141Y1501192I203J0D01*
G37*
G36*
G01X671464D02*
X674284D01*
G02X674486Y1500989I-1J-203D01*
G01Y1500370D01*
G03X674536Y1500238I200J0D01*
G02Y1497322I-1661J-1458D01*
G03X674486Y1497190I150J-132D01*
G01Y1495252D01*
G03X674536Y1495120I200J0D01*
G02Y1492204I-1661J-1458D01*
G03X674486Y1492072I150J-132D01*
G01Y1491451D01*
G02X674284Y1491248I-202J-1D01*
G01X671464D01*
G02X671262Y1491451I1J203D01*
G01Y1492072D01*
G03X671212Y1492204I-200J0D01*
G02Y1495120I1661J1458D01*
G03X671262Y1495252I-150J132D01*
G01Y1497190D01*
G03X671212Y1497322I-200J0D01*
G02Y1500238I1661J1458D01*
G03X671262Y1500370I-150J132D01*
G01Y1500989D01*
G02X671464Y1501192I202J1D01*
G37*
G36*
G01X688787D02*
X691607D01*
G02X691810Y1500989I0J-203D01*
G01Y1500368D01*
G03X691860Y1500236I200J0D01*
G02Y1497324I-1664J-1456D01*
G03X691810Y1497192I150J-132D01*
G01Y1495250D01*
G03X691860Y1495118I200J0D01*
G02Y1492206I-1664J-1456D01*
G03X691810Y1492074I150J-132D01*
G01Y1491451D01*
G02X691607Y1491248I-203J0D01*
G01X688787D01*
G02X688584Y1491451I0J203D01*
G01Y1492074D01*
G03X688534Y1492206I-200J0D01*
G02Y1495118I1664J1456D01*
G03X688584Y1495250I-150J132D01*
G01Y1497192D01*
G03X688534Y1497324I-200J0D01*
G02Y1500236I1664J1456D01*
G03X688584Y1500368I-150J132D01*
G01Y1500989D01*
G02X688787Y1501192I203J0D01*
G37*
G36*
G01X1173747D02*
X1176567D01*
G02X1176770Y1500989I0J-203D01*
G01Y1500368D01*
G03X1176820Y1500236I200J0D01*
G02Y1497324I-1664J-1456D01*
G03X1176770Y1497192I150J-132D01*
G01Y1495250D01*
G03X1176820Y1495118I200J0D01*
G02Y1492206I-1664J-1456D01*
G03X1176770Y1492074I150J-132D01*
G01Y1491451D01*
G02X1176567Y1491248I-203J0D01*
G01X1173747D01*
G02X1173544Y1491451I0J203D01*
G01Y1492074D01*
G03X1173494Y1492206I-200J0D01*
G02Y1495118I1664J1456D01*
G03X1173544Y1495250I-150J132D01*
G01Y1497192D01*
G03X1173494Y1497324I-200J0D01*
G02Y1500236I1664J1456D01*
G03X1173544Y1500368I-150J132D01*
G01Y1500989D01*
G02X1173747Y1501192I203J0D01*
G37*
G36*
G01X1191070D02*
X1193890D01*
G02X1194092Y1500989I-1J-203D01*
G01Y1500370D01*
G03X1194142Y1500238I200J0D01*
G02Y1497322I-1661J-1458D01*
G03X1194092Y1497190I150J-132D01*
G01Y1495252D01*
G03X1194142Y1495120I200J0D01*
G02Y1492204I-1661J-1458D01*
G03X1194092Y1492072I150J-132D01*
G01Y1491451D01*
G02X1193890Y1491248I-202J-1D01*
G01X1191070D01*
G02X1190868Y1491451I1J203D01*
G01Y1492072D01*
G03X1190818Y1492204I-200J0D01*
G02Y1495120I1661J1458D01*
G03X1190868Y1495252I-150J132D01*
G01Y1497190D01*
G03X1190818Y1497322I-200J0D01*
G02Y1500238I1661J1458D01*
G03X1190868Y1500370I-150J132D01*
G01Y1500989D01*
G02X1191070Y1501192I202J1D01*
G37*
G36*
G01X1312330D02*
X1315150D01*
G02X1315352Y1500989I-1J-203D01*
G01Y1500370D01*
G03X1315402Y1500238I200J0D01*
G02Y1497322I-1661J-1458D01*
G03X1315352Y1497190I150J-132D01*
G01Y1495252D01*
G03X1315402Y1495120I200J0D01*
G02Y1492204I-1661J-1458D01*
G03X1315352Y1492072I150J-132D01*
G01Y1491451D01*
G02X1315150Y1491248I-202J-1D01*
G01X1312330D01*
G02X1312128Y1491451I1J203D01*
G01Y1492072D01*
G03X1312078Y1492204I-200J0D01*
G02Y1495120I1661J1458D01*
G03X1312128Y1495252I-150J132D01*
G01Y1497190D01*
G03X1312078Y1497322I-200J0D01*
G02Y1500238I1661J1458D01*
G03X1312128Y1500370I-150J132D01*
G01Y1500989D01*
G02X1312330Y1501192I202J1D01*
G37*
G36*
G01X1329653D02*
X1332473D01*
G02X1332676Y1500989I0J-203D01*
G01Y1500368D01*
G03X1332726Y1500236I200J0D01*
G02Y1497324I-1664J-1456D01*
G03X1332676Y1497192I150J-132D01*
G01Y1495250D01*
G03X1332726Y1495118I200J0D01*
G02Y1492206I-1664J-1456D01*
G03X1332676Y1492074I150J-132D01*
G01Y1491451D01*
G02X1332473Y1491248I-203J0D01*
G01X1329653D01*
G02X1329450Y1491451I0J203D01*
G01Y1492074D01*
G03X1329400Y1492206I-200J0D01*
G02Y1495118I1664J1456D01*
G03X1329450Y1495250I-150J132D01*
G01Y1497192D01*
G03X1329400Y1497324I-200J0D01*
G02Y1500236I1664J1456D01*
G03X1329450Y1500368I-150J132D01*
G01Y1500989D01*
G02X1329653Y1501192I203J0D01*
G37*
G36*
G01X1346976D02*
X1349796D01*
G02X1349998Y1500989I-1J-203D01*
G01Y1500370D01*
G03X1350048Y1500238I200J0D01*
G02Y1497322I-1661J-1458D01*
G03X1349998Y1497190I150J-132D01*
G01Y1495252D01*
G03X1350048Y1495120I200J0D01*
G02Y1492204I-1661J-1458D01*
G03X1349998Y1492072I150J-132D01*
G01Y1491451D01*
G02X1349796Y1491248I-202J-1D01*
G01X1346976D01*
G02X1346774Y1491451I1J203D01*
G01Y1492072D01*
G03X1346724Y1492204I-200J0D01*
G02Y1495120I1661J1458D01*
G03X1346774Y1495252I-150J132D01*
G01Y1497190D01*
G03X1346724Y1497322I-200J0D01*
G02Y1500238I1661J1458D01*
G03X1346774Y1500370I-150J132D01*
G01Y1500989D01*
G02X1346976Y1501192I202J1D01*
G37*
G36*
G01X1364299D02*
X1367119D01*
G02X1367322Y1500989I0J-203D01*
G01Y1500368D01*
G03X1367372Y1500236I200J0D01*
G02Y1497324I-1664J-1456D01*
G03X1367322Y1497192I150J-132D01*
G01Y1495250D01*
G03X1367372Y1495118I200J0D01*
G02Y1492206I-1664J-1456D01*
G03X1367322Y1492074I150J-132D01*
G01Y1491451D01*
G02X1367119Y1491248I-203J0D01*
G01X1364299D01*
G02X1364096Y1491451I0J203D01*
G01Y1492074D01*
G03X1364046Y1492206I-200J0D01*
G02Y1495118I1664J1456D01*
G03X1364096Y1495250I-150J132D01*
G01Y1497192D01*
G03X1364046Y1497324I-200J0D01*
G02Y1500236I1664J1456D01*
G03X1364096Y1500368I-150J132D01*
G01Y1500989D01*
G02X1364299Y1501192I203J0D01*
G37*
G36*
G01X1485558D02*
X1488378D01*
G02X1488580Y1500989I-1J-203D01*
G01Y1500370D01*
G03X1488630Y1500238I200J0D01*
G02Y1497322I-1661J-1458D01*
G03X1488580Y1497190I150J-132D01*
G01Y1495252D01*
G03X1488630Y1495120I200J0D01*
G02Y1492204I-1661J-1458D01*
G03X1488580Y1492072I150J-132D01*
G01Y1491451D01*
G02X1488378Y1491248I-202J-1D01*
G01X1485558D01*
G02X1485356Y1491451I1J203D01*
G01Y1492072D01*
G03X1485306Y1492204I-200J0D01*
G02Y1495120I1661J1458D01*
G03X1485356Y1495252I-150J132D01*
G01Y1497190D01*
G03X1485306Y1497322I-200J0D01*
G02Y1500238I1661J1458D01*
G03X1485356Y1500370I-150J132D01*
G01Y1500989D01*
G02X1485558Y1501192I202J1D01*
G37*
G36*
G01X1502881D02*
X1505701D01*
G02X1505904Y1500989I0J-203D01*
G01Y1500368D01*
G03X1505954Y1500236I200J0D01*
G02Y1497324I-1664J-1456D01*
G03X1505904Y1497192I150J-132D01*
G01Y1495250D01*
G03X1505954Y1495118I200J0D01*
G02Y1492206I-1664J-1456D01*
G03X1505904Y1492074I150J-132D01*
G01Y1491451D01*
G02X1505701Y1491248I-203J0D01*
G01X1502881D01*
G02X1502678Y1491451I0J203D01*
G01Y1492074D01*
G03X1502628Y1492206I-200J0D01*
G02Y1495118I1664J1456D01*
G03X1502678Y1495250I-150J132D01*
G01Y1497192D01*
G03X1502628Y1497324I-200J0D01*
G02Y1500236I1664J1456D01*
G03X1502678Y1500368I-150J132D01*
G01Y1500989D01*
G02X1502881Y1501192I203J0D01*
G37*
G36*
G01X1520204D02*
X1523024D01*
G02X1523226Y1500989I-1J-203D01*
G01Y1500370D01*
G03X1523276Y1500238I200J0D01*
G02Y1497322I-1661J-1458D01*
G03X1523226Y1497190I150J-132D01*
G01Y1495252D01*
G03X1523276Y1495120I200J0D01*
G02Y1492204I-1661J-1458D01*
G03X1523226Y1492072I150J-132D01*
G01Y1491451D01*
G02X1523024Y1491248I-202J-1D01*
G01X1520204D01*
G02X1520002Y1491451I1J203D01*
G01Y1492072D01*
G03X1519952Y1492204I-200J0D01*
G02Y1495120I1661J1458D01*
G03X1520002Y1495252I-150J132D01*
G01Y1497190D01*
G03X1519952Y1497322I-200J0D01*
G02Y1500238I1661J1458D01*
G03X1520002Y1500370I-150J132D01*
G01Y1500989D01*
G02X1520204Y1501192I202J1D01*
G37*
G36*
G01X1537527D02*
X1540347D01*
G02X1540550Y1500989I0J-203D01*
G01Y1500368D01*
G03X1540600Y1500236I200J0D01*
G02Y1497324I-1664J-1456D01*
G03X1540550Y1497192I150J-132D01*
G01Y1495250D01*
G03X1540600Y1495118I200J0D01*
G02Y1492206I-1664J-1456D01*
G03X1540550Y1492074I150J-132D01*
G01Y1491451D01*
G02X1540347Y1491248I-203J0D01*
G01X1537527D01*
G02X1537324Y1491451I0J203D01*
G01Y1492074D01*
G03X1537274Y1492206I-200J0D01*
G02Y1495118I1664J1456D01*
G03X1537324Y1495250I-150J132D01*
G01Y1497192D01*
G03X1537274Y1497324I-200J0D01*
G02Y1500236I1664J1456D01*
G03X1537324Y1500368I-150J132D01*
G01Y1500989D01*
G02X1537527Y1501192I203J0D01*
G37*
G36*
G01X1693432D02*
X1696252D01*
G02X1696454Y1500989I-1J-203D01*
G01Y1500370D01*
G03X1696504Y1500238I200J0D01*
G02Y1497322I-1661J-1458D01*
G03X1696454Y1497190I150J-132D01*
G01Y1495252D01*
G03X1696504Y1495120I200J0D01*
G02Y1492204I-1661J-1458D01*
G03X1696454Y1492072I150J-132D01*
G01Y1491451D01*
G02X1696252Y1491248I-202J-1D01*
G01X1693432D01*
G02X1693230Y1491451I1J203D01*
G01Y1492072D01*
G03X1693180Y1492204I-200J0D01*
G02Y1495120I1661J1458D01*
G03X1693230Y1495252I-150J132D01*
G01Y1497190D01*
G03X1693180Y1497322I-200J0D01*
G02Y1500238I1661J1458D01*
G03X1693230Y1500370I-150J132D01*
G01Y1500989D01*
G02X1693432Y1501192I202J1D01*
G37*
G36*
G01X1710755D02*
X1713575D01*
G02X1713778Y1500989I0J-203D01*
G01Y1500368D01*
G03X1713828Y1500236I200J0D01*
G02Y1497324I-1664J-1456D01*
G03X1713778Y1497192I150J-132D01*
G01Y1495250D01*
G03X1713828Y1495118I200J0D01*
G02Y1492206I-1664J-1456D01*
G03X1713778Y1492074I150J-132D01*
G01Y1491451D01*
G02X1713575Y1491248I-203J0D01*
G01X1710755D01*
G02X1710552Y1491451I0J203D01*
G01Y1492074D01*
G03X1710502Y1492206I-200J0D01*
G02Y1495118I1664J1456D01*
G03X1710552Y1495250I-150J132D01*
G01Y1497192D01*
G03X1710502Y1497324I-200J0D01*
G02Y1500236I1664J1456D01*
G03X1710552Y1500368I-150J132D01*
G01Y1500989D01*
G02X1710755Y1501192I203J0D01*
G37*
G36*
G01X143118Y1512216D02*
X145938D01*
G02X146140Y1512014I0J-202D01*
G01Y1511394D01*
G03X146190Y1511262I200J0D01*
G02Y1508346I-1661J-1458D01*
G03X146140Y1508214I150J-132D01*
G01Y1506275D01*
G03X146190Y1506143I200J0D01*
G02Y1503227I-1661J-1458D01*
G03X146140Y1503095I150J-132D01*
G01Y1502476D01*
G02X145938Y1502274I-202J0D01*
G01X143118D01*
G02X142916Y1502476I0J202D01*
G01Y1503095D01*
G03X142866Y1503227I-200J0D01*
G02Y1506143I1661J1458D01*
G03X142916Y1506275I-150J132D01*
G01Y1508214D01*
G03X142866Y1508346I-200J0D01*
G02Y1511262I1661J1458D01*
G03X142916Y1511394I-150J132D01*
G01Y1512014D01*
G02X143118Y1512216I202J0D01*
G37*
G36*
G01X160440D02*
X163260D01*
G02X163462Y1512014I0J-202D01*
G01Y1511394D01*
G03X163512Y1511262I200J0D01*
G02Y1508346I-1661J-1458D01*
G03X163462Y1508214I150J-132D01*
G01Y1506275D01*
G03X163512Y1506143I200J0D01*
G02Y1503227I-1661J-1458D01*
G03X163462Y1503095I150J-132D01*
G01Y1502476D01*
G02X163260Y1502274I-202J0D01*
G01X160440D01*
G02X160238Y1502476I0J202D01*
G01Y1503095D01*
G03X160188Y1503227I-200J0D01*
G02Y1506143I1661J1458D01*
G03X160238Y1506275I-150J132D01*
G01Y1508214D01*
G03X160188Y1508346I-200J0D01*
G02Y1511262I1661J1458D01*
G03X160238Y1511394I-150J132D01*
G01Y1512014D01*
G02X160440Y1512216I202J0D01*
G37*
G36*
G01X281700D02*
X284520D01*
G02X284722Y1512014I0J-202D01*
G01Y1511394D01*
G03X284772Y1511262I200J0D01*
G02Y1508346I-1661J-1458D01*
G03X284722Y1508214I150J-132D01*
G01Y1506275D01*
G03X284772Y1506143I200J0D01*
G02Y1503227I-1661J-1458D01*
G03X284722Y1503095I150J-132D01*
G01Y1502476D01*
G02X284520Y1502274I-202J0D01*
G01X281700D01*
G02X281498Y1502476I0J202D01*
G01Y1503095D01*
G03X281448Y1503227I-200J0D01*
G02Y1506143I1661J1458D01*
G03X281498Y1506275I-150J132D01*
G01Y1508214D01*
G03X281448Y1508346I-200J0D01*
G02Y1511262I1661J1458D01*
G03X281498Y1511394I-150J132D01*
G01Y1512014D01*
G02X281700Y1512216I202J0D01*
G37*
G36*
G01X472252D02*
X475072D01*
G02X475274Y1512014I0J-202D01*
G01Y1511394D01*
G03X475324Y1511262I200J0D01*
G02Y1508346I-1661J-1458D01*
G03X475274Y1508214I150J-132D01*
G01Y1506275D01*
G03X475324Y1506143I200J0D01*
G02Y1503227I-1661J-1458D01*
G03X475274Y1503095I150J-132D01*
G01Y1502476D01*
G02X475072Y1502274I-202J0D01*
G01X472252D01*
G02X472050Y1502476I0J202D01*
G01Y1503095D01*
G03X472000Y1503227I-200J0D01*
G02Y1506143I1661J1458D01*
G03X472050Y1506275I-150J132D01*
G01Y1508214D01*
G03X472000Y1508346I-200J0D01*
G02Y1511262I1661J1458D01*
G03X472050Y1511394I-150J132D01*
G01Y1512014D01*
G02X472252Y1512216I202J0D01*
G37*
G36*
G01X645480D02*
X648300D01*
G02X648502Y1512014I0J-202D01*
G01Y1511394D01*
G03X648552Y1511262I200J0D01*
G02Y1508346I-1661J-1458D01*
G03X648502Y1508214I150J-132D01*
G01Y1506275D01*
G03X648552Y1506143I200J0D01*
G02Y1503227I-1661J-1458D01*
G03X648502Y1503095I150J-132D01*
G01Y1502476D01*
G02X648300Y1502274I-202J0D01*
G01X645480D01*
G02X645278Y1502476I0J202D01*
G01Y1503095D01*
G03X645228Y1503227I-200J0D01*
G02Y1506143I1661J1458D01*
G03X645278Y1506275I-150J132D01*
G01Y1508214D01*
G03X645228Y1508346I-200J0D01*
G02Y1511262I1661J1458D01*
G03X645278Y1511394I-150J132D01*
G01Y1512014D01*
G02X645480Y1512216I202J0D01*
G37*
G36*
G01X1165086D02*
X1167906D01*
G02X1168108Y1512014I0J-202D01*
G01Y1511394D01*
G03X1168158Y1511262I200J0D01*
G02Y1508346I-1661J-1458D01*
G03X1168108Y1508214I150J-132D01*
G01Y1506275D01*
G03X1168158Y1506143I200J0D01*
G02Y1503227I-1661J-1458D01*
G03X1168108Y1503095I150J-132D01*
G01Y1502476D01*
G02X1167906Y1502274I-202J0D01*
G01X1165086D01*
G02X1164884Y1502476I0J202D01*
G01Y1503095D01*
G03X1164834Y1503227I-200J0D01*
G02Y1506143I1661J1458D01*
G03X1164884Y1506275I-150J132D01*
G01Y1508214D01*
G03X1164834Y1508346I-200J0D01*
G02Y1511262I1661J1458D01*
G03X1164884Y1511394I-150J132D01*
G01Y1512014D01*
G02X1165086Y1512216I202J0D01*
G37*
G36*
G01X1182408D02*
X1185228D01*
G02X1185430Y1512014I0J-202D01*
G01Y1511394D01*
G03X1185480Y1511262I200J0D01*
G02Y1508346I-1661J-1458D01*
G03X1185430Y1508214I150J-132D01*
G01Y1506275D01*
G03X1185480Y1506143I200J0D01*
G02Y1503227I-1661J-1458D01*
G03X1185430Y1503095I150J-132D01*
G01Y1502476D01*
G02X1185228Y1502274I-202J0D01*
G01X1182408D01*
G02X1182206Y1502476I0J202D01*
G01Y1503095D01*
G03X1182156Y1503227I-200J0D01*
G02Y1506143I1661J1458D01*
G03X1182206Y1506275I-150J132D01*
G01Y1508214D01*
G03X1182156Y1508346I-200J0D01*
G02Y1511262I1661J1458D01*
G03X1182206Y1511394I-150J132D01*
G01Y1512014D01*
G02X1182408Y1512216I202J0D01*
G37*
G36*
G01X1320992D02*
X1323812D01*
G02X1324014Y1512014I0J-202D01*
G01Y1511394D01*
G03X1324064Y1511262I200J0D01*
G02Y1508346I-1661J-1458D01*
G03X1324014Y1508214I150J-132D01*
G01Y1506275D01*
G03X1324064Y1506143I200J0D01*
G02Y1503227I-1661J-1458D01*
G03X1324014Y1503095I150J-132D01*
G01Y1502476D01*
G02X1323812Y1502274I-202J0D01*
G01X1320992D01*
G02X1320790Y1502476I0J202D01*
G01Y1503095D01*
G03X1320740Y1503227I-200J0D01*
G02Y1506143I1661J1458D01*
G03X1320790Y1506275I-150J132D01*
G01Y1508214D01*
G03X1320740Y1508346I-200J0D01*
G02Y1511262I1661J1458D01*
G03X1320790Y1511394I-150J132D01*
G01Y1512014D01*
G02X1320992Y1512216I202J0D01*
G37*
G36*
G01X1494220D02*
X1497040D01*
G02X1497242Y1512014I0J-202D01*
G01Y1511394D01*
G03X1497292Y1511262I200J0D01*
G02Y1508346I-1661J-1458D01*
G03X1497242Y1508214I150J-132D01*
G01Y1506275D01*
G03X1497292Y1506143I200J0D01*
G02Y1503227I-1661J-1458D01*
G03X1497242Y1503095I150J-132D01*
G01Y1502476D01*
G02X1497040Y1502274I-202J0D01*
G01X1494220D01*
G02X1494018Y1502476I0J202D01*
G01Y1503095D01*
G03X1493968Y1503227I-200J0D01*
G02Y1506143I1661J1458D01*
G03X1494018Y1506275I-150J132D01*
G01Y1508214D01*
G03X1493968Y1508346I-200J0D01*
G02Y1511262I1661J1458D01*
G03X1494018Y1511394I-150J132D01*
G01Y1512014D01*
G02X1494220Y1512216I202J0D01*
G37*
G36*
G01X125795D02*
X128615D01*
G02X128818Y1512014I1J-202D01*
G01Y1511392D01*
G03X128868Y1511260I200J0D01*
G02Y1508348I-1664J-1456D01*
G03X128818Y1508216I150J-132D01*
G01Y1506273D01*
G03X128868Y1506141I200J0D01*
G02Y1503229I-1664J-1456D01*
G03X128818Y1503097I150J-132D01*
G01Y1502476D01*
G02X128615Y1502274I-203J1D01*
G01X125795D01*
G02X125592Y1502476I-1J202D01*
G01Y1503097D01*
G03X125542Y1503229I-200J0D01*
G02Y1506141I1664J1456D01*
G03X125592Y1506273I-150J132D01*
G01Y1508216D01*
G03X125542Y1508348I-200J0D01*
G02Y1511260I1664J1456D01*
G03X125592Y1511392I-150J132D01*
G01Y1512014D01*
G02X125795Y1512216I203J-1D01*
G37*
G36*
G01X299023D02*
X301843D01*
G02X302046Y1512014I1J-202D01*
G01Y1511392D01*
G03X302096Y1511260I200J0D01*
G02Y1508348I-1664J-1456D01*
G03X302046Y1508216I150J-132D01*
G01Y1506273D01*
G03X302096Y1506141I200J0D01*
G02Y1503229I-1664J-1456D01*
G03X302046Y1503097I150J-132D01*
G01Y1502476D01*
G02X301843Y1502274I-203J1D01*
G01X299023D01*
G02X298820Y1502476I-1J202D01*
G01Y1503097D01*
G03X298770Y1503229I-200J0D01*
G02Y1506141I1664J1456D01*
G03X298820Y1506273I-150J132D01*
G01Y1508216D01*
G03X298770Y1508348I-200J0D01*
G02Y1511260I1664J1456D01*
G03X298820Y1511392I-150J132D01*
G01Y1512014D01*
G02X299023Y1512216I203J-1D01*
G37*
G36*
G01X454929D02*
X457749D01*
G02X457952Y1512014I1J-202D01*
G01Y1511392D01*
G03X458002Y1511260I200J0D01*
G02Y1508348I-1664J-1456D01*
G03X457952Y1508216I150J-132D01*
G01Y1506273D01*
G03X458002Y1506141I200J0D01*
G02Y1503229I-1664J-1456D01*
G03X457952Y1503097I150J-132D01*
G01Y1502476D01*
G02X457749Y1502274I-203J1D01*
G01X454929D01*
G02X454726Y1502476I-1J202D01*
G01Y1503097D01*
G03X454676Y1503229I-200J0D01*
G02Y1506141I1664J1456D01*
G03X454726Y1506273I-150J132D01*
G01Y1508216D01*
G03X454676Y1508348I-200J0D01*
G02Y1511260I1664J1456D01*
G03X454726Y1511392I-150J132D01*
G01Y1512014D01*
G02X454929Y1512216I203J-1D01*
G37*
G36*
G01X489575D02*
X492395D01*
G02X492598Y1512014I1J-202D01*
G01Y1511392D01*
G03X492648Y1511260I200J0D01*
G02Y1508348I-1664J-1456D01*
G03X492598Y1508216I150J-132D01*
G01Y1506273D01*
G03X492648Y1506141I200J0D01*
G02Y1503229I-1664J-1456D01*
G03X492598Y1503097I150J-132D01*
G01Y1502476D01*
G02X492395Y1502274I-203J1D01*
G01X489575D01*
G02X489372Y1502476I-1J202D01*
G01Y1503097D01*
G03X489322Y1503229I-200J0D01*
G02Y1506141I1664J1456D01*
G03X489372Y1506273I-150J132D01*
G01Y1508216D01*
G03X489322Y1508348I-200J0D01*
G02Y1511260I1664J1456D01*
G03X489372Y1511392I-150J132D01*
G01Y1512014D01*
G02X489575Y1512216I203J-1D01*
G37*
G36*
G01X506897D02*
X509717D01*
G02X509920Y1512014I1J-202D01*
G01Y1511392D01*
G03X509970Y1511260I200J0D01*
G02Y1508348I-1664J-1456D01*
G03X509920Y1508216I150J-132D01*
G01Y1506273D01*
G03X509970Y1506141I200J0D01*
G02Y1503229I-1664J-1456D01*
G03X509920Y1503097I150J-132D01*
G01Y1502476D01*
G02X509717Y1502274I-203J1D01*
G01X506897D01*
G02X506694Y1502476I-1J202D01*
G01Y1503097D01*
G03X506644Y1503229I-200J0D01*
G02Y1506141I1664J1456D01*
G03X506694Y1506273I-150J132D01*
G01Y1508216D01*
G03X506644Y1508348I-200J0D01*
G02Y1511260I1664J1456D01*
G03X506694Y1511392I-150J132D01*
G01Y1512014D01*
G02X506897Y1512216I203J-1D01*
G37*
G36*
G01X662803D02*
X665623D01*
G02X665826Y1512014I1J-202D01*
G01Y1511392D01*
G03X665876Y1511260I200J0D01*
G02Y1508348I-1664J-1456D01*
G03X665826Y1508216I150J-132D01*
G01Y1506273D01*
G03X665876Y1506141I200J0D01*
G02Y1503229I-1664J-1456D01*
G03X665826Y1503097I150J-132D01*
G01Y1502476D01*
G02X665623Y1502274I-203J1D01*
G01X662803D01*
G02X662600Y1502476I-1J202D01*
G01Y1503097D01*
G03X662550Y1503229I-200J0D01*
G02Y1506141I1664J1456D01*
G03X662600Y1506273I-150J132D01*
G01Y1508216D01*
G03X662550Y1508348I-200J0D01*
G02Y1511260I1664J1456D01*
G03X662600Y1511392I-150J132D01*
G01Y1512014D01*
G02X662803Y1512216I203J-1D01*
G37*
G36*
G01X680125D02*
X682945D01*
G02X683148Y1512014I1J-202D01*
G01Y1511392D01*
G03X683198Y1511260I200J0D01*
G02Y1508348I-1664J-1456D01*
G03X683148Y1508216I150J-132D01*
G01Y1506273D01*
G03X683198Y1506141I200J0D01*
G02Y1503229I-1664J-1456D01*
G03X683148Y1503097I150J-132D01*
G01Y1502476D01*
G02X682945Y1502274I-203J1D01*
G01X680125D01*
G02X679922Y1502476I-1J202D01*
G01Y1503097D01*
G03X679872Y1503229I-200J0D01*
G02Y1506141I1664J1456D01*
G03X679922Y1506273I-150J132D01*
G01Y1508216D01*
G03X679872Y1508348I-200J0D01*
G02Y1511260I1664J1456D01*
G03X679922Y1511392I-150J132D01*
G01Y1512014D01*
G02X680125Y1512216I203J-1D01*
G37*
G36*
G01X1303669D02*
X1306489D01*
G02X1306692Y1512014I1J-202D01*
G01Y1511392D01*
G03X1306742Y1511260I200J0D01*
G02Y1508348I-1664J-1456D01*
G03X1306692Y1508216I150J-132D01*
G01Y1506273D01*
G03X1306742Y1506141I200J0D01*
G02Y1503229I-1664J-1456D01*
G03X1306692Y1503097I150J-132D01*
G01Y1502476D01*
G02X1306489Y1502274I-203J1D01*
G01X1303669D01*
G02X1303466Y1502476I-1J202D01*
G01Y1503097D01*
G03X1303416Y1503229I-200J0D01*
G02Y1506141I1664J1456D01*
G03X1303466Y1506273I-150J132D01*
G01Y1508216D01*
G03X1303416Y1508348I-200J0D01*
G02Y1511260I1664J1456D01*
G03X1303466Y1511392I-150J132D01*
G01Y1512014D01*
G02X1303669Y1512216I203J-1D01*
G37*
G36*
G01X1338315D02*
X1341135D01*
G02X1341338Y1512014I1J-202D01*
G01Y1511392D01*
G03X1341388Y1511260I200J0D01*
G02Y1508348I-1664J-1456D01*
G03X1341338Y1508216I150J-132D01*
G01Y1506273D01*
G03X1341388Y1506141I200J0D01*
G02Y1503229I-1664J-1456D01*
G03X1341338Y1503097I150J-132D01*
G01Y1502476D01*
G02X1341135Y1502274I-203J1D01*
G01X1338315D01*
G02X1338112Y1502476I-1J202D01*
G01Y1503097D01*
G03X1338062Y1503229I-200J0D01*
G02Y1506141I1664J1456D01*
G03X1338112Y1506273I-150J132D01*
G01Y1508216D01*
G03X1338062Y1508348I-200J0D01*
G02Y1511260I1664J1456D01*
G03X1338112Y1511392I-150J132D01*
G01Y1512014D01*
G02X1338315Y1512216I203J-1D01*
G37*
G36*
G01X1355637D02*
X1358457D01*
G02X1358660Y1512014I1J-202D01*
G01Y1511392D01*
G03X1358710Y1511260I200J0D01*
G02Y1508348I-1664J-1456D01*
G03X1358660Y1508216I150J-132D01*
G01Y1506273D01*
G03X1358710Y1506141I200J0D01*
G02Y1503229I-1664J-1456D01*
G03X1358660Y1503097I150J-132D01*
G01Y1502476D01*
G02X1358457Y1502274I-203J1D01*
G01X1355637D01*
G02X1355434Y1502476I-1J202D01*
G01Y1503097D01*
G03X1355384Y1503229I-200J0D01*
G02Y1506141I1664J1456D01*
G03X1355434Y1506273I-150J132D01*
G01Y1508216D01*
G03X1355384Y1508348I-200J0D01*
G02Y1511260I1664J1456D01*
G03X1355434Y1511392I-150J132D01*
G01Y1512014D01*
G02X1355637Y1512216I203J-1D01*
G37*
G36*
G01X1476897D02*
X1479717D01*
G02X1479920Y1512014I1J-202D01*
G01Y1511392D01*
G03X1479970Y1511260I200J0D01*
G02Y1508348I-1664J-1456D01*
G03X1479920Y1508216I150J-132D01*
G01Y1506273D01*
G03X1479970Y1506141I200J0D01*
G02Y1503229I-1664J-1456D01*
G03X1479920Y1503097I150J-132D01*
G01Y1502476D01*
G02X1479717Y1502274I-203J1D01*
G01X1476897D01*
G02X1476694Y1502476I-1J202D01*
G01Y1503097D01*
G03X1476644Y1503229I-200J0D01*
G02Y1506141I1664J1456D01*
G03X1476694Y1506273I-150J132D01*
G01Y1508216D01*
G03X1476644Y1508348I-200J0D01*
G02Y1511260I1664J1456D01*
G03X1476694Y1511392I-150J132D01*
G01Y1512014D01*
G02X1476897Y1512216I203J-1D01*
G37*
G36*
G01X1511543D02*
X1514363D01*
G02X1514566Y1512014I1J-202D01*
G01Y1511392D01*
G03X1514616Y1511260I200J0D01*
G02Y1508348I-1664J-1456D01*
G03X1514566Y1508216I150J-132D01*
G01Y1506273D01*
G03X1514616Y1506141I200J0D01*
G02Y1503229I-1664J-1456D01*
G03X1514566Y1503097I150J-132D01*
G01Y1502476D01*
G02X1514363Y1502274I-203J1D01*
G01X1511543D01*
G02X1511340Y1502476I-1J202D01*
G01Y1503097D01*
G03X1511290Y1503229I-200J0D01*
G02Y1506141I1664J1456D01*
G03X1511340Y1506273I-150J132D01*
G01Y1508216D01*
G03X1511290Y1508348I-200J0D01*
G02Y1511260I1664J1456D01*
G03X1511340Y1511392I-150J132D01*
G01Y1512014D01*
G02X1511543Y1512216I203J-1D01*
G37*
G36*
G01X1528865D02*
X1531685D01*
G02X1531888Y1512014I1J-202D01*
G01Y1511392D01*
G03X1531938Y1511260I200J0D01*
G02Y1508348I-1664J-1456D01*
G03X1531888Y1508216I150J-132D01*
G01Y1506273D01*
G03X1531938Y1506141I200J0D01*
G02Y1503229I-1664J-1456D01*
G03X1531888Y1503097I150J-132D01*
G01Y1502476D01*
G02X1531685Y1502274I-203J1D01*
G01X1528865D01*
G02X1528662Y1502476I-1J202D01*
G01Y1503097D01*
G03X1528612Y1503229I-200J0D01*
G02Y1506141I1664J1456D01*
G03X1528662Y1506273I-150J132D01*
G01Y1508216D01*
G03X1528612Y1508348I-200J0D01*
G02Y1511260I1664J1456D01*
G03X1528662Y1511392I-150J132D01*
G01Y1512014D01*
G02X1528865Y1512216I203J-1D01*
G37*
G36*
G01X1684771D02*
X1687591D01*
G02X1687794Y1512014I1J-202D01*
G01Y1511392D01*
G03X1687844Y1511260I200J0D01*
G02Y1508348I-1664J-1456D01*
G03X1687794Y1508216I150J-132D01*
G01Y1506273D01*
G03X1687844Y1506141I200J0D01*
G02Y1503229I-1664J-1456D01*
G03X1687794Y1503097I150J-132D01*
G01Y1502476D01*
G02X1687591Y1502274I-203J1D01*
G01X1684771D01*
G02X1684568Y1502476I-1J202D01*
G01Y1503097D01*
G03X1684518Y1503229I-200J0D01*
G02Y1506141I1664J1456D01*
G03X1684568Y1506273I-150J132D01*
G01Y1508216D01*
G03X1684518Y1508348I-200J0D01*
G02Y1511260I1664J1456D01*
G03X1684568Y1511392I-150J132D01*
G01Y1512014D01*
G02X1684771Y1512216I203J-1D01*
G37*
G36*
G01X1702093D02*
X1704913D01*
G02X1705116Y1512014I1J-202D01*
G01Y1511392D01*
G03X1705166Y1511260I200J0D01*
G02Y1508348I-1664J-1456D01*
G03X1705116Y1508216I150J-132D01*
G01Y1506273D01*
G03X1705166Y1506141I200J0D01*
G02Y1503229I-1664J-1456D01*
G03X1705116Y1503097I150J-132D01*
G01Y1502476D01*
G02X1704913Y1502274I-203J1D01*
G01X1702093D01*
G02X1701890Y1502476I-1J202D01*
G01Y1503097D01*
G03X1701840Y1503229I-200J0D01*
G02Y1506141I1664J1456D01*
G03X1701890Y1506273I-150J132D01*
G01Y1508216D01*
G03X1701840Y1508348I-200J0D01*
G02Y1511260I1664J1456D01*
G03X1701890Y1511392I-150J132D01*
G01Y1512014D01*
G02X1702093Y1512216I203J-1D01*
G37*
G36*
G01X134456Y1516546D02*
X137276D01*
G02X137478Y1516344I0J-202D01*
G01Y1515724D01*
G03X137528Y1515592I200J0D01*
G02Y1512676I-1661J-1458D01*
G03X137478Y1512544I150J-132D01*
G01Y1510606D01*
G03X137528Y1510474I200J0D01*
G02Y1507558I-1661J-1458D01*
G03X137478Y1507426I150J-132D01*
G01Y1506806D01*
G02X137276Y1506604I-202J0D01*
G01X134456D01*
G02X134254Y1506806I0J202D01*
G01Y1507426D01*
G03X134204Y1507558I-200J0D01*
G02Y1510474I1661J1458D01*
G03X134254Y1510606I-150J132D01*
G01Y1512544D01*
G03X134204Y1512676I-200J0D01*
G02Y1515592I1661J1458D01*
G03X134254Y1515724I-150J132D01*
G01Y1516344D01*
G02X134456Y1516546I202J0D01*
G37*
G36*
G01X169102D02*
X171922D01*
G02X172124Y1516344I0J-202D01*
G01Y1515724D01*
G03X172174Y1515592I200J0D01*
G02Y1512676I-1661J-1458D01*
G03X172124Y1512544I150J-132D01*
G01Y1510606D01*
G03X172174Y1510474I200J0D01*
G02Y1507558I-1661J-1458D01*
G03X172124Y1507426I150J-132D01*
G01Y1506806D01*
G02X171922Y1506604I-202J0D01*
G01X169102D01*
G02X168900Y1506806I0J202D01*
G01Y1507426D01*
G03X168850Y1507558I-200J0D01*
G02Y1510474I1661J1458D01*
G03X168900Y1510606I-150J132D01*
G01Y1512544D01*
G03X168850Y1512676I-200J0D01*
G02Y1515592I1661J1458D01*
G03X168900Y1515724I-150J132D01*
G01Y1516344D01*
G02X169102Y1516546I202J0D01*
G37*
G36*
G01X463590D02*
X466410D01*
G02X466612Y1516344I0J-202D01*
G01Y1515724D01*
G03X466662Y1515592I200J0D01*
G02Y1512676I-1661J-1458D01*
G03X466612Y1512544I150J-132D01*
G01Y1510606D01*
G03X466662Y1510474I200J0D01*
G02Y1507558I-1661J-1458D01*
G03X466612Y1507426I150J-132D01*
G01Y1506806D01*
G02X466410Y1506604I-202J0D01*
G01X463590D01*
G02X463388Y1506806I0J202D01*
G01Y1507426D01*
G03X463338Y1507558I-200J0D01*
G02Y1510474I1661J1458D01*
G03X463388Y1510606I-150J132D01*
G01Y1512544D01*
G03X463338Y1512676I-200J0D01*
G02Y1515592I1661J1458D01*
G03X463388Y1515724I-150J132D01*
G01Y1516344D01*
G02X463590Y1516546I202J0D01*
G37*
G36*
G01X498236D02*
X501056D01*
G02X501258Y1516344I0J-202D01*
G01Y1515724D01*
G03X501308Y1515592I200J0D01*
G02Y1512676I-1661J-1458D01*
G03X501258Y1512544I150J-132D01*
G01Y1510606D01*
G03X501308Y1510474I200J0D01*
G02Y1507558I-1661J-1458D01*
G03X501258Y1507426I150J-132D01*
G01Y1506806D01*
G02X501056Y1506604I-202J0D01*
G01X498236D01*
G02X498034Y1506806I0J202D01*
G01Y1507426D01*
G03X497984Y1507558I-200J0D01*
G02Y1510474I1661J1458D01*
G03X498034Y1510606I-150J132D01*
G01Y1512544D01*
G03X497984Y1512676I-200J0D01*
G02Y1515592I1661J1458D01*
G03X498034Y1515724I-150J132D01*
G01Y1516344D01*
G02X498236Y1516546I202J0D01*
G37*
G36*
G01X671464D02*
X674284D01*
G02X674486Y1516344I0J-202D01*
G01Y1515724D01*
G03X674536Y1515592I200J0D01*
G02Y1512676I-1661J-1458D01*
G03X674486Y1512544I150J-132D01*
G01Y1510606D01*
G03X674536Y1510474I200J0D01*
G02Y1507558I-1661J-1458D01*
G03X674486Y1507426I150J-132D01*
G01Y1506806D01*
G02X674284Y1506604I-202J0D01*
G01X671464D01*
G02X671262Y1506806I0J202D01*
G01Y1507426D01*
G03X671212Y1507558I-200J0D01*
G02Y1510474I1661J1458D01*
G03X671262Y1510606I-150J132D01*
G01Y1512544D01*
G03X671212Y1512676I-200J0D01*
G02Y1515592I1661J1458D01*
G03X671262Y1515724I-150J132D01*
G01Y1516344D01*
G02X671464Y1516546I202J0D01*
G37*
G36*
G01X1191070D02*
X1193890D01*
G02X1194092Y1516344I0J-202D01*
G01Y1515724D01*
G03X1194142Y1515592I200J0D01*
G02Y1512676I-1661J-1458D01*
G03X1194092Y1512544I150J-132D01*
G01Y1510606D01*
G03X1194142Y1510474I200J0D01*
G02Y1507558I-1661J-1458D01*
G03X1194092Y1507426I150J-132D01*
G01Y1506806D01*
G02X1193890Y1506604I-202J0D01*
G01X1191070D01*
G02X1190868Y1506806I0J202D01*
G01Y1507426D01*
G03X1190818Y1507558I-200J0D01*
G02Y1510474I1661J1458D01*
G03X1190868Y1510606I-150J132D01*
G01Y1512544D01*
G03X1190818Y1512676I-200J0D01*
G02Y1515592I1661J1458D01*
G03X1190868Y1515724I-150J132D01*
G01Y1516344D01*
G02X1191070Y1516546I202J0D01*
G37*
G36*
G01X1312330D02*
X1315150D01*
G02X1315352Y1516344I0J-202D01*
G01Y1515724D01*
G03X1315402Y1515592I200J0D01*
G02Y1512676I-1661J-1458D01*
G03X1315352Y1512544I150J-132D01*
G01Y1510606D01*
G03X1315402Y1510474I200J0D01*
G02Y1507558I-1661J-1458D01*
G03X1315352Y1507426I150J-132D01*
G01Y1506806D01*
G02X1315150Y1506604I-202J0D01*
G01X1312330D01*
G02X1312128Y1506806I0J202D01*
G01Y1507426D01*
G03X1312078Y1507558I-200J0D01*
G02Y1510474I1661J1458D01*
G03X1312128Y1510606I-150J132D01*
G01Y1512544D01*
G03X1312078Y1512676I-200J0D01*
G02Y1515592I1661J1458D01*
G03X1312128Y1515724I-150J132D01*
G01Y1516344D01*
G02X1312330Y1516546I202J0D01*
G37*
G36*
G01X1346976D02*
X1349796D01*
G02X1349998Y1516344I0J-202D01*
G01Y1515724D01*
G03X1350048Y1515592I200J0D01*
G02Y1512676I-1661J-1458D01*
G03X1349998Y1512544I150J-132D01*
G01Y1510606D01*
G03X1350048Y1510474I200J0D01*
G02Y1507558I-1661J-1458D01*
G03X1349998Y1507426I150J-132D01*
G01Y1506806D01*
G02X1349796Y1506604I-202J0D01*
G01X1346976D01*
G02X1346774Y1506806I0J202D01*
G01Y1507426D01*
G03X1346724Y1507558I-200J0D01*
G02Y1510474I1661J1458D01*
G03X1346774Y1510606I-150J132D01*
G01Y1512544D01*
G03X1346724Y1512676I-200J0D01*
G02Y1515592I1661J1458D01*
G03X1346774Y1515724I-150J132D01*
G01Y1516344D01*
G02X1346976Y1516546I202J0D01*
G37*
G36*
G01X1485558D02*
X1488378D01*
G02X1488580Y1516344I0J-202D01*
G01Y1515724D01*
G03X1488630Y1515592I200J0D01*
G02Y1512676I-1661J-1458D01*
G03X1488580Y1512544I150J-132D01*
G01Y1510606D01*
G03X1488630Y1510474I200J0D01*
G02Y1507558I-1661J-1458D01*
G03X1488580Y1507426I150J-132D01*
G01Y1506806D01*
G02X1488378Y1506604I-202J0D01*
G01X1485558D01*
G02X1485356Y1506806I0J202D01*
G01Y1507426D01*
G03X1485306Y1507558I-200J0D01*
G02Y1510474I1661J1458D01*
G03X1485356Y1510606I-150J132D01*
G01Y1512544D01*
G03X1485306Y1512676I-200J0D01*
G02Y1515592I1661J1458D01*
G03X1485356Y1515724I-150J132D01*
G01Y1516344D01*
G02X1485558Y1516546I202J0D01*
G37*
G36*
G01X1520204D02*
X1523024D01*
G02X1523226Y1516344I0J-202D01*
G01Y1515724D01*
G03X1523276Y1515592I200J0D01*
G02Y1512676I-1661J-1458D01*
G03X1523226Y1512544I150J-132D01*
G01Y1510606D01*
G03X1523276Y1510474I200J0D01*
G02Y1507558I-1661J-1458D01*
G03X1523226Y1507426I150J-132D01*
G01Y1506806D01*
G02X1523024Y1506604I-202J0D01*
G01X1520204D01*
G02X1520002Y1506806I0J202D01*
G01Y1507426D01*
G03X1519952Y1507558I-200J0D01*
G02Y1510474I1661J1458D01*
G03X1520002Y1510606I-150J132D01*
G01Y1512544D01*
G03X1519952Y1512676I-200J0D01*
G02Y1515592I1661J1458D01*
G03X1520002Y1515724I-150J132D01*
G01Y1516344D01*
G02X1520204Y1516546I202J0D01*
G37*
G36*
G01X1693432D02*
X1696252D01*
G02X1696454Y1516344I0J-202D01*
G01Y1515724D01*
G03X1696504Y1515592I200J0D01*
G02Y1512676I-1661J-1458D01*
G03X1696454Y1512544I150J-132D01*
G01Y1510606D01*
G03X1696504Y1510474I200J0D01*
G02Y1507558I-1661J-1458D01*
G03X1696454Y1507426I150J-132D01*
G01Y1506806D01*
G02X1696252Y1506604I-202J0D01*
G01X1693432D01*
G02X1693230Y1506806I0J202D01*
G01Y1507426D01*
G03X1693180Y1507558I-200J0D01*
G02Y1510474I1661J1458D01*
G03X1693230Y1510606I-150J132D01*
G01Y1512544D01*
G03X1693180Y1512676I-200J0D01*
G02Y1515592I1661J1458D01*
G03X1693230Y1515724I-150J132D01*
G01Y1516344D01*
G02X1693432Y1516546I202J0D01*
G37*
G36*
G01X151779D02*
X154599D01*
G02X154802Y1516344I1J-202D01*
G01Y1515722D01*
G03X154852Y1515590I200J0D01*
G02Y1512678I-1664J-1456D01*
G03X154802Y1512546I150J-132D01*
G01Y1510604D01*
G03X154852Y1510472I200J0D01*
G02Y1507560I-1664J-1456D01*
G03X154802Y1507428I150J-132D01*
G01Y1506806D01*
G02X154599Y1506604I-203J1D01*
G01X151779D01*
G02X151576Y1506806I-1J202D01*
G01Y1507428D01*
G03X151526Y1507560I-200J0D01*
G02Y1510472I1664J1456D01*
G03X151576Y1510604I-150J132D01*
G01Y1512546D01*
G03X151526Y1512678I-200J0D01*
G02Y1515590I1664J1456D01*
G03X151576Y1515722I-150J132D01*
G01Y1516344D01*
G02X151779Y1516546I203J-1D01*
G37*
G36*
G01X290361D02*
X293181D01*
G02X293384Y1516344I1J-202D01*
G01Y1515722D01*
G03X293434Y1515590I200J0D01*
G02Y1512678I-1664J-1456D01*
G03X293384Y1512546I150J-132D01*
G01Y1510604D01*
G03X293434Y1510472I200J0D01*
G02Y1507560I-1664J-1456D01*
G03X293384Y1507428I150J-132D01*
G01Y1506806D01*
G02X293181Y1506604I-203J1D01*
G01X290361D01*
G02X290158Y1506806I-1J202D01*
G01Y1507428D01*
G03X290108Y1507560I-200J0D01*
G02Y1510472I1664J1456D01*
G03X290158Y1510604I-150J132D01*
G01Y1512546D01*
G03X290108Y1512678I-200J0D01*
G02Y1515590I1664J1456D01*
G03X290158Y1515722I-150J132D01*
G01Y1516344D01*
G02X290361Y1516546I203J-1D01*
G37*
G36*
G01X480913D02*
X483733D01*
G02X483936Y1516344I1J-202D01*
G01Y1515722D01*
G03X483986Y1515590I200J0D01*
G02Y1512678I-1664J-1456D01*
G03X483936Y1512546I150J-132D01*
G01Y1510604D01*
G03X483986Y1510472I200J0D01*
G02Y1507560I-1664J-1456D01*
G03X483936Y1507428I150J-132D01*
G01Y1506806D01*
G02X483733Y1506604I-203J1D01*
G01X480913D01*
G02X480710Y1506806I-1J202D01*
G01Y1507428D01*
G03X480660Y1507560I-200J0D01*
G02Y1510472I1664J1456D01*
G03X480710Y1510604I-150J132D01*
G01Y1512546D01*
G03X480660Y1512678I-200J0D01*
G02Y1515590I1664J1456D01*
G03X480710Y1515722I-150J132D01*
G01Y1516344D01*
G02X480913Y1516546I203J-1D01*
G37*
G36*
G01X515559D02*
X518379D01*
G02X518582Y1516344I1J-202D01*
G01Y1515722D01*
G03X518632Y1515590I200J0D01*
G02Y1512678I-1664J-1456D01*
G03X518582Y1512546I150J-132D01*
G01Y1510604D01*
G03X518632Y1510472I200J0D01*
G02Y1507560I-1664J-1456D01*
G03X518582Y1507428I150J-132D01*
G01Y1506806D01*
G02X518379Y1506604I-203J1D01*
G01X515559D01*
G02X515356Y1506806I-1J202D01*
G01Y1507428D01*
G03X515306Y1507560I-200J0D01*
G02Y1510472I1664J1456D01*
G03X515356Y1510604I-150J132D01*
G01Y1512546D01*
G03X515306Y1512678I-200J0D01*
G02Y1515590I1664J1456D01*
G03X515356Y1515722I-150J132D01*
G01Y1516344D01*
G02X515559Y1516546I203J-1D01*
G37*
G36*
G01X654141D02*
X656961D01*
G02X657164Y1516344I1J-202D01*
G01Y1515722D01*
G03X657214Y1515590I200J0D01*
G02Y1512678I-1664J-1456D01*
G03X657164Y1512546I150J-132D01*
G01Y1510604D01*
G03X657214Y1510472I200J0D01*
G02Y1507560I-1664J-1456D01*
G03X657164Y1507428I150J-132D01*
G01Y1506806D01*
G02X656961Y1506604I-203J1D01*
G01X654141D01*
G02X653938Y1506806I-1J202D01*
G01Y1507428D01*
G03X653888Y1507560I-200J0D01*
G02Y1510472I1664J1456D01*
G03X653938Y1510604I-150J132D01*
G01Y1512546D01*
G03X653888Y1512678I-200J0D01*
G02Y1515590I1664J1456D01*
G03X653938Y1515722I-150J132D01*
G01Y1516344D01*
G02X654141Y1516546I203J-1D01*
G37*
G36*
G01X688787D02*
X691607D01*
G02X691810Y1516344I1J-202D01*
G01Y1515722D01*
G03X691860Y1515590I200J0D01*
G02Y1512678I-1664J-1456D01*
G03X691810Y1512546I150J-132D01*
G01Y1510604D01*
G03X691860Y1510472I200J0D01*
G02Y1507560I-1664J-1456D01*
G03X691810Y1507428I150J-132D01*
G01Y1506806D01*
G02X691607Y1506604I-203J1D01*
G01X688787D01*
G02X688584Y1506806I-1J202D01*
G01Y1507428D01*
G03X688534Y1507560I-200J0D01*
G02Y1510472I1664J1456D01*
G03X688584Y1510604I-150J132D01*
G01Y1512546D01*
G03X688534Y1512678I-200J0D01*
G02Y1515590I1664J1456D01*
G03X688584Y1515722I-150J132D01*
G01Y1516344D01*
G02X688787Y1516546I203J-1D01*
G37*
G36*
G01X1173747D02*
X1176567D01*
G02X1176770Y1516344I1J-202D01*
G01Y1515722D01*
G03X1176820Y1515590I200J0D01*
G02Y1512678I-1664J-1456D01*
G03X1176770Y1512546I150J-132D01*
G01Y1510604D01*
G03X1176820Y1510472I200J0D01*
G02Y1507560I-1664J-1456D01*
G03X1176770Y1507428I150J-132D01*
G01Y1506806D01*
G02X1176567Y1506604I-203J1D01*
G01X1173747D01*
G02X1173544Y1506806I-1J202D01*
G01Y1507428D01*
G03X1173494Y1507560I-200J0D01*
G02Y1510472I1664J1456D01*
G03X1173544Y1510604I-150J132D01*
G01Y1512546D01*
G03X1173494Y1512678I-200J0D01*
G02Y1515590I1664J1456D01*
G03X1173544Y1515722I-150J132D01*
G01Y1516344D01*
G02X1173747Y1516546I203J-1D01*
G37*
G36*
G01X1329653D02*
X1332473D01*
G02X1332676Y1516344I1J-202D01*
G01Y1515722D01*
G03X1332726Y1515590I200J0D01*
G02Y1512678I-1664J-1456D01*
G03X1332676Y1512546I150J-132D01*
G01Y1510604D01*
G03X1332726Y1510472I200J0D01*
G02Y1507560I-1664J-1456D01*
G03X1332676Y1507428I150J-132D01*
G01Y1506806D01*
G02X1332473Y1506604I-203J1D01*
G01X1329653D01*
G02X1329450Y1506806I-1J202D01*
G01Y1507428D01*
G03X1329400Y1507560I-200J0D01*
G02Y1510472I1664J1456D01*
G03X1329450Y1510604I-150J132D01*
G01Y1512546D01*
G03X1329400Y1512678I-200J0D01*
G02Y1515590I1664J1456D01*
G03X1329450Y1515722I-150J132D01*
G01Y1516344D01*
G02X1329653Y1516546I203J-1D01*
G37*
G36*
G01X1364299D02*
X1367119D01*
G02X1367322Y1516344I1J-202D01*
G01Y1515722D01*
G03X1367372Y1515590I200J0D01*
G02Y1512678I-1664J-1456D01*
G03X1367322Y1512546I150J-132D01*
G01Y1510604D01*
G03X1367372Y1510472I200J0D01*
G02Y1507560I-1664J-1456D01*
G03X1367322Y1507428I150J-132D01*
G01Y1506806D01*
G02X1367119Y1506604I-203J1D01*
G01X1364299D01*
G02X1364096Y1506806I-1J202D01*
G01Y1507428D01*
G03X1364046Y1507560I-200J0D01*
G02Y1510472I1664J1456D01*
G03X1364096Y1510604I-150J132D01*
G01Y1512546D01*
G03X1364046Y1512678I-200J0D01*
G02Y1515590I1664J1456D01*
G03X1364096Y1515722I-150J132D01*
G01Y1516344D01*
G02X1364299Y1516546I203J-1D01*
G37*
G36*
G01X1502881D02*
X1505701D01*
G02X1505904Y1516344I1J-202D01*
G01Y1515722D01*
G03X1505954Y1515590I200J0D01*
G02Y1512678I-1664J-1456D01*
G03X1505904Y1512546I150J-132D01*
G01Y1510604D01*
G03X1505954Y1510472I200J0D01*
G02Y1507560I-1664J-1456D01*
G03X1505904Y1507428I150J-132D01*
G01Y1506806D01*
G02X1505701Y1506604I-203J1D01*
G01X1502881D01*
G02X1502678Y1506806I-1J202D01*
G01Y1507428D01*
G03X1502628Y1507560I-200J0D01*
G02Y1510472I1664J1456D01*
G03X1502678Y1510604I-150J132D01*
G01Y1512546D01*
G03X1502628Y1512678I-200J0D01*
G02Y1515590I1664J1456D01*
G03X1502678Y1515722I-150J132D01*
G01Y1516344D01*
G02X1502881Y1516546I203J-1D01*
G37*
G36*
G01X1537527D02*
X1540347D01*
G02X1540550Y1516344I1J-202D01*
G01Y1515722D01*
G03X1540600Y1515590I200J0D01*
G02Y1512678I-1664J-1456D01*
G03X1540550Y1512546I150J-132D01*
G01Y1510604D01*
G03X1540600Y1510472I200J0D01*
G02Y1507560I-1664J-1456D01*
G03X1540550Y1507428I150J-132D01*
G01Y1506806D01*
G02X1540347Y1506604I-203J1D01*
G01X1537527D01*
G02X1537324Y1506806I-1J202D01*
G01Y1507428D01*
G03X1537274Y1507560I-200J0D01*
G02Y1510472I1664J1456D01*
G03X1537324Y1510604I-150J132D01*
G01Y1512546D01*
G03X1537274Y1512678I-200J0D01*
G02Y1515590I1664J1456D01*
G03X1537324Y1515722I-150J132D01*
G01Y1516344D01*
G02X1537527Y1516546I203J-1D01*
G37*
G36*
G01X1710755D02*
X1713575D01*
G02X1713778Y1516344I1J-202D01*
G01Y1515722D01*
G03X1713828Y1515590I200J0D01*
G02Y1512678I-1664J-1456D01*
G03X1713778Y1512546I150J-132D01*
G01Y1510604D01*
G03X1713828Y1510472I200J0D01*
G02Y1507560I-1664J-1456D01*
G03X1713778Y1507428I150J-132D01*
G01Y1506806D01*
G02X1713575Y1506604I-203J1D01*
G01X1710755D01*
G02X1710552Y1506806I-1J202D01*
G01Y1507428D01*
G03X1710502Y1507560I-200J0D01*
G02Y1510472I1664J1456D01*
G03X1710552Y1510604I-150J132D01*
G01Y1512546D01*
G03X1710502Y1512678I-200J0D01*
G02Y1515590I1664J1456D01*
G03X1710552Y1515722I-150J132D01*
G01Y1516344D01*
G02X1710755Y1516546I203J-1D01*
G37*
G36*
G01X108472Y1568516D02*
X111292D01*
G02X111494Y1568313I-1J-203D01*
G01Y1567693D01*
G03X111544Y1567561I200J0D01*
G02Y1564645I-1661J-1458D01*
G03X111494Y1564513I150J-132D01*
G01Y1562575D01*
G03X111544Y1562443I200J0D01*
G02Y1559527I-1661J-1458D01*
G03X111494Y1559395I150J-132D01*
G01Y1558775D01*
G02X111292Y1558572I-202J-1D01*
G01X108472D01*
G02X108270Y1558775I1J203D01*
G01Y1559395D01*
G03X108220Y1559527I-200J0D01*
G02Y1562443I1661J1458D01*
G03X108270Y1562575I-150J132D01*
G01Y1564513D01*
G03X108220Y1564645I-200J0D01*
G02Y1567561I1661J1458D01*
G03X108270Y1567693I-150J132D01*
G01Y1568313D01*
G02X108472Y1568516I202J1D01*
G37*
G36*
G01X125795D02*
X128615D01*
G02X128818Y1568313I0J-203D01*
G01Y1567691D01*
G03X128868Y1567559I200J0D01*
G02Y1564647I-1664J-1456D01*
G03X128818Y1564515I150J-132D01*
G01Y1562573D01*
G03X128868Y1562441I200J0D01*
G02Y1559529I-1664J-1456D01*
G03X128818Y1559397I150J-132D01*
G01Y1558775D01*
G02X128615Y1558572I-203J0D01*
G01X125795D01*
G02X125592Y1558775I0J203D01*
G01Y1559397D01*
G03X125542Y1559529I-200J0D01*
G02Y1562441I1664J1456D01*
G03X125592Y1562573I-150J132D01*
G01Y1564515D01*
G03X125542Y1564647I-200J0D01*
G02Y1567559I1664J1456D01*
G03X125592Y1567691I-150J132D01*
G01Y1568313D01*
G02X125795Y1568516I203J0D01*
G37*
G36*
G01X143118D02*
X145938D01*
G02X146140Y1568313I-1J-203D01*
G01Y1567693D01*
G03X146190Y1567561I200J0D01*
G02Y1564645I-1661J-1458D01*
G03X146140Y1564513I150J-132D01*
G01Y1562575D01*
G03X146190Y1562443I200J0D01*
G02Y1559527I-1661J-1458D01*
G03X146140Y1559395I150J-132D01*
G01Y1558775D01*
G02X145938Y1558572I-202J-1D01*
G01X143118D01*
G02X142916Y1558775I1J203D01*
G01Y1559395D01*
G03X142866Y1559527I-200J0D01*
G02Y1562443I1661J1458D01*
G03X142916Y1562575I-150J132D01*
G01Y1564513D01*
G03X142866Y1564645I-200J0D01*
G02Y1567561I1661J1458D01*
G03X142916Y1567693I-150J132D01*
G01Y1568313D01*
G02X143118Y1568516I202J1D01*
G37*
G36*
G01X160440D02*
X163260D01*
G02X163462Y1568313I-1J-203D01*
G01Y1567693D01*
G03X163512Y1567561I200J0D01*
G02Y1564645I-1661J-1458D01*
G03X163462Y1564513I150J-132D01*
G01Y1562575D01*
G03X163512Y1562443I200J0D01*
G02Y1559527I-1661J-1458D01*
G03X163462Y1559395I150J-132D01*
G01Y1558775D01*
G02X163260Y1558572I-202J-1D01*
G01X160440D01*
G02X160238Y1558775I1J203D01*
G01Y1559395D01*
G03X160188Y1559527I-200J0D01*
G02Y1562443I1661J1458D01*
G03X160238Y1562575I-150J132D01*
G01Y1564513D01*
G03X160188Y1564645I-200J0D01*
G02Y1567561I1661J1458D01*
G03X160238Y1567693I-150J132D01*
G01Y1568313D01*
G02X160440Y1568516I202J1D01*
G37*
G36*
G01X281700D02*
X284520D01*
G02X284722Y1568313I-1J-203D01*
G01Y1567693D01*
G03X284772Y1567561I200J0D01*
G02Y1564645I-1661J-1458D01*
G03X284722Y1564513I150J-132D01*
G01Y1562575D01*
G03X284772Y1562443I200J0D01*
G02Y1559527I-1661J-1458D01*
G03X284722Y1559395I150J-132D01*
G01Y1558775D01*
G02X284520Y1558572I-202J-1D01*
G01X281700D01*
G02X281498Y1558775I1J203D01*
G01Y1559395D01*
G03X281448Y1559527I-200J0D01*
G02Y1562443I1661J1458D01*
G03X281498Y1562575I-150J132D01*
G01Y1564513D01*
G03X281448Y1564645I-200J0D01*
G02Y1567561I1661J1458D01*
G03X281498Y1567693I-150J132D01*
G01Y1568313D01*
G02X281700Y1568516I202J1D01*
G37*
G36*
G01X299023D02*
X301843D01*
G02X302046Y1568313I0J-203D01*
G01Y1567691D01*
G03X302096Y1567559I200J0D01*
G02Y1564647I-1664J-1456D01*
G03X302046Y1564515I150J-132D01*
G01Y1562573D01*
G03X302096Y1562441I200J0D01*
G02Y1559529I-1664J-1456D01*
G03X302046Y1559397I150J-132D01*
G01Y1558775D01*
G02X301843Y1558572I-203J0D01*
G01X299023D01*
G02X298820Y1558775I0J203D01*
G01Y1559397D01*
G03X298770Y1559529I-200J0D01*
G02Y1562441I1664J1456D01*
G03X298820Y1562573I-150J132D01*
G01Y1564515D01*
G03X298770Y1564647I-200J0D01*
G02Y1567559I1664J1456D01*
G03X298820Y1567691I-150J132D01*
G01Y1568313D01*
G02X299023Y1568516I203J0D01*
G37*
G36*
G01X316346D02*
X319166D01*
G02X319368Y1568313I-1J-203D01*
G01Y1567693D01*
G03X319418Y1567561I200J0D01*
G02Y1564645I-1661J-1458D01*
G03X319368Y1564513I150J-132D01*
G01Y1562575D01*
G03X319418Y1562443I200J0D01*
G02Y1559527I-1661J-1458D01*
G03X319368Y1559395I150J-132D01*
G01Y1558775D01*
G02X319166Y1558572I-202J-1D01*
G01X316346D01*
G02X316144Y1558775I1J203D01*
G01Y1559395D01*
G03X316094Y1559527I-200J0D01*
G02Y1562443I1661J1458D01*
G03X316144Y1562575I-150J132D01*
G01Y1564513D01*
G03X316094Y1564645I-200J0D01*
G02Y1567561I1661J1458D01*
G03X316144Y1567693I-150J132D01*
G01Y1568313D01*
G02X316346Y1568516I202J1D01*
G37*
G36*
G01X333668D02*
X336488D01*
G02X336690Y1568313I-1J-203D01*
G01Y1567693D01*
G03X336740Y1567561I200J0D01*
G02Y1564645I-1661J-1458D01*
G03X336690Y1564513I150J-132D01*
G01Y1562575D01*
G03X336740Y1562443I200J0D01*
G02Y1559527I-1661J-1458D01*
G03X336690Y1559395I150J-132D01*
G01Y1558775D01*
G02X336488Y1558572I-202J-1D01*
G01X333668D01*
G02X333466Y1558775I1J203D01*
G01Y1559395D01*
G03X333416Y1559527I-200J0D01*
G02Y1562443I1661J1458D01*
G03X333466Y1562575I-150J132D01*
G01Y1564513D01*
G03X333416Y1564645I-200J0D01*
G02Y1567561I1661J1458D01*
G03X333466Y1567693I-150J132D01*
G01Y1568313D01*
G02X333668Y1568516I202J1D01*
G37*
G36*
G01X628157D02*
X630977D01*
G02X631180Y1568313I0J-203D01*
G01Y1567691D01*
G03X631230Y1567559I200J0D01*
G02Y1564647I-1664J-1456D01*
G03X631180Y1564515I150J-132D01*
G01Y1562573D01*
G03X631230Y1562441I200J0D01*
G02Y1559529I-1664J-1456D01*
G03X631180Y1559397I150J-132D01*
G01Y1558775D01*
G02X630977Y1558572I-203J0D01*
G01X628157D01*
G02X627954Y1558775I0J203D01*
G01Y1559397D01*
G03X627904Y1559529I-200J0D01*
G02Y1562441I1664J1456D01*
G03X627954Y1562573I-150J132D01*
G01Y1564515D01*
G03X627904Y1564647I-200J0D01*
G02Y1567559I1664J1456D01*
G03X627954Y1567691I-150J132D01*
G01Y1568313D01*
G02X628157Y1568516I203J0D01*
G37*
G36*
G01X645480D02*
X648300D01*
G02X648502Y1568313I-1J-203D01*
G01Y1567693D01*
G03X648552Y1567561I200J0D01*
G02Y1564645I-1661J-1458D01*
G03X648502Y1564513I150J-132D01*
G01Y1562575D01*
G03X648552Y1562443I200J0D01*
G02Y1559527I-1661J-1458D01*
G03X648502Y1559395I150J-132D01*
G01Y1558775D01*
G02X648300Y1558572I-202J-1D01*
G01X645480D01*
G02X645278Y1558775I1J203D01*
G01Y1559395D01*
G03X645228Y1559527I-200J0D01*
G02Y1562443I1661J1458D01*
G03X645278Y1562575I-150J132D01*
G01Y1564513D01*
G03X645228Y1564645I-200J0D01*
G02Y1567561I1661J1458D01*
G03X645278Y1567693I-150J132D01*
G01Y1568313D01*
G02X645480Y1568516I202J1D01*
G37*
G36*
G01X662803D02*
X665623D01*
G02X665826Y1568313I0J-203D01*
G01Y1567691D01*
G03X665876Y1567559I200J0D01*
G02Y1564647I-1664J-1456D01*
G03X665826Y1564515I150J-132D01*
G01Y1562573D01*
G03X665876Y1562441I200J0D01*
G02Y1559529I-1664J-1456D01*
G03X665826Y1559397I150J-132D01*
G01Y1558775D01*
G02X665623Y1558572I-203J0D01*
G01X662803D01*
G02X662600Y1558775I0J203D01*
G01Y1559397D01*
G03X662550Y1559529I-200J0D01*
G02Y1562441I1664J1456D01*
G03X662600Y1562573I-150J132D01*
G01Y1564515D01*
G03X662550Y1564647I-200J0D01*
G02Y1567559I1664J1456D01*
G03X662600Y1567691I-150J132D01*
G01Y1568313D01*
G02X662803Y1568516I203J0D01*
G37*
G36*
G01X680125D02*
X682945D01*
G02X683148Y1568313I0J-203D01*
G01Y1567691D01*
G03X683198Y1567559I200J0D01*
G02Y1564647I-1664J-1456D01*
G03X683148Y1564515I150J-132D01*
G01Y1562573D01*
G03X683198Y1562441I200J0D01*
G02Y1559529I-1664J-1456D01*
G03X683148Y1559397I150J-132D01*
G01Y1558775D01*
G02X682945Y1558572I-203J0D01*
G01X680125D01*
G02X679922Y1558775I0J203D01*
G01Y1559397D01*
G03X679872Y1559529I-200J0D01*
G02Y1562441I1664J1456D01*
G03X679922Y1562573I-150J132D01*
G01Y1564515D01*
G03X679872Y1564647I-200J0D01*
G02Y1567559I1664J1456D01*
G03X679922Y1567691I-150J132D01*
G01Y1568313D01*
G02X680125Y1568516I203J0D01*
G37*
G36*
G01X1130440D02*
X1133260D01*
G02X1133462Y1568313I-1J-203D01*
G01Y1567693D01*
G03X1133512Y1567561I200J0D01*
G02Y1564645I-1661J-1458D01*
G03X1133462Y1564513I150J-132D01*
G01Y1562575D01*
G03X1133512Y1562443I200J0D01*
G02Y1559527I-1661J-1458D01*
G03X1133462Y1559395I150J-132D01*
G01Y1558775D01*
G02X1133260Y1558572I-202J-1D01*
G01X1130440D01*
G02X1130238Y1558775I1J203D01*
G01Y1559395D01*
G03X1130188Y1559527I-200J0D01*
G02Y1562443I1661J1458D01*
G03X1130238Y1562575I-150J132D01*
G01Y1564513D01*
G03X1130188Y1564645I-200J0D01*
G02Y1567561I1661J1458D01*
G03X1130238Y1567693I-150J132D01*
G01Y1568313D01*
G02X1130440Y1568516I202J1D01*
G37*
G36*
G01X1147763D02*
X1150583D01*
G02X1150786Y1568313I0J-203D01*
G01Y1567691D01*
G03X1150836Y1567559I200J0D01*
G02Y1564647I-1664J-1456D01*
G03X1150786Y1564515I150J-132D01*
G01Y1562573D01*
G03X1150836Y1562441I200J0D01*
G02Y1559529I-1664J-1456D01*
G03X1150786Y1559397I150J-132D01*
G01Y1558775D01*
G02X1150583Y1558572I-203J0D01*
G01X1147763D01*
G02X1147560Y1558775I0J203D01*
G01Y1559397D01*
G03X1147510Y1559529I-200J0D01*
G02Y1562441I1664J1456D01*
G03X1147560Y1562573I-150J132D01*
G01Y1564515D01*
G03X1147510Y1564647I-200J0D01*
G02Y1567559I1664J1456D01*
G03X1147560Y1567691I-150J132D01*
G01Y1568313D01*
G02X1147763Y1568516I203J0D01*
G37*
G36*
G01X1165086D02*
X1167906D01*
G02X1168108Y1568313I-1J-203D01*
G01Y1567693D01*
G03X1168158Y1567561I200J0D01*
G02Y1564645I-1661J-1458D01*
G03X1168108Y1564513I150J-132D01*
G01Y1562575D01*
G03X1168158Y1562443I200J0D01*
G02Y1559527I-1661J-1458D01*
G03X1168108Y1559395I150J-132D01*
G01Y1558775D01*
G02X1167906Y1558572I-202J-1D01*
G01X1165086D01*
G02X1164884Y1558775I1J203D01*
G01Y1559395D01*
G03X1164834Y1559527I-200J0D01*
G02Y1562443I1661J1458D01*
G03X1164884Y1562575I-150J132D01*
G01Y1564513D01*
G03X1164834Y1564645I-200J0D01*
G02Y1567561I1661J1458D01*
G03X1164884Y1567693I-150J132D01*
G01Y1568313D01*
G02X1165086Y1568516I202J1D01*
G37*
G36*
G01X1182408D02*
X1185228D01*
G02X1185430Y1568313I-1J-203D01*
G01Y1567693D01*
G03X1185480Y1567561I200J0D01*
G02Y1564645I-1661J-1458D01*
G03X1185430Y1564513I150J-132D01*
G01Y1562575D01*
G03X1185480Y1562443I200J0D01*
G02Y1559527I-1661J-1458D01*
G03X1185430Y1559395I150J-132D01*
G01Y1558775D01*
G02X1185228Y1558572I-202J-1D01*
G01X1182408D01*
G02X1182206Y1558775I1J203D01*
G01Y1559395D01*
G03X1182156Y1559527I-200J0D01*
G02Y1562443I1661J1458D01*
G03X1182206Y1562575I-150J132D01*
G01Y1564513D01*
G03X1182156Y1564645I-200J0D01*
G02Y1567561I1661J1458D01*
G03X1182206Y1567693I-150J132D01*
G01Y1568313D01*
G02X1182408Y1568516I202J1D01*
G37*
G36*
G01X1303669D02*
X1306489D01*
G02X1306692Y1568313I0J-203D01*
G01Y1567691D01*
G03X1306742Y1567559I200J0D01*
G02Y1564647I-1664J-1456D01*
G03X1306692Y1564515I150J-132D01*
G01Y1562573D01*
G03X1306742Y1562441I200J0D01*
G02Y1559529I-1664J-1456D01*
G03X1306692Y1559397I150J-132D01*
G01Y1558775D01*
G02X1306489Y1558572I-203J0D01*
G01X1303669D01*
G02X1303466Y1558775I0J203D01*
G01Y1559397D01*
G03X1303416Y1559529I-200J0D01*
G02Y1562441I1664J1456D01*
G03X1303466Y1562573I-150J132D01*
G01Y1564515D01*
G03X1303416Y1564647I-200J0D01*
G02Y1567559I1664J1456D01*
G03X1303466Y1567691I-150J132D01*
G01Y1568313D01*
G02X1303669Y1568516I203J0D01*
G37*
G36*
G01X1320992D02*
X1323812D01*
G02X1324014Y1568313I-1J-203D01*
G01Y1567693D01*
G03X1324064Y1567561I200J0D01*
G02Y1564645I-1661J-1458D01*
G03X1324014Y1564513I150J-132D01*
G01Y1562575D01*
G03X1324064Y1562443I200J0D01*
G02Y1559527I-1661J-1458D01*
G03X1324014Y1559395I150J-132D01*
G01Y1558775D01*
G02X1323812Y1558572I-202J-1D01*
G01X1320992D01*
G02X1320790Y1558775I1J203D01*
G01Y1559395D01*
G03X1320740Y1559527I-200J0D01*
G02Y1562443I1661J1458D01*
G03X1320790Y1562575I-150J132D01*
G01Y1564513D01*
G03X1320740Y1564645I-200J0D01*
G02Y1567561I1661J1458D01*
G03X1320790Y1567693I-150J132D01*
G01Y1568313D01*
G02X1320992Y1568516I202J1D01*
G37*
G36*
G01X1338315D02*
X1341135D01*
G02X1341338Y1568313I0J-203D01*
G01Y1567691D01*
G03X1341388Y1567559I200J0D01*
G02Y1564647I-1664J-1456D01*
G03X1341338Y1564515I150J-132D01*
G01Y1562573D01*
G03X1341388Y1562441I200J0D01*
G02Y1559529I-1664J-1456D01*
G03X1341338Y1559397I150J-132D01*
G01Y1558775D01*
G02X1341135Y1558572I-203J0D01*
G01X1338315D01*
G02X1338112Y1558775I0J203D01*
G01Y1559397D01*
G03X1338062Y1559529I-200J0D01*
G02Y1562441I1664J1456D01*
G03X1338112Y1562573I-150J132D01*
G01Y1564515D01*
G03X1338062Y1564647I-200J0D01*
G02Y1567559I1664J1456D01*
G03X1338112Y1567691I-150J132D01*
G01Y1568313D01*
G02X1338315Y1568516I203J0D01*
G37*
G36*
G01X1355637D02*
X1358457D01*
G02X1358660Y1568313I0J-203D01*
G01Y1567691D01*
G03X1358710Y1567559I200J0D01*
G02Y1564647I-1664J-1456D01*
G03X1358660Y1564515I150J-132D01*
G01Y1562573D01*
G03X1358710Y1562441I200J0D01*
G02Y1559529I-1664J-1456D01*
G03X1358660Y1559397I150J-132D01*
G01Y1558775D01*
G02X1358457Y1558572I-203J0D01*
G01X1355637D01*
G02X1355434Y1558775I0J203D01*
G01Y1559397D01*
G03X1355384Y1559529I-200J0D01*
G02Y1562441I1664J1456D01*
G03X1355434Y1562573I-150J132D01*
G01Y1564515D01*
G03X1355384Y1564647I-200J0D01*
G02Y1567559I1664J1456D01*
G03X1355434Y1567691I-150J132D01*
G01Y1568313D01*
G02X1355637Y1568516I203J0D01*
G37*
G36*
G01X1476897D02*
X1479717D01*
G02X1479920Y1568313I0J-203D01*
G01Y1567691D01*
G03X1479970Y1567559I200J0D01*
G02Y1564647I-1664J-1456D01*
G03X1479920Y1564515I150J-132D01*
G01Y1562573D01*
G03X1479970Y1562441I200J0D01*
G02Y1559529I-1664J-1456D01*
G03X1479920Y1559397I150J-132D01*
G01Y1558775D01*
G02X1479717Y1558572I-203J0D01*
G01X1476897D01*
G02X1476694Y1558775I0J203D01*
G01Y1559397D01*
G03X1476644Y1559529I-200J0D01*
G02Y1562441I1664J1456D01*
G03X1476694Y1562573I-150J132D01*
G01Y1564515D01*
G03X1476644Y1564647I-200J0D01*
G02Y1567559I1664J1456D01*
G03X1476694Y1567691I-150J132D01*
G01Y1568313D01*
G02X1476897Y1568516I203J0D01*
G37*
G36*
G01X1650125D02*
X1652945D01*
G02X1653148Y1568313I0J-203D01*
G01Y1567691D01*
G03X1653198Y1567559I200J0D01*
G02Y1564647I-1664J-1456D01*
G03X1653148Y1564515I150J-132D01*
G01Y1562573D01*
G03X1653198Y1562441I200J0D01*
G02Y1559529I-1664J-1456D01*
G03X1653148Y1559397I150J-132D01*
G01Y1558775D01*
G02X1652945Y1558572I-203J0D01*
G01X1650125D01*
G02X1649922Y1558775I0J203D01*
G01Y1559397D01*
G03X1649872Y1559529I-200J0D01*
G02Y1562441I1664J1456D01*
G03X1649922Y1562573I-150J132D01*
G01Y1564515D01*
G03X1649872Y1564647I-200J0D01*
G02Y1567559I1664J1456D01*
G03X1649922Y1567691I-150J132D01*
G01Y1568313D01*
G02X1650125Y1568516I203J0D01*
G37*
G36*
G01X1667448D02*
X1670268D01*
G02X1670470Y1568313I-1J-203D01*
G01Y1567693D01*
G03X1670520Y1567561I200J0D01*
G02Y1564645I-1661J-1458D01*
G03X1670470Y1564513I150J-132D01*
G01Y1562575D01*
G03X1670520Y1562443I200J0D01*
G02Y1559527I-1661J-1458D01*
G03X1670470Y1559395I150J-132D01*
G01Y1558775D01*
G02X1670268Y1558572I-202J-1D01*
G01X1667448D01*
G02X1667246Y1558775I1J203D01*
G01Y1559395D01*
G03X1667196Y1559527I-200J0D01*
G02Y1562443I1661J1458D01*
G03X1667246Y1562575I-150J132D01*
G01Y1564513D01*
G03X1667196Y1564645I-200J0D01*
G02Y1567561I1661J1458D01*
G03X1667246Y1567693I-150J132D01*
G01Y1568313D01*
G02X1667448Y1568516I202J1D01*
G37*
G36*
G01X1684771D02*
X1687591D01*
G02X1687794Y1568313I0J-203D01*
G01Y1567691D01*
G03X1687844Y1567559I200J0D01*
G02Y1564647I-1664J-1456D01*
G03X1687794Y1564515I150J-132D01*
G01Y1562573D01*
G03X1687844Y1562441I200J0D01*
G02Y1559529I-1664J-1456D01*
G03X1687794Y1559397I150J-132D01*
G01Y1558775D01*
G02X1687591Y1558572I-203J0D01*
G01X1684771D01*
G02X1684568Y1558775I0J203D01*
G01Y1559397D01*
G03X1684518Y1559529I-200J0D01*
G02Y1562441I1664J1456D01*
G03X1684568Y1562573I-150J132D01*
G01Y1564515D01*
G03X1684518Y1564647I-200J0D01*
G02Y1567559I1664J1456D01*
G03X1684568Y1567691I-150J132D01*
G01Y1568313D01*
G02X1684771Y1568516I203J0D01*
G37*
G36*
G01X1702093D02*
X1704913D01*
G02X1705116Y1568313I0J-203D01*
G01Y1567691D01*
G03X1705166Y1567559I200J0D01*
G02Y1564647I-1664J-1456D01*
G03X1705116Y1564515I150J-132D01*
G01Y1562573D01*
G03X1705166Y1562441I200J0D01*
G02Y1559529I-1664J-1456D01*
G03X1705116Y1559397I150J-132D01*
G01Y1558775D01*
G02X1704913Y1558572I-203J0D01*
G01X1702093D01*
G02X1701890Y1558775I0J203D01*
G01Y1559397D01*
G03X1701840Y1559529I-200J0D01*
G02Y1562441I1664J1456D01*
G03X1701890Y1562573I-150J132D01*
G01Y1564515D01*
G03X1701840Y1564647I-200J0D01*
G02Y1567559I1664J1456D01*
G03X1701890Y1567691I-150J132D01*
G01Y1568313D01*
G02X1702093Y1568516I203J0D01*
G37*
G36*
G01X134456Y1572846D02*
X137276D01*
G02X137478Y1572644I0J-202D01*
G01Y1572024D01*
G03X137528Y1571892I200J0D01*
G02Y1568976I-1661J-1458D01*
G03X137478Y1568844I150J-132D01*
G01Y1566905D01*
G03X137528Y1566773I200J0D01*
G02Y1563857I-1661J-1458D01*
G03X137478Y1563725I150J-132D01*
G01Y1563106D01*
G02X137276Y1562904I-202J0D01*
G01X134456D01*
G02X134254Y1563106I0J202D01*
G01Y1563725D01*
G03X134204Y1563857I-200J0D01*
G02Y1566773I1661J1458D01*
G03X134254Y1566905I-150J132D01*
G01Y1568844D01*
G03X134204Y1568976I-200J0D01*
G02Y1571892I1661J1458D01*
G03X134254Y1572024I-150J132D01*
G01Y1572644D01*
G02X134456Y1572846I202J0D01*
G37*
G36*
G01X169102D02*
X171922D01*
G02X172124Y1572644I0J-202D01*
G01Y1572024D01*
G03X172174Y1571892I200J0D01*
G02Y1568976I-1661J-1458D01*
G03X172124Y1568844I150J-132D01*
G01Y1566905D01*
G03X172174Y1566773I200J0D01*
G02Y1563857I-1661J-1458D01*
G03X172124Y1563725I150J-132D01*
G01Y1563106D01*
G02X171922Y1562904I-202J0D01*
G01X169102D01*
G02X168900Y1563106I0J202D01*
G01Y1563725D01*
G03X168850Y1563857I-200J0D01*
G02Y1566773I1661J1458D01*
G03X168900Y1566905I-150J132D01*
G01Y1568844D01*
G03X168850Y1568976I-200J0D01*
G02Y1571892I1661J1458D01*
G03X168900Y1572024I-150J132D01*
G01Y1572644D01*
G02X169102Y1572846I202J0D01*
G37*
G36*
G01X307684D02*
X310504D01*
G02X310706Y1572644I0J-202D01*
G01Y1572024D01*
G03X310756Y1571892I200J0D01*
G02Y1568976I-1661J-1458D01*
G03X310706Y1568844I150J-132D01*
G01Y1566905D01*
G03X310756Y1566773I200J0D01*
G02Y1563857I-1661J-1458D01*
G03X310706Y1563725I150J-132D01*
G01Y1563106D01*
G02X310504Y1562904I-202J0D01*
G01X307684D01*
G02X307482Y1563106I0J202D01*
G01Y1563725D01*
G03X307432Y1563857I-200J0D01*
G02Y1566773I1661J1458D01*
G03X307482Y1566905I-150J132D01*
G01Y1568844D01*
G03X307432Y1568976I-200J0D01*
G02Y1571892I1661J1458D01*
G03X307482Y1572024I-150J132D01*
G01Y1572644D01*
G02X307684Y1572846I202J0D01*
G37*
G36*
G01X342330D02*
X345150D01*
G02X345352Y1572644I0J-202D01*
G01Y1572024D01*
G03X345402Y1571892I200J0D01*
G02Y1568976I-1661J-1458D01*
G03X345352Y1568844I150J-132D01*
G01Y1566905D01*
G03X345402Y1566773I200J0D01*
G02Y1563857I-1661J-1458D01*
G03X345352Y1563725I150J-132D01*
G01Y1563106D01*
G02X345150Y1562904I-202J0D01*
G01X342330D01*
G02X342128Y1563106I0J202D01*
G01Y1563725D01*
G03X342078Y1563857I-200J0D01*
G02Y1566773I1661J1458D01*
G03X342128Y1566905I-150J132D01*
G01Y1568844D01*
G03X342078Y1568976I-200J0D01*
G02Y1571892I1661J1458D01*
G03X342128Y1572024I-150J132D01*
G01Y1572644D01*
G02X342330Y1572846I202J0D01*
G37*
G36*
G01X636818D02*
X639638D01*
G02X639840Y1572644I0J-202D01*
G01Y1572024D01*
G03X639890Y1571892I200J0D01*
G02Y1568976I-1661J-1458D01*
G03X639840Y1568844I150J-132D01*
G01Y1566905D01*
G03X639890Y1566773I200J0D01*
G02Y1563857I-1661J-1458D01*
G03X639840Y1563725I150J-132D01*
G01Y1563106D01*
G02X639638Y1562904I-202J0D01*
G01X636818D01*
G02X636616Y1563106I0J202D01*
G01Y1563725D01*
G03X636566Y1563857I-200J0D01*
G02Y1566773I1661J1458D01*
G03X636616Y1566905I-150J132D01*
G01Y1568844D01*
G03X636566Y1568976I-200J0D01*
G02Y1571892I1661J1458D01*
G03X636616Y1572024I-150J132D01*
G01Y1572644D01*
G02X636818Y1572846I202J0D01*
G37*
G36*
G01X671464D02*
X674284D01*
G02X674486Y1572644I0J-202D01*
G01Y1572024D01*
G03X674536Y1571892I200J0D01*
G02Y1568976I-1661J-1458D01*
G03X674486Y1568844I150J-132D01*
G01Y1566905D01*
G03X674536Y1566773I200J0D01*
G02Y1563857I-1661J-1458D01*
G03X674486Y1563725I150J-132D01*
G01Y1563106D01*
G02X674284Y1562904I-202J0D01*
G01X671464D01*
G02X671262Y1563106I0J202D01*
G01Y1563725D01*
G03X671212Y1563857I-200J0D01*
G02Y1566773I1661J1458D01*
G03X671262Y1566905I-150J132D01*
G01Y1568844D01*
G03X671212Y1568976I-200J0D01*
G02Y1571892I1661J1458D01*
G03X671262Y1572024I-150J132D01*
G01Y1572644D01*
G02X671464Y1572846I202J0D01*
G37*
G36*
G01X1156424D02*
X1159244D01*
G02X1159446Y1572644I0J-202D01*
G01Y1572024D01*
G03X1159496Y1571892I200J0D01*
G02Y1568976I-1661J-1458D01*
G03X1159446Y1568844I150J-132D01*
G01Y1566905D01*
G03X1159496Y1566773I200J0D01*
G02Y1563857I-1661J-1458D01*
G03X1159446Y1563725I150J-132D01*
G01Y1563106D01*
G02X1159244Y1562904I-202J0D01*
G01X1156424D01*
G02X1156222Y1563106I0J202D01*
G01Y1563725D01*
G03X1156172Y1563857I-200J0D01*
G02Y1566773I1661J1458D01*
G03X1156222Y1566905I-150J132D01*
G01Y1568844D01*
G03X1156172Y1568976I-200J0D01*
G02Y1571892I1661J1458D01*
G03X1156222Y1572024I-150J132D01*
G01Y1572644D01*
G02X1156424Y1572846I202J0D01*
G37*
G36*
G01X1191070D02*
X1193890D01*
G02X1194092Y1572644I0J-202D01*
G01Y1572024D01*
G03X1194142Y1571892I200J0D01*
G02Y1568976I-1661J-1458D01*
G03X1194092Y1568844I150J-132D01*
G01Y1566905D01*
G03X1194142Y1566773I200J0D01*
G02Y1563857I-1661J-1458D01*
G03X1194092Y1563725I150J-132D01*
G01Y1563106D01*
G02X1193890Y1562904I-202J0D01*
G01X1191070D01*
G02X1190868Y1563106I0J202D01*
G01Y1563725D01*
G03X1190818Y1563857I-200J0D01*
G02Y1566773I1661J1458D01*
G03X1190868Y1566905I-150J132D01*
G01Y1568844D01*
G03X1190818Y1568976I-200J0D01*
G02Y1571892I1661J1458D01*
G03X1190868Y1572024I-150J132D01*
G01Y1572644D01*
G02X1191070Y1572846I202J0D01*
G37*
G36*
G01X1312330D02*
X1315150D01*
G02X1315352Y1572644I0J-202D01*
G01Y1572024D01*
G03X1315402Y1571892I200J0D01*
G02Y1568976I-1661J-1458D01*
G03X1315352Y1568844I150J-132D01*
G01Y1566905D01*
G03X1315402Y1566773I200J0D01*
G02Y1563857I-1661J-1458D01*
G03X1315352Y1563725I150J-132D01*
G01Y1563106D01*
G02X1315150Y1562904I-202J0D01*
G01X1312330D01*
G02X1312128Y1563106I0J202D01*
G01Y1563725D01*
G03X1312078Y1563857I-200J0D01*
G02Y1566773I1661J1458D01*
G03X1312128Y1566905I-150J132D01*
G01Y1568844D01*
G03X1312078Y1568976I-200J0D01*
G02Y1571892I1661J1458D01*
G03X1312128Y1572024I-150J132D01*
G01Y1572644D01*
G02X1312330Y1572846I202J0D01*
G37*
G36*
G01X1346976D02*
X1349796D01*
G02X1349998Y1572644I0J-202D01*
G01Y1572024D01*
G03X1350048Y1571892I200J0D01*
G02Y1568976I-1661J-1458D01*
G03X1349998Y1568844I150J-132D01*
G01Y1566905D01*
G03X1350048Y1566773I200J0D01*
G02Y1563857I-1661J-1458D01*
G03X1349998Y1563725I150J-132D01*
G01Y1563106D01*
G02X1349796Y1562904I-202J0D01*
G01X1346976D01*
G02X1346774Y1563106I0J202D01*
G01Y1563725D01*
G03X1346724Y1563857I-200J0D01*
G02Y1566773I1661J1458D01*
G03X1346774Y1566905I-150J132D01*
G01Y1568844D01*
G03X1346724Y1568976I-200J0D01*
G02Y1571892I1661J1458D01*
G03X1346774Y1572024I-150J132D01*
G01Y1572644D01*
G02X1346976Y1572846I202J0D01*
G37*
G36*
G01X1658786D02*
X1661606D01*
G02X1661808Y1572644I0J-202D01*
G01Y1572024D01*
G03X1661858Y1571892I200J0D01*
G02Y1568976I-1661J-1458D01*
G03X1661808Y1568844I150J-132D01*
G01Y1566905D01*
G03X1661858Y1566773I200J0D01*
G02Y1563857I-1661J-1458D01*
G03X1661808Y1563725I150J-132D01*
G01Y1563106D01*
G02X1661606Y1562904I-202J0D01*
G01X1658786D01*
G02X1658584Y1563106I0J202D01*
G01Y1563725D01*
G03X1658534Y1563857I-200J0D01*
G02Y1566773I1661J1458D01*
G03X1658584Y1566905I-150J132D01*
G01Y1568844D01*
G03X1658534Y1568976I-200J0D01*
G02Y1571892I1661J1458D01*
G03X1658584Y1572024I-150J132D01*
G01Y1572644D01*
G02X1658786Y1572846I202J0D01*
G37*
G36*
G01X1693432D02*
X1696252D01*
G02X1696454Y1572644I0J-202D01*
G01Y1572024D01*
G03X1696504Y1571892I200J0D01*
G02Y1568976I-1661J-1458D01*
G03X1696454Y1568844I150J-132D01*
G01Y1566905D01*
G03X1696504Y1566773I200J0D01*
G02Y1563857I-1661J-1458D01*
G03X1696454Y1563725I150J-132D01*
G01Y1563106D01*
G02X1696252Y1562904I-202J0D01*
G01X1693432D01*
G02X1693230Y1563106I0J202D01*
G01Y1563725D01*
G03X1693180Y1563857I-200J0D01*
G02Y1566773I1661J1458D01*
G03X1693230Y1566905I-150J132D01*
G01Y1568844D01*
G03X1693180Y1568976I-200J0D01*
G02Y1571892I1661J1458D01*
G03X1693230Y1572024I-150J132D01*
G01Y1572644D01*
G02X1693432Y1572846I202J0D01*
G37*
G36*
G01X117133D02*
X119953D01*
G02X120156Y1572644I1J-202D01*
G01Y1572022D01*
G03X120206Y1571890I200J0D01*
G02Y1568978I-1664J-1456D01*
G03X120156Y1568846I150J-132D01*
G01Y1566903D01*
G03X120206Y1566771I200J0D01*
G02Y1563859I-1664J-1456D01*
G03X120156Y1563727I150J-132D01*
G01Y1563106D01*
G02X119953Y1562904I-203J1D01*
G01X117133D01*
G02X116930Y1563106I-1J202D01*
G01Y1563727D01*
G03X116880Y1563859I-200J0D01*
G02Y1566771I1664J1456D01*
G03X116930Y1566903I-150J132D01*
G01Y1568846D01*
G03X116880Y1568978I-200J0D01*
G02Y1571890I1664J1456D01*
G03X116930Y1572022I-150J132D01*
G01Y1572644D01*
G02X117133Y1572846I203J-1D01*
G37*
G36*
G01X151779D02*
X154599D01*
G02X154802Y1572644I1J-202D01*
G01Y1572022D01*
G03X154852Y1571890I200J0D01*
G02Y1568978I-1664J-1456D01*
G03X154802Y1568846I150J-132D01*
G01Y1566903D01*
G03X154852Y1566771I200J0D01*
G02Y1563859I-1664J-1456D01*
G03X154802Y1563727I150J-132D01*
G01Y1563106D01*
G02X154599Y1562904I-203J1D01*
G01X151779D01*
G02X151576Y1563106I-1J202D01*
G01Y1563727D01*
G03X151526Y1563859I-200J0D01*
G02Y1566771I1664J1456D01*
G03X151576Y1566903I-150J132D01*
G01Y1568846D01*
G03X151526Y1568978I-200J0D01*
G02Y1571890I1664J1456D01*
G03X151576Y1572022I-150J132D01*
G01Y1572644D01*
G02X151779Y1572846I203J-1D01*
G37*
G36*
G01X290361D02*
X293181D01*
G02X293384Y1572644I1J-202D01*
G01Y1572022D01*
G03X293434Y1571890I200J0D01*
G02Y1568978I-1664J-1456D01*
G03X293384Y1568846I150J-132D01*
G01Y1566903D01*
G03X293434Y1566771I200J0D01*
G02Y1563859I-1664J-1456D01*
G03X293384Y1563727I150J-132D01*
G01Y1563106D01*
G02X293181Y1562904I-203J1D01*
G01X290361D01*
G02X290158Y1563106I-1J202D01*
G01Y1563727D01*
G03X290108Y1563859I-200J0D01*
G02Y1566771I1664J1456D01*
G03X290158Y1566903I-150J132D01*
G01Y1568846D01*
G03X290108Y1568978I-200J0D01*
G02Y1571890I1664J1456D01*
G03X290158Y1572022I-150J132D01*
G01Y1572644D01*
G02X290361Y1572846I203J-1D01*
G37*
G36*
G01X325007D02*
X327827D01*
G02X328030Y1572644I1J-202D01*
G01Y1572022D01*
G03X328080Y1571890I200J0D01*
G02Y1568978I-1664J-1456D01*
G03X328030Y1568846I150J-132D01*
G01Y1566903D01*
G03X328080Y1566771I200J0D01*
G02Y1563859I-1664J-1456D01*
G03X328030Y1563727I150J-132D01*
G01Y1563106D01*
G02X327827Y1562904I-203J1D01*
G01X325007D01*
G02X324804Y1563106I-1J202D01*
G01Y1563727D01*
G03X324754Y1563859I-200J0D01*
G02Y1566771I1664J1456D01*
G03X324804Y1566903I-150J132D01*
G01Y1568846D01*
G03X324754Y1568978I-200J0D01*
G02Y1571890I1664J1456D01*
G03X324804Y1572022I-150J132D01*
G01Y1572644D01*
G02X325007Y1572846I203J-1D01*
G37*
G36*
G01X515559D02*
X518379D01*
G02X518582Y1572644I1J-202D01*
G01Y1572022D01*
G03X518632Y1571890I200J0D01*
G02Y1568978I-1664J-1456D01*
G03X518582Y1568846I150J-132D01*
G01Y1566903D01*
G03X518632Y1566771I200J0D01*
G02Y1563859I-1664J-1456D01*
G03X518582Y1563727I150J-132D01*
G01Y1563106D01*
G02X518379Y1562904I-203J1D01*
G01X515559D01*
G02X515356Y1563106I-1J202D01*
G01Y1563727D01*
G03X515306Y1563859I-200J0D01*
G02Y1566771I1664J1456D01*
G03X515356Y1566903I-150J132D01*
G01Y1568846D01*
G03X515306Y1568978I-200J0D01*
G02Y1571890I1664J1456D01*
G03X515356Y1572022I-150J132D01*
G01Y1572644D01*
G02X515559Y1572846I203J-1D01*
G37*
G36*
G01X654141D02*
X656961D01*
G02X657164Y1572644I1J-202D01*
G01Y1572022D01*
G03X657214Y1571890I200J0D01*
G02Y1568978I-1664J-1456D01*
G03X657164Y1568846I150J-132D01*
G01Y1566903D01*
G03X657214Y1566771I200J0D01*
G02Y1563859I-1664J-1456D01*
G03X657164Y1563727I150J-132D01*
G01Y1563106D01*
G02X656961Y1562904I-203J1D01*
G01X654141D01*
G02X653938Y1563106I-1J202D01*
G01Y1563727D01*
G03X653888Y1563859I-200J0D01*
G02Y1566771I1664J1456D01*
G03X653938Y1566903I-150J132D01*
G01Y1568846D01*
G03X653888Y1568978I-200J0D01*
G02Y1571890I1664J1456D01*
G03X653938Y1572022I-150J132D01*
G01Y1572644D01*
G02X654141Y1572846I203J-1D01*
G37*
G36*
G01X688787D02*
X691607D01*
G02X691810Y1572644I1J-202D01*
G01Y1572022D01*
G03X691860Y1571890I200J0D01*
G02Y1568978I-1664J-1456D01*
G03X691810Y1568846I150J-132D01*
G01Y1566903D01*
G03X691860Y1566771I200J0D01*
G02Y1563859I-1664J-1456D01*
G03X691810Y1563727I150J-132D01*
G01Y1563106D01*
G02X691607Y1562904I-203J1D01*
G01X688787D01*
G02X688584Y1563106I-1J202D01*
G01Y1563727D01*
G03X688534Y1563859I-200J0D01*
G02Y1566771I1664J1456D01*
G03X688584Y1566903I-150J132D01*
G01Y1568846D01*
G03X688534Y1568978I-200J0D01*
G02Y1571890I1664J1456D01*
G03X688584Y1572022I-150J132D01*
G01Y1572644D01*
G02X688787Y1572846I203J-1D01*
G37*
G36*
G01X1139101D02*
X1141921D01*
G02X1142124Y1572644I1J-202D01*
G01Y1572022D01*
G03X1142174Y1571890I200J0D01*
G02Y1568978I-1664J-1456D01*
G03X1142124Y1568846I150J-132D01*
G01Y1566903D01*
G03X1142174Y1566771I200J0D01*
G02Y1563859I-1664J-1456D01*
G03X1142124Y1563727I150J-132D01*
G01Y1563106D01*
G02X1141921Y1562904I-203J1D01*
G01X1139101D01*
G02X1138898Y1563106I-1J202D01*
G01Y1563727D01*
G03X1138848Y1563859I-200J0D01*
G02Y1566771I1664J1456D01*
G03X1138898Y1566903I-150J132D01*
G01Y1568846D01*
G03X1138848Y1568978I-200J0D01*
G02Y1571890I1664J1456D01*
G03X1138898Y1572022I-150J132D01*
G01Y1572644D01*
G02X1139101Y1572846I203J-1D01*
G37*
G36*
G01X1173747D02*
X1176567D01*
G02X1176770Y1572644I1J-202D01*
G01Y1572022D01*
G03X1176820Y1571890I200J0D01*
G02Y1568978I-1664J-1456D01*
G03X1176770Y1568846I150J-132D01*
G01Y1566903D01*
G03X1176820Y1566771I200J0D01*
G02Y1563859I-1664J-1456D01*
G03X1176770Y1563727I150J-132D01*
G01Y1563106D01*
G02X1176567Y1562904I-203J1D01*
G01X1173747D01*
G02X1173544Y1563106I-1J202D01*
G01Y1563727D01*
G03X1173494Y1563859I-200J0D01*
G02Y1566771I1664J1456D01*
G03X1173544Y1566903I-150J132D01*
G01Y1568846D01*
G03X1173494Y1568978I-200J0D01*
G02Y1571890I1664J1456D01*
G03X1173544Y1572022I-150J132D01*
G01Y1572644D01*
G02X1173747Y1572846I203J-1D01*
G37*
G36*
G01X1329653D02*
X1332473D01*
G02X1332676Y1572644I1J-202D01*
G01Y1572022D01*
G03X1332726Y1571890I200J0D01*
G02Y1568978I-1664J-1456D01*
G03X1332676Y1568846I150J-132D01*
G01Y1566903D01*
G03X1332726Y1566771I200J0D01*
G02Y1563859I-1664J-1456D01*
G03X1332676Y1563727I150J-132D01*
G01Y1563106D01*
G02X1332473Y1562904I-203J1D01*
G01X1329653D01*
G02X1329450Y1563106I-1J202D01*
G01Y1563727D01*
G03X1329400Y1563859I-200J0D01*
G02Y1566771I1664J1456D01*
G03X1329450Y1566903I-150J132D01*
G01Y1568846D01*
G03X1329400Y1568978I-200J0D01*
G02Y1571890I1664J1456D01*
G03X1329450Y1572022I-150J132D01*
G01Y1572644D01*
G02X1329653Y1572846I203J-1D01*
G37*
G36*
G01X1364299D02*
X1367119D01*
G02X1367322Y1572644I1J-202D01*
G01Y1572022D01*
G03X1367372Y1571890I200J0D01*
G02Y1568978I-1664J-1456D01*
G03X1367322Y1568846I150J-132D01*
G01Y1566903D01*
G03X1367372Y1566771I200J0D01*
G02Y1563859I-1664J-1456D01*
G03X1367322Y1563727I150J-132D01*
G01Y1563106D01*
G02X1367119Y1562904I-203J1D01*
G01X1364299D01*
G02X1364096Y1563106I-1J202D01*
G01Y1563727D01*
G03X1364046Y1563859I-200J0D01*
G02Y1566771I1664J1456D01*
G03X1364096Y1566903I-150J132D01*
G01Y1568846D01*
G03X1364046Y1568978I-200J0D01*
G02Y1571890I1664J1456D01*
G03X1364096Y1572022I-150J132D01*
G01Y1572644D01*
G02X1364299Y1572846I203J-1D01*
G37*
G36*
G01X1676109D02*
X1678929D01*
G02X1679132Y1572644I1J-202D01*
G01Y1572022D01*
G03X1679182Y1571890I200J0D01*
G02Y1568978I-1664J-1456D01*
G03X1679132Y1568846I150J-132D01*
G01Y1566903D01*
G03X1679182Y1566771I200J0D01*
G02Y1563859I-1664J-1456D01*
G03X1679132Y1563727I150J-132D01*
G01Y1563106D01*
G02X1678929Y1562904I-203J1D01*
G01X1676109D01*
G02X1675906Y1563106I-1J202D01*
G01Y1563727D01*
G03X1675856Y1563859I-200J0D01*
G02Y1566771I1664J1456D01*
G03X1675906Y1566903I-150J132D01*
G01Y1568846D01*
G03X1675856Y1568978I-200J0D01*
G02Y1571890I1664J1456D01*
G03X1675906Y1572022I-150J132D01*
G01Y1572644D01*
G02X1676109Y1572846I203J-1D01*
G37*
G36*
G01X1710755D02*
X1713575D01*
G02X1713778Y1572644I1J-202D01*
G01Y1572022D01*
G03X1713828Y1571890I200J0D01*
G02Y1568978I-1664J-1456D01*
G03X1713778Y1568846I150J-132D01*
G01Y1566903D01*
G03X1713828Y1566771I200J0D01*
G02Y1563859I-1664J-1456D01*
G03X1713778Y1563727I150J-132D01*
G01Y1563106D01*
G02X1713575Y1562904I-203J1D01*
G01X1710755D01*
G02X1710552Y1563106I-1J202D01*
G01Y1563727D01*
G03X1710502Y1563859I-200J0D01*
G02Y1566771I1664J1456D01*
G03X1710552Y1566903I-150J132D01*
G01Y1568846D01*
G03X1710502Y1568978I-200J0D01*
G02Y1571890I1664J1456D01*
G03X1710552Y1572022I-150J132D01*
G01Y1572644D01*
G02X1710755Y1572846I203J-1D01*
G37*
G36*
G01X108472Y1583870D02*
X111292D01*
G02X111494Y1583667I-1J-203D01*
G01Y1583047D01*
G03X111544Y1582915I200J0D01*
G02Y1579999I-1661J-1458D01*
G03X111494Y1579867I150J-132D01*
G01Y1577929D01*
G03X111544Y1577797I200J0D01*
G02Y1574881I-1661J-1458D01*
G03X111494Y1574749I150J-132D01*
G01Y1574129D01*
G02X111292Y1573926I-202J-1D01*
G01X108472D01*
G02X108270Y1574129I1J203D01*
G01Y1574749D01*
G03X108220Y1574881I-200J0D01*
G02Y1577797I1661J1458D01*
G03X108270Y1577929I-150J132D01*
G01Y1579867D01*
G03X108220Y1579999I-200J0D01*
G02Y1582915I1661J1458D01*
G03X108270Y1583047I-150J132D01*
G01Y1583667D01*
G02X108472Y1583870I202J1D01*
G37*
G36*
G01X125795D02*
X128615D01*
G02X128818Y1583667I0J-203D01*
G01Y1583045D01*
G03X128868Y1582913I200J0D01*
G02Y1580001I-1664J-1456D01*
G03X128818Y1579869I150J-132D01*
G01Y1577927D01*
G03X128868Y1577795I200J0D01*
G02Y1574883I-1664J-1456D01*
G03X128818Y1574751I150J-132D01*
G01Y1574129D01*
G02X128615Y1573926I-203J0D01*
G01X125795D01*
G02X125592Y1574129I0J203D01*
G01Y1574751D01*
G03X125542Y1574883I-200J0D01*
G02Y1577795I1664J1456D01*
G03X125592Y1577927I-150J132D01*
G01Y1579869D01*
G03X125542Y1580001I-200J0D01*
G02Y1582913I1664J1456D01*
G03X125592Y1583045I-150J132D01*
G01Y1583667D01*
G02X125795Y1583870I203J0D01*
G37*
G36*
G01X143118D02*
X145938D01*
G02X146140Y1583667I-1J-203D01*
G01Y1583047D01*
G03X146190Y1582915I200J0D01*
G02Y1579999I-1661J-1458D01*
G03X146140Y1579867I150J-132D01*
G01Y1577929D01*
G03X146190Y1577797I200J0D01*
G02Y1574881I-1661J-1458D01*
G03X146140Y1574749I150J-132D01*
G01Y1574129D01*
G02X145938Y1573926I-202J-1D01*
G01X143118D01*
G02X142916Y1574129I1J203D01*
G01Y1574749D01*
G03X142866Y1574881I-200J0D01*
G02Y1577797I1661J1458D01*
G03X142916Y1577929I-150J132D01*
G01Y1579867D01*
G03X142866Y1579999I-200J0D01*
G02Y1582915I1661J1458D01*
G03X142916Y1583047I-150J132D01*
G01Y1583667D01*
G02X143118Y1583870I202J1D01*
G37*
G36*
G01X160440D02*
X163260D01*
G02X163462Y1583667I-1J-203D01*
G01Y1583047D01*
G03X163512Y1582915I200J0D01*
G02Y1579999I-1661J-1458D01*
G03X163462Y1579867I150J-132D01*
G01Y1577929D01*
G03X163512Y1577797I200J0D01*
G02Y1574881I-1661J-1458D01*
G03X163462Y1574749I150J-132D01*
G01Y1574129D01*
G02X163260Y1573926I-202J-1D01*
G01X160440D01*
G02X160238Y1574129I1J203D01*
G01Y1574749D01*
G03X160188Y1574881I-200J0D01*
G02Y1577797I1661J1458D01*
G03X160238Y1577929I-150J132D01*
G01Y1579867D01*
G03X160188Y1579999I-200J0D01*
G02Y1582915I1661J1458D01*
G03X160238Y1583047I-150J132D01*
G01Y1583667D01*
G02X160440Y1583870I202J1D01*
G37*
G36*
G01X281700D02*
X284520D01*
G02X284722Y1583667I-1J-203D01*
G01Y1583047D01*
G03X284772Y1582915I200J0D01*
G02Y1579999I-1661J-1458D01*
G03X284722Y1579867I150J-132D01*
G01Y1577929D01*
G03X284772Y1577797I200J0D01*
G02Y1574881I-1661J-1458D01*
G03X284722Y1574749I150J-132D01*
G01Y1574129D01*
G02X284520Y1573926I-202J-1D01*
G01X281700D01*
G02X281498Y1574129I1J203D01*
G01Y1574749D01*
G03X281448Y1574881I-200J0D01*
G02Y1577797I1661J1458D01*
G03X281498Y1577929I-150J132D01*
G01Y1579867D01*
G03X281448Y1579999I-200J0D01*
G02Y1582915I1661J1458D01*
G03X281498Y1583047I-150J132D01*
G01Y1583667D01*
G02X281700Y1583870I202J1D01*
G37*
G36*
G01X299023D02*
X301843D01*
G02X302046Y1583667I0J-203D01*
G01Y1583045D01*
G03X302096Y1582913I200J0D01*
G02Y1580001I-1664J-1456D01*
G03X302046Y1579869I150J-132D01*
G01Y1577927D01*
G03X302096Y1577795I200J0D01*
G02Y1574883I-1664J-1456D01*
G03X302046Y1574751I150J-132D01*
G01Y1574129D01*
G02X301843Y1573926I-203J0D01*
G01X299023D01*
G02X298820Y1574129I0J203D01*
G01Y1574751D01*
G03X298770Y1574883I-200J0D01*
G02Y1577795I1664J1456D01*
G03X298820Y1577927I-150J132D01*
G01Y1579869D01*
G03X298770Y1580001I-200J0D01*
G02Y1582913I1664J1456D01*
G03X298820Y1583045I-150J132D01*
G01Y1583667D01*
G02X299023Y1583870I203J0D01*
G37*
G36*
G01X316346D02*
X319166D01*
G02X319368Y1583667I-1J-203D01*
G01Y1583047D01*
G03X319418Y1582915I200J0D01*
G02Y1579999I-1661J-1458D01*
G03X319368Y1579867I150J-132D01*
G01Y1577929D01*
G03X319418Y1577797I200J0D01*
G02Y1574881I-1661J-1458D01*
G03X319368Y1574749I150J-132D01*
G01Y1574129D01*
G02X319166Y1573926I-202J-1D01*
G01X316346D01*
G02X316144Y1574129I1J203D01*
G01Y1574749D01*
G03X316094Y1574881I-200J0D01*
G02Y1577797I1661J1458D01*
G03X316144Y1577929I-150J132D01*
G01Y1579867D01*
G03X316094Y1579999I-200J0D01*
G02Y1582915I1661J1458D01*
G03X316144Y1583047I-150J132D01*
G01Y1583667D01*
G02X316346Y1583870I202J1D01*
G37*
G36*
G01X333668D02*
X336488D01*
G02X336690Y1583667I-1J-203D01*
G01Y1583047D01*
G03X336740Y1582915I200J0D01*
G02Y1579999I-1661J-1458D01*
G03X336690Y1579867I150J-132D01*
G01Y1577929D01*
G03X336740Y1577797I200J0D01*
G02Y1574881I-1661J-1458D01*
G03X336690Y1574749I150J-132D01*
G01Y1574129D01*
G02X336488Y1573926I-202J-1D01*
G01X333668D01*
G02X333466Y1574129I1J203D01*
G01Y1574749D01*
G03X333416Y1574881I-200J0D01*
G02Y1577797I1661J1458D01*
G03X333466Y1577929I-150J132D01*
G01Y1579867D01*
G03X333416Y1579999I-200J0D01*
G02Y1582915I1661J1458D01*
G03X333466Y1583047I-150J132D01*
G01Y1583667D01*
G02X333668Y1583870I202J1D01*
G37*
G36*
G01X628157D02*
X630977D01*
G02X631180Y1583667I0J-203D01*
G01Y1583045D01*
G03X631230Y1582913I200J0D01*
G02Y1580001I-1664J-1456D01*
G03X631180Y1579869I150J-132D01*
G01Y1577927D01*
G03X631230Y1577795I200J0D01*
G02Y1574883I-1664J-1456D01*
G03X631180Y1574751I150J-132D01*
G01Y1574129D01*
G02X630977Y1573926I-203J0D01*
G01X628157D01*
G02X627954Y1574129I0J203D01*
G01Y1574751D01*
G03X627904Y1574883I-200J0D01*
G02Y1577795I1664J1456D01*
G03X627954Y1577927I-150J132D01*
G01Y1579869D01*
G03X627904Y1580001I-200J0D01*
G02Y1582913I1664J1456D01*
G03X627954Y1583045I-150J132D01*
G01Y1583667D01*
G02X628157Y1583870I203J0D01*
G37*
G36*
G01X645480D02*
X648300D01*
G02X648502Y1583667I-1J-203D01*
G01Y1583047D01*
G03X648552Y1582915I200J0D01*
G02Y1579999I-1661J-1458D01*
G03X648502Y1579867I150J-132D01*
G01Y1577929D01*
G03X648552Y1577797I200J0D01*
G02Y1574881I-1661J-1458D01*
G03X648502Y1574749I150J-132D01*
G01Y1574129D01*
G02X648300Y1573926I-202J-1D01*
G01X645480D01*
G02X645278Y1574129I1J203D01*
G01Y1574749D01*
G03X645228Y1574881I-200J0D01*
G02Y1577797I1661J1458D01*
G03X645278Y1577929I-150J132D01*
G01Y1579867D01*
G03X645228Y1579999I-200J0D01*
G02Y1582915I1661J1458D01*
G03X645278Y1583047I-150J132D01*
G01Y1583667D01*
G02X645480Y1583870I202J1D01*
G37*
G36*
G01X662803D02*
X665623D01*
G02X665826Y1583667I0J-203D01*
G01Y1583045D01*
G03X665876Y1582913I200J0D01*
G02Y1580001I-1664J-1456D01*
G03X665826Y1579869I150J-132D01*
G01Y1577927D01*
G03X665876Y1577795I200J0D01*
G02Y1574883I-1664J-1456D01*
G03X665826Y1574751I150J-132D01*
G01Y1574129D01*
G02X665623Y1573926I-203J0D01*
G01X662803D01*
G02X662600Y1574129I0J203D01*
G01Y1574751D01*
G03X662550Y1574883I-200J0D01*
G02Y1577795I1664J1456D01*
G03X662600Y1577927I-150J132D01*
G01Y1579869D01*
G03X662550Y1580001I-200J0D01*
G02Y1582913I1664J1456D01*
G03X662600Y1583045I-150J132D01*
G01Y1583667D01*
G02X662803Y1583870I203J0D01*
G37*
G36*
G01X680125D02*
X682945D01*
G02X683148Y1583667I0J-203D01*
G01Y1583045D01*
G03X683198Y1582913I200J0D01*
G02Y1580001I-1664J-1456D01*
G03X683148Y1579869I150J-132D01*
G01Y1577927D01*
G03X683198Y1577795I200J0D01*
G02Y1574883I-1664J-1456D01*
G03X683148Y1574751I150J-132D01*
G01Y1574129D01*
G02X682945Y1573926I-203J0D01*
G01X680125D01*
G02X679922Y1574129I0J203D01*
G01Y1574751D01*
G03X679872Y1574883I-200J0D01*
G02Y1577795I1664J1456D01*
G03X679922Y1577927I-150J132D01*
G01Y1579869D01*
G03X679872Y1580001I-200J0D01*
G02Y1582913I1664J1456D01*
G03X679922Y1583045I-150J132D01*
G01Y1583667D01*
G02X680125Y1583870I203J0D01*
G37*
G36*
G01X1130440D02*
X1133260D01*
G02X1133462Y1583667I-1J-203D01*
G01Y1583047D01*
G03X1133512Y1582915I200J0D01*
G02Y1579999I-1661J-1458D01*
G03X1133462Y1579867I150J-132D01*
G01Y1577929D01*
G03X1133512Y1577797I200J0D01*
G02Y1574881I-1661J-1458D01*
G03X1133462Y1574749I150J-132D01*
G01Y1574129D01*
G02X1133260Y1573926I-202J-1D01*
G01X1130440D01*
G02X1130238Y1574129I1J203D01*
G01Y1574749D01*
G03X1130188Y1574881I-200J0D01*
G02Y1577797I1661J1458D01*
G03X1130238Y1577929I-150J132D01*
G01Y1579867D01*
G03X1130188Y1579999I-200J0D01*
G02Y1582915I1661J1458D01*
G03X1130238Y1583047I-150J132D01*
G01Y1583667D01*
G02X1130440Y1583870I202J1D01*
G37*
G36*
G01X1147763D02*
X1150583D01*
G02X1150786Y1583667I0J-203D01*
G01Y1583045D01*
G03X1150836Y1582913I200J0D01*
G02Y1580001I-1664J-1456D01*
G03X1150786Y1579869I150J-132D01*
G01Y1577927D01*
G03X1150836Y1577795I200J0D01*
G02Y1574883I-1664J-1456D01*
G03X1150786Y1574751I150J-132D01*
G01Y1574129D01*
G02X1150583Y1573926I-203J0D01*
G01X1147763D01*
G02X1147560Y1574129I0J203D01*
G01Y1574751D01*
G03X1147510Y1574883I-200J0D01*
G02Y1577795I1664J1456D01*
G03X1147560Y1577927I-150J132D01*
G01Y1579869D01*
G03X1147510Y1580001I-200J0D01*
G02Y1582913I1664J1456D01*
G03X1147560Y1583045I-150J132D01*
G01Y1583667D01*
G02X1147763Y1583870I203J0D01*
G37*
G36*
G01X1165086D02*
X1167906D01*
G02X1168108Y1583667I-1J-203D01*
G01Y1583047D01*
G03X1168158Y1582915I200J0D01*
G02Y1579999I-1661J-1458D01*
G03X1168108Y1579867I150J-132D01*
G01Y1577929D01*
G03X1168158Y1577797I200J0D01*
G02Y1574881I-1661J-1458D01*
G03X1168108Y1574749I150J-132D01*
G01Y1574129D01*
G02X1167906Y1573926I-202J-1D01*
G01X1165086D01*
G02X1164884Y1574129I1J203D01*
G01Y1574749D01*
G03X1164834Y1574881I-200J0D01*
G02Y1577797I1661J1458D01*
G03X1164884Y1577929I-150J132D01*
G01Y1579867D01*
G03X1164834Y1579999I-200J0D01*
G02Y1582915I1661J1458D01*
G03X1164884Y1583047I-150J132D01*
G01Y1583667D01*
G02X1165086Y1583870I202J1D01*
G37*
G36*
G01X1182408D02*
X1185228D01*
G02X1185430Y1583667I-1J-203D01*
G01Y1583047D01*
G03X1185480Y1582915I200J0D01*
G02Y1579999I-1661J-1458D01*
G03X1185430Y1579867I150J-132D01*
G01Y1577929D01*
G03X1185480Y1577797I200J0D01*
G02Y1574881I-1661J-1458D01*
G03X1185430Y1574749I150J-132D01*
G01Y1574129D01*
G02X1185228Y1573926I-202J-1D01*
G01X1182408D01*
G02X1182206Y1574129I1J203D01*
G01Y1574749D01*
G03X1182156Y1574881I-200J0D01*
G02Y1577797I1661J1458D01*
G03X1182206Y1577929I-150J132D01*
G01Y1579867D01*
G03X1182156Y1579999I-200J0D01*
G02Y1582915I1661J1458D01*
G03X1182206Y1583047I-150J132D01*
G01Y1583667D01*
G02X1182408Y1583870I202J1D01*
G37*
G36*
G01X1303669D02*
X1306489D01*
G02X1306692Y1583667I0J-203D01*
G01Y1583045D01*
G03X1306742Y1582913I200J0D01*
G02Y1580001I-1664J-1456D01*
G03X1306692Y1579869I150J-132D01*
G01Y1577927D01*
G03X1306742Y1577795I200J0D01*
G02Y1574883I-1664J-1456D01*
G03X1306692Y1574751I150J-132D01*
G01Y1574129D01*
G02X1306489Y1573926I-203J0D01*
G01X1303669D01*
G02X1303466Y1574129I0J203D01*
G01Y1574751D01*
G03X1303416Y1574883I-200J0D01*
G02Y1577795I1664J1456D01*
G03X1303466Y1577927I-150J132D01*
G01Y1579869D01*
G03X1303416Y1580001I-200J0D01*
G02Y1582913I1664J1456D01*
G03X1303466Y1583045I-150J132D01*
G01Y1583667D01*
G02X1303669Y1583870I203J0D01*
G37*
G36*
G01X1320992D02*
X1323812D01*
G02X1324014Y1583667I-1J-203D01*
G01Y1583047D01*
G03X1324064Y1582915I200J0D01*
G02Y1579999I-1661J-1458D01*
G03X1324014Y1579867I150J-132D01*
G01Y1577929D01*
G03X1324064Y1577797I200J0D01*
G02Y1574881I-1661J-1458D01*
G03X1324014Y1574749I150J-132D01*
G01Y1574129D01*
G02X1323812Y1573926I-202J-1D01*
G01X1320992D01*
G02X1320790Y1574129I1J203D01*
G01Y1574749D01*
G03X1320740Y1574881I-200J0D01*
G02Y1577797I1661J1458D01*
G03X1320790Y1577929I-150J132D01*
G01Y1579867D01*
G03X1320740Y1579999I-200J0D01*
G02Y1582915I1661J1458D01*
G03X1320790Y1583047I-150J132D01*
G01Y1583667D01*
G02X1320992Y1583870I202J1D01*
G37*
G36*
G01X1338315D02*
X1341135D01*
G02X1341338Y1583667I0J-203D01*
G01Y1583045D01*
G03X1341388Y1582913I200J0D01*
G02Y1580001I-1664J-1456D01*
G03X1341338Y1579869I150J-132D01*
G01Y1577927D01*
G03X1341388Y1577795I200J0D01*
G02Y1574883I-1664J-1456D01*
G03X1341338Y1574751I150J-132D01*
G01Y1574129D01*
G02X1341135Y1573926I-203J0D01*
G01X1338315D01*
G02X1338112Y1574129I0J203D01*
G01Y1574751D01*
G03X1338062Y1574883I-200J0D01*
G02Y1577795I1664J1456D01*
G03X1338112Y1577927I-150J132D01*
G01Y1579869D01*
G03X1338062Y1580001I-200J0D01*
G02Y1582913I1664J1456D01*
G03X1338112Y1583045I-150J132D01*
G01Y1583667D01*
G02X1338315Y1583870I203J0D01*
G37*
G36*
G01X1355637D02*
X1358457D01*
G02X1358660Y1583667I0J-203D01*
G01Y1583045D01*
G03X1358710Y1582913I200J0D01*
G02Y1580001I-1664J-1456D01*
G03X1358660Y1579869I150J-132D01*
G01Y1577927D01*
G03X1358710Y1577795I200J0D01*
G02Y1574883I-1664J-1456D01*
G03X1358660Y1574751I150J-132D01*
G01Y1574129D01*
G02X1358457Y1573926I-203J0D01*
G01X1355637D01*
G02X1355434Y1574129I0J203D01*
G01Y1574751D01*
G03X1355384Y1574883I-200J0D01*
G02Y1577795I1664J1456D01*
G03X1355434Y1577927I-150J132D01*
G01Y1579869D01*
G03X1355384Y1580001I-200J0D01*
G02Y1582913I1664J1456D01*
G03X1355434Y1583045I-150J132D01*
G01Y1583667D01*
G02X1355637Y1583870I203J0D01*
G37*
G36*
G01X1476897D02*
X1479717D01*
G02X1479920Y1583667I0J-203D01*
G01Y1583045D01*
G03X1479970Y1582913I200J0D01*
G02Y1580001I-1664J-1456D01*
G03X1479920Y1579869I150J-132D01*
G01Y1577927D01*
G03X1479970Y1577795I200J0D01*
G02Y1574883I-1664J-1456D01*
G03X1479920Y1574751I150J-132D01*
G01Y1574129D01*
G02X1479717Y1573926I-203J0D01*
G01X1476897D01*
G02X1476694Y1574129I0J203D01*
G01Y1574751D01*
G03X1476644Y1574883I-200J0D01*
G02Y1577795I1664J1456D01*
G03X1476694Y1577927I-150J132D01*
G01Y1579869D01*
G03X1476644Y1580001I-200J0D01*
G02Y1582913I1664J1456D01*
G03X1476694Y1583045I-150J132D01*
G01Y1583667D01*
G02X1476897Y1583870I203J0D01*
G37*
G36*
G01X1650125D02*
X1652945D01*
G02X1653148Y1583667I0J-203D01*
G01Y1583045D01*
G03X1653198Y1582913I200J0D01*
G02Y1580001I-1664J-1456D01*
G03X1653148Y1579869I150J-132D01*
G01Y1577927D01*
G03X1653198Y1577795I200J0D01*
G02Y1574883I-1664J-1456D01*
G03X1653148Y1574751I150J-132D01*
G01Y1574129D01*
G02X1652945Y1573926I-203J0D01*
G01X1650125D01*
G02X1649922Y1574129I0J203D01*
G01Y1574751D01*
G03X1649872Y1574883I-200J0D01*
G02Y1577795I1664J1456D01*
G03X1649922Y1577927I-150J132D01*
G01Y1579869D01*
G03X1649872Y1580001I-200J0D01*
G02Y1582913I1664J1456D01*
G03X1649922Y1583045I-150J132D01*
G01Y1583667D01*
G02X1650125Y1583870I203J0D01*
G37*
G36*
G01X1667448D02*
X1670268D01*
G02X1670470Y1583667I-1J-203D01*
G01Y1583047D01*
G03X1670520Y1582915I200J0D01*
G02Y1579999I-1661J-1458D01*
G03X1670470Y1579867I150J-132D01*
G01Y1577929D01*
G03X1670520Y1577797I200J0D01*
G02Y1574881I-1661J-1458D01*
G03X1670470Y1574749I150J-132D01*
G01Y1574129D01*
G02X1670268Y1573926I-202J-1D01*
G01X1667448D01*
G02X1667246Y1574129I1J203D01*
G01Y1574749D01*
G03X1667196Y1574881I-200J0D01*
G02Y1577797I1661J1458D01*
G03X1667246Y1577929I-150J132D01*
G01Y1579867D01*
G03X1667196Y1579999I-200J0D01*
G02Y1582915I1661J1458D01*
G03X1667246Y1583047I-150J132D01*
G01Y1583667D01*
G02X1667448Y1583870I202J1D01*
G37*
G36*
G01X1684771D02*
X1687591D01*
G02X1687794Y1583667I0J-203D01*
G01Y1583045D01*
G03X1687844Y1582913I200J0D01*
G02Y1580001I-1664J-1456D01*
G03X1687794Y1579869I150J-132D01*
G01Y1577927D01*
G03X1687844Y1577795I200J0D01*
G02Y1574883I-1664J-1456D01*
G03X1687794Y1574751I150J-132D01*
G01Y1574129D01*
G02X1687591Y1573926I-203J0D01*
G01X1684771D01*
G02X1684568Y1574129I0J203D01*
G01Y1574751D01*
G03X1684518Y1574883I-200J0D01*
G02Y1577795I1664J1456D01*
G03X1684568Y1577927I-150J132D01*
G01Y1579869D01*
G03X1684518Y1580001I-200J0D01*
G02Y1582913I1664J1456D01*
G03X1684568Y1583045I-150J132D01*
G01Y1583667D01*
G02X1684771Y1583870I203J0D01*
G37*
G36*
G01X1702093D02*
X1704913D01*
G02X1705116Y1583667I0J-203D01*
G01Y1583045D01*
G03X1705166Y1582913I200J0D01*
G02Y1580001I-1664J-1456D01*
G03X1705116Y1579869I150J-132D01*
G01Y1577927D01*
G03X1705166Y1577795I200J0D01*
G02Y1574883I-1664J-1456D01*
G03X1705116Y1574751I150J-132D01*
G01Y1574129D01*
G02X1704913Y1573926I-203J0D01*
G01X1702093D01*
G02X1701890Y1574129I0J203D01*
G01Y1574751D01*
G03X1701840Y1574883I-200J0D01*
G02Y1577795I1664J1456D01*
G03X1701890Y1577927I-150J132D01*
G01Y1579869D01*
G03X1701840Y1580001I-200J0D01*
G02Y1582913I1664J1456D01*
G03X1701890Y1583045I-150J132D01*
G01Y1583667D01*
G02X1702093Y1583870I203J0D01*
G37*
G36*
G01X134456Y1588200D02*
X137276D01*
G02X137478Y1587998I0J-202D01*
G01Y1587378D01*
G03X137528Y1587246I200J0D01*
G02Y1584330I-1661J-1458D01*
G03X137478Y1584198I150J-132D01*
G01Y1582260D01*
G03X137528Y1582128I200J0D01*
G02Y1579212I-1661J-1458D01*
G03X137478Y1579080I150J-132D01*
G01Y1578460D01*
G02X137276Y1578258I-202J0D01*
G01X134456D01*
G02X134254Y1578460I0J202D01*
G01Y1579080D01*
G03X134204Y1579212I-200J0D01*
G02Y1582128I1661J1458D01*
G03X134254Y1582260I-150J132D01*
G01Y1584198D01*
G03X134204Y1584330I-200J0D01*
G02Y1587246I1661J1458D01*
G03X134254Y1587378I-150J132D01*
G01Y1587998D01*
G02X134456Y1588200I202J0D01*
G37*
G36*
G01X169102D02*
X171922D01*
G02X172124Y1587998I0J-202D01*
G01Y1587378D01*
G03X172174Y1587246I200J0D01*
G02Y1584330I-1661J-1458D01*
G03X172124Y1584198I150J-132D01*
G01Y1582260D01*
G03X172174Y1582128I200J0D01*
G02Y1579212I-1661J-1458D01*
G03X172124Y1579080I150J-132D01*
G01Y1578460D01*
G02X171922Y1578258I-202J0D01*
G01X169102D01*
G02X168900Y1578460I0J202D01*
G01Y1579080D01*
G03X168850Y1579212I-200J0D01*
G02Y1582128I1661J1458D01*
G03X168900Y1582260I-150J132D01*
G01Y1584198D01*
G03X168850Y1584330I-200J0D01*
G02Y1587246I1661J1458D01*
G03X168900Y1587378I-150J132D01*
G01Y1587998D01*
G02X169102Y1588200I202J0D01*
G37*
G36*
G01X307684D02*
X310504D01*
G02X310706Y1587998I0J-202D01*
G01Y1587378D01*
G03X310756Y1587246I200J0D01*
G02Y1584330I-1661J-1458D01*
G03X310706Y1584198I150J-132D01*
G01Y1582260D01*
G03X310756Y1582128I200J0D01*
G02Y1579212I-1661J-1458D01*
G03X310706Y1579080I150J-132D01*
G01Y1578460D01*
G02X310504Y1578258I-202J0D01*
G01X307684D01*
G02X307482Y1578460I0J202D01*
G01Y1579080D01*
G03X307432Y1579212I-200J0D01*
G02Y1582128I1661J1458D01*
G03X307482Y1582260I-150J132D01*
G01Y1584198D01*
G03X307432Y1584330I-200J0D01*
G02Y1587246I1661J1458D01*
G03X307482Y1587378I-150J132D01*
G01Y1587998D01*
G02X307684Y1588200I202J0D01*
G37*
G36*
G01X342330D02*
X345150D01*
G02X345352Y1587998I0J-202D01*
G01Y1587378D01*
G03X345402Y1587246I200J0D01*
G02Y1584330I-1661J-1458D01*
G03X345352Y1584198I150J-132D01*
G01Y1582260D01*
G03X345402Y1582128I200J0D01*
G02Y1579212I-1661J-1458D01*
G03X345352Y1579080I150J-132D01*
G01Y1578460D01*
G02X345150Y1578258I-202J0D01*
G01X342330D01*
G02X342128Y1578460I0J202D01*
G01Y1579080D01*
G03X342078Y1579212I-200J0D01*
G02Y1582128I1661J1458D01*
G03X342128Y1582260I-150J132D01*
G01Y1584198D01*
G03X342078Y1584330I-200J0D01*
G02Y1587246I1661J1458D01*
G03X342128Y1587378I-150J132D01*
G01Y1587998D01*
G02X342330Y1588200I202J0D01*
G37*
G36*
G01X636818D02*
X639638D01*
G02X639840Y1587998I0J-202D01*
G01Y1587378D01*
G03X639890Y1587246I200J0D01*
G02Y1584330I-1661J-1458D01*
G03X639840Y1584198I150J-132D01*
G01Y1582260D01*
G03X639890Y1582128I200J0D01*
G02Y1579212I-1661J-1458D01*
G03X639840Y1579080I150J-132D01*
G01Y1578460D01*
G02X639638Y1578258I-202J0D01*
G01X636818D01*
G02X636616Y1578460I0J202D01*
G01Y1579080D01*
G03X636566Y1579212I-200J0D01*
G02Y1582128I1661J1458D01*
G03X636616Y1582260I-150J132D01*
G01Y1584198D01*
G03X636566Y1584330I-200J0D01*
G02Y1587246I1661J1458D01*
G03X636616Y1587378I-150J132D01*
G01Y1587998D01*
G02X636818Y1588200I202J0D01*
G37*
G36*
G01X671464D02*
X674284D01*
G02X674486Y1587998I0J-202D01*
G01Y1587378D01*
G03X674536Y1587246I200J0D01*
G02Y1584330I-1661J-1458D01*
G03X674486Y1584198I150J-132D01*
G01Y1582260D01*
G03X674536Y1582128I200J0D01*
G02Y1579212I-1661J-1458D01*
G03X674486Y1579080I150J-132D01*
G01Y1578460D01*
G02X674284Y1578258I-202J0D01*
G01X671464D01*
G02X671262Y1578460I0J202D01*
G01Y1579080D01*
G03X671212Y1579212I-200J0D01*
G02Y1582128I1661J1458D01*
G03X671262Y1582260I-150J132D01*
G01Y1584198D01*
G03X671212Y1584330I-200J0D01*
G02Y1587246I1661J1458D01*
G03X671262Y1587378I-150J132D01*
G01Y1587998D01*
G02X671464Y1588200I202J0D01*
G37*
G36*
G01X1156424D02*
X1159244D01*
G02X1159446Y1587998I0J-202D01*
G01Y1587378D01*
G03X1159496Y1587246I200J0D01*
G02Y1584330I-1661J-1458D01*
G03X1159446Y1584198I150J-132D01*
G01Y1582260D01*
G03X1159496Y1582128I200J0D01*
G02Y1579212I-1661J-1458D01*
G03X1159446Y1579080I150J-132D01*
G01Y1578460D01*
G02X1159244Y1578258I-202J0D01*
G01X1156424D01*
G02X1156222Y1578460I0J202D01*
G01Y1579080D01*
G03X1156172Y1579212I-200J0D01*
G02Y1582128I1661J1458D01*
G03X1156222Y1582260I-150J132D01*
G01Y1584198D01*
G03X1156172Y1584330I-200J0D01*
G02Y1587246I1661J1458D01*
G03X1156222Y1587378I-150J132D01*
G01Y1587998D01*
G02X1156424Y1588200I202J0D01*
G37*
G36*
G01X1191070D02*
X1193890D01*
G02X1194092Y1587998I0J-202D01*
G01Y1587378D01*
G03X1194142Y1587246I200J0D01*
G02Y1584330I-1661J-1458D01*
G03X1194092Y1584198I150J-132D01*
G01Y1582260D01*
G03X1194142Y1582128I200J0D01*
G02Y1579212I-1661J-1458D01*
G03X1194092Y1579080I150J-132D01*
G01Y1578460D01*
G02X1193890Y1578258I-202J0D01*
G01X1191070D01*
G02X1190868Y1578460I0J202D01*
G01Y1579080D01*
G03X1190818Y1579212I-200J0D01*
G02Y1582128I1661J1458D01*
G03X1190868Y1582260I-150J132D01*
G01Y1584198D01*
G03X1190818Y1584330I-200J0D01*
G02Y1587246I1661J1458D01*
G03X1190868Y1587378I-150J132D01*
G01Y1587998D01*
G02X1191070Y1588200I202J0D01*
G37*
G36*
G01X1312330D02*
X1315150D01*
G02X1315352Y1587998I0J-202D01*
G01Y1587378D01*
G03X1315402Y1587246I200J0D01*
G02Y1584330I-1661J-1458D01*
G03X1315352Y1584198I150J-132D01*
G01Y1582260D01*
G03X1315402Y1582128I200J0D01*
G02Y1579212I-1661J-1458D01*
G03X1315352Y1579080I150J-132D01*
G01Y1578460D01*
G02X1315150Y1578258I-202J0D01*
G01X1312330D01*
G02X1312128Y1578460I0J202D01*
G01Y1579080D01*
G03X1312078Y1579212I-200J0D01*
G02Y1582128I1661J1458D01*
G03X1312128Y1582260I-150J132D01*
G01Y1584198D01*
G03X1312078Y1584330I-200J0D01*
G02Y1587246I1661J1458D01*
G03X1312128Y1587378I-150J132D01*
G01Y1587998D01*
G02X1312330Y1588200I202J0D01*
G37*
G36*
G01X1346976D02*
X1349796D01*
G02X1349998Y1587998I0J-202D01*
G01Y1587378D01*
G03X1350048Y1587246I200J0D01*
G02Y1584330I-1661J-1458D01*
G03X1349998Y1584198I150J-132D01*
G01Y1582260D01*
G03X1350048Y1582128I200J0D01*
G02Y1579212I-1661J-1458D01*
G03X1349998Y1579080I150J-132D01*
G01Y1578460D01*
G02X1349796Y1578258I-202J0D01*
G01X1346976D01*
G02X1346774Y1578460I0J202D01*
G01Y1579080D01*
G03X1346724Y1579212I-200J0D01*
G02Y1582128I1661J1458D01*
G03X1346774Y1582260I-150J132D01*
G01Y1584198D01*
G03X1346724Y1584330I-200J0D01*
G02Y1587246I1661J1458D01*
G03X1346774Y1587378I-150J132D01*
G01Y1587998D01*
G02X1346976Y1588200I202J0D01*
G37*
G36*
G01X1658786D02*
X1661606D01*
G02X1661808Y1587998I0J-202D01*
G01Y1587378D01*
G03X1661858Y1587246I200J0D01*
G02Y1584330I-1661J-1458D01*
G03X1661808Y1584198I150J-132D01*
G01Y1582260D01*
G03X1661858Y1582128I200J0D01*
G02Y1579212I-1661J-1458D01*
G03X1661808Y1579080I150J-132D01*
G01Y1578460D01*
G02X1661606Y1578258I-202J0D01*
G01X1658786D01*
G02X1658584Y1578460I0J202D01*
G01Y1579080D01*
G03X1658534Y1579212I-200J0D01*
G02Y1582128I1661J1458D01*
G03X1658584Y1582260I-150J132D01*
G01Y1584198D01*
G03X1658534Y1584330I-200J0D01*
G02Y1587246I1661J1458D01*
G03X1658584Y1587378I-150J132D01*
G01Y1587998D01*
G02X1658786Y1588200I202J0D01*
G37*
G36*
G01X1693432D02*
X1696252D01*
G02X1696454Y1587998I0J-202D01*
G01Y1587378D01*
G03X1696504Y1587246I200J0D01*
G02Y1584330I-1661J-1458D01*
G03X1696454Y1584198I150J-132D01*
G01Y1582260D01*
G03X1696504Y1582128I200J0D01*
G02Y1579212I-1661J-1458D01*
G03X1696454Y1579080I150J-132D01*
G01Y1578460D01*
G02X1696252Y1578258I-202J0D01*
G01X1693432D01*
G02X1693230Y1578460I0J202D01*
G01Y1579080D01*
G03X1693180Y1579212I-200J0D01*
G02Y1582128I1661J1458D01*
G03X1693230Y1582260I-150J132D01*
G01Y1584198D01*
G03X1693180Y1584330I-200J0D01*
G02Y1587246I1661J1458D01*
G03X1693230Y1587378I-150J132D01*
G01Y1587998D01*
G02X1693432Y1588200I202J0D01*
G37*
G36*
G01X117133D02*
X119953D01*
G02X120156Y1587998I1J-202D01*
G01Y1587376D01*
G03X120206Y1587244I200J0D01*
G02Y1584332I-1664J-1456D01*
G03X120156Y1584200I150J-132D01*
G01Y1582258D01*
G03X120206Y1582126I200J0D01*
G02Y1579214I-1664J-1456D01*
G03X120156Y1579082I150J-132D01*
G01Y1578460D01*
G02X119953Y1578258I-203J1D01*
G01X117133D01*
G02X116930Y1578460I-1J202D01*
G01Y1579082D01*
G03X116880Y1579214I-200J0D01*
G02Y1582126I1664J1456D01*
G03X116930Y1582258I-150J132D01*
G01Y1584200D01*
G03X116880Y1584332I-200J0D01*
G02Y1587244I1664J1456D01*
G03X116930Y1587376I-150J132D01*
G01Y1587998D01*
G02X117133Y1588200I203J-1D01*
G37*
G36*
G01X151779D02*
X154599D01*
G02X154802Y1587998I1J-202D01*
G01Y1587376D01*
G03X154852Y1587244I200J0D01*
G02Y1584332I-1664J-1456D01*
G03X154802Y1584200I150J-132D01*
G01Y1582258D01*
G03X154852Y1582126I200J0D01*
G02Y1579214I-1664J-1456D01*
G03X154802Y1579082I150J-132D01*
G01Y1578460D01*
G02X154599Y1578258I-203J1D01*
G01X151779D01*
G02X151576Y1578460I-1J202D01*
G01Y1579082D01*
G03X151526Y1579214I-200J0D01*
G02Y1582126I1664J1456D01*
G03X151576Y1582258I-150J132D01*
G01Y1584200D01*
G03X151526Y1584332I-200J0D01*
G02Y1587244I1664J1456D01*
G03X151576Y1587376I-150J132D01*
G01Y1587998D01*
G02X151779Y1588200I203J-1D01*
G37*
G36*
G01X290361D02*
X293181D01*
G02X293384Y1587998I1J-202D01*
G01Y1587376D01*
G03X293434Y1587244I200J0D01*
G02Y1584332I-1664J-1456D01*
G03X293384Y1584200I150J-132D01*
G01Y1582258D01*
G03X293434Y1582126I200J0D01*
G02Y1579214I-1664J-1456D01*
G03X293384Y1579082I150J-132D01*
G01Y1578460D01*
G02X293181Y1578258I-203J1D01*
G01X290361D01*
G02X290158Y1578460I-1J202D01*
G01Y1579082D01*
G03X290108Y1579214I-200J0D01*
G02Y1582126I1664J1456D01*
G03X290158Y1582258I-150J132D01*
G01Y1584200D01*
G03X290108Y1584332I-200J0D01*
G02Y1587244I1664J1456D01*
G03X290158Y1587376I-150J132D01*
G01Y1587998D01*
G02X290361Y1588200I203J-1D01*
G37*
G36*
G01X325007D02*
X327827D01*
G02X328030Y1587998I1J-202D01*
G01Y1587376D01*
G03X328080Y1587244I200J0D01*
G02Y1584332I-1664J-1456D01*
G03X328030Y1584200I150J-132D01*
G01Y1582258D01*
G03X328080Y1582126I200J0D01*
G02Y1579214I-1664J-1456D01*
G03X328030Y1579082I150J-132D01*
G01Y1578460D01*
G02X327827Y1578258I-203J1D01*
G01X325007D01*
G02X324804Y1578460I-1J202D01*
G01Y1579082D01*
G03X324754Y1579214I-200J0D01*
G02Y1582126I1664J1456D01*
G03X324804Y1582258I-150J132D01*
G01Y1584200D01*
G03X324754Y1584332I-200J0D01*
G02Y1587244I1664J1456D01*
G03X324804Y1587376I-150J132D01*
G01Y1587998D01*
G02X325007Y1588200I203J-1D01*
G37*
G36*
G01X515559D02*
X518379D01*
G02X518582Y1587998I1J-202D01*
G01Y1587376D01*
G03X518632Y1587244I200J0D01*
G02Y1584332I-1664J-1456D01*
G03X518582Y1584200I150J-132D01*
G01Y1582258D01*
G03X518632Y1582126I200J0D01*
G02Y1579214I-1664J-1456D01*
G03X518582Y1579082I150J-132D01*
G01Y1578460D01*
G02X518379Y1578258I-203J1D01*
G01X515559D01*
G02X515356Y1578460I-1J202D01*
G01Y1579082D01*
G03X515306Y1579214I-200J0D01*
G02Y1582126I1664J1456D01*
G03X515356Y1582258I-150J132D01*
G01Y1584200D01*
G03X515306Y1584332I-200J0D01*
G02Y1587244I1664J1456D01*
G03X515356Y1587376I-150J132D01*
G01Y1587998D01*
G02X515559Y1588200I203J-1D01*
G37*
G36*
G01X654141D02*
X656961D01*
G02X657164Y1587998I1J-202D01*
G01Y1587376D01*
G03X657214Y1587244I200J0D01*
G02Y1584332I-1664J-1456D01*
G03X657164Y1584200I150J-132D01*
G01Y1582258D01*
G03X657214Y1582126I200J0D01*
G02Y1579214I-1664J-1456D01*
G03X657164Y1579082I150J-132D01*
G01Y1578460D01*
G02X656961Y1578258I-203J1D01*
G01X654141D01*
G02X653938Y1578460I-1J202D01*
G01Y1579082D01*
G03X653888Y1579214I-200J0D01*
G02Y1582126I1664J1456D01*
G03X653938Y1582258I-150J132D01*
G01Y1584200D01*
G03X653888Y1584332I-200J0D01*
G02Y1587244I1664J1456D01*
G03X653938Y1587376I-150J132D01*
G01Y1587998D01*
G02X654141Y1588200I203J-1D01*
G37*
G36*
G01X688787D02*
X691607D01*
G02X691810Y1587998I1J-202D01*
G01Y1587376D01*
G03X691860Y1587244I200J0D01*
G02Y1584332I-1664J-1456D01*
G03X691810Y1584200I150J-132D01*
G01Y1582258D01*
G03X691860Y1582126I200J0D01*
G02Y1579214I-1664J-1456D01*
G03X691810Y1579082I150J-132D01*
G01Y1578460D01*
G02X691607Y1578258I-203J1D01*
G01X688787D01*
G02X688584Y1578460I-1J202D01*
G01Y1579082D01*
G03X688534Y1579214I-200J0D01*
G02Y1582126I1664J1456D01*
G03X688584Y1582258I-150J132D01*
G01Y1584200D01*
G03X688534Y1584332I-200J0D01*
G02Y1587244I1664J1456D01*
G03X688584Y1587376I-150J132D01*
G01Y1587998D01*
G02X688787Y1588200I203J-1D01*
G37*
G36*
G01X1139101D02*
X1141921D01*
G02X1142124Y1587998I1J-202D01*
G01Y1587376D01*
G03X1142174Y1587244I200J0D01*
G02Y1584332I-1664J-1456D01*
G03X1142124Y1584200I150J-132D01*
G01Y1582258D01*
G03X1142174Y1582126I200J0D01*
G02Y1579214I-1664J-1456D01*
G03X1142124Y1579082I150J-132D01*
G01Y1578460D01*
G02X1141921Y1578258I-203J1D01*
G01X1139101D01*
G02X1138898Y1578460I-1J202D01*
G01Y1579082D01*
G03X1138848Y1579214I-200J0D01*
G02Y1582126I1664J1456D01*
G03X1138898Y1582258I-150J132D01*
G01Y1584200D01*
G03X1138848Y1584332I-200J0D01*
G02Y1587244I1664J1456D01*
G03X1138898Y1587376I-150J132D01*
G01Y1587998D01*
G02X1139101Y1588200I203J-1D01*
G37*
G36*
G01X1173747D02*
X1176567D01*
G02X1176770Y1587998I1J-202D01*
G01Y1587376D01*
G03X1176820Y1587244I200J0D01*
G02Y1584332I-1664J-1456D01*
G03X1176770Y1584200I150J-132D01*
G01Y1582258D01*
G03X1176820Y1582126I200J0D01*
G02Y1579214I-1664J-1456D01*
G03X1176770Y1579082I150J-132D01*
G01Y1578460D01*
G02X1176567Y1578258I-203J1D01*
G01X1173747D01*
G02X1173544Y1578460I-1J202D01*
G01Y1579082D01*
G03X1173494Y1579214I-200J0D01*
G02Y1582126I1664J1456D01*
G03X1173544Y1582258I-150J132D01*
G01Y1584200D01*
G03X1173494Y1584332I-200J0D01*
G02Y1587244I1664J1456D01*
G03X1173544Y1587376I-150J132D01*
G01Y1587998D01*
G02X1173747Y1588200I203J-1D01*
G37*
G36*
G01X1329653D02*
X1332473D01*
G02X1332676Y1587998I1J-202D01*
G01Y1587376D01*
G03X1332726Y1587244I200J0D01*
G02Y1584332I-1664J-1456D01*
G03X1332676Y1584200I150J-132D01*
G01Y1582258D01*
G03X1332726Y1582126I200J0D01*
G02Y1579214I-1664J-1456D01*
G03X1332676Y1579082I150J-132D01*
G01Y1578460D01*
G02X1332473Y1578258I-203J1D01*
G01X1329653D01*
G02X1329450Y1578460I-1J202D01*
G01Y1579082D01*
G03X1329400Y1579214I-200J0D01*
G02Y1582126I1664J1456D01*
G03X1329450Y1582258I-150J132D01*
G01Y1584200D01*
G03X1329400Y1584332I-200J0D01*
G02Y1587244I1664J1456D01*
G03X1329450Y1587376I-150J132D01*
G01Y1587998D01*
G02X1329653Y1588200I203J-1D01*
G37*
G36*
G01X1364299D02*
X1367119D01*
G02X1367322Y1587998I1J-202D01*
G01Y1587376D01*
G03X1367372Y1587244I200J0D01*
G02Y1584332I-1664J-1456D01*
G03X1367322Y1584200I150J-132D01*
G01Y1582258D01*
G03X1367372Y1582126I200J0D01*
G02Y1579214I-1664J-1456D01*
G03X1367322Y1579082I150J-132D01*
G01Y1578460D01*
G02X1367119Y1578258I-203J1D01*
G01X1364299D01*
G02X1364096Y1578460I-1J202D01*
G01Y1579082D01*
G03X1364046Y1579214I-200J0D01*
G02Y1582126I1664J1456D01*
G03X1364096Y1582258I-150J132D01*
G01Y1584200D01*
G03X1364046Y1584332I-200J0D01*
G02Y1587244I1664J1456D01*
G03X1364096Y1587376I-150J132D01*
G01Y1587998D01*
G02X1364299Y1588200I203J-1D01*
G37*
G36*
G01X1676109D02*
X1678929D01*
G02X1679132Y1587998I1J-202D01*
G01Y1587376D01*
G03X1679182Y1587244I200J0D01*
G02Y1584332I-1664J-1456D01*
G03X1679132Y1584200I150J-132D01*
G01Y1582258D01*
G03X1679182Y1582126I200J0D01*
G02Y1579214I-1664J-1456D01*
G03X1679132Y1579082I150J-132D01*
G01Y1578460D01*
G02X1678929Y1578258I-203J1D01*
G01X1676109D01*
G02X1675906Y1578460I-1J202D01*
G01Y1579082D01*
G03X1675856Y1579214I-200J0D01*
G02Y1582126I1664J1456D01*
G03X1675906Y1582258I-150J132D01*
G01Y1584200D01*
G03X1675856Y1584332I-200J0D01*
G02Y1587244I1664J1456D01*
G03X1675906Y1587376I-150J132D01*
G01Y1587998D01*
G02X1676109Y1588200I203J-1D01*
G37*
G36*
G01X1710755D02*
X1713575D01*
G02X1713778Y1587998I1J-202D01*
G01Y1587376D01*
G03X1713828Y1587244I200J0D01*
G02Y1584332I-1664J-1456D01*
G03X1713778Y1584200I150J-132D01*
G01Y1582258D01*
G03X1713828Y1582126I200J0D01*
G02Y1579214I-1664J-1456D01*
G03X1713778Y1579082I150J-132D01*
G01Y1578460D01*
G02X1713575Y1578258I-203J1D01*
G01X1710755D01*
G02X1710552Y1578460I-1J202D01*
G01Y1579082D01*
G03X1710502Y1579214I-200J0D01*
G02Y1582126I1664J1456D01*
G03X1710552Y1582258I-150J132D01*
G01Y1584200D01*
G03X1710502Y1584332I-200J0D01*
G02Y1587244I1664J1456D01*
G03X1710552Y1587376I-150J132D01*
G01Y1587998D01*
G02X1710755Y1588200I203J-1D01*
G37*
G36*
G01X108472Y1599224D02*
X111292D01*
G02X111494Y1599021I-1J-203D01*
G01Y1598401D01*
G03X111544Y1598269I200J0D01*
G02Y1595353I-1661J-1458D01*
G03X111494Y1595221I150J-132D01*
G01Y1593283D01*
G03X111544Y1593151I200J0D01*
G02Y1590235I-1661J-1458D01*
G03X111494Y1590103I150J-132D01*
G01Y1589483D01*
G02X111292Y1589280I-202J-1D01*
G01X108472D01*
G02X108270Y1589483I1J203D01*
G01Y1590103D01*
G03X108220Y1590235I-200J0D01*
G02Y1593151I1661J1458D01*
G03X108270Y1593283I-150J132D01*
G01Y1595221D01*
G03X108220Y1595353I-200J0D01*
G02Y1598269I1661J1458D01*
G03X108270Y1598401I-150J132D01*
G01Y1599021D01*
G02X108472Y1599224I202J1D01*
G37*
G36*
G01X125795D02*
X128615D01*
G02X128818Y1599021I0J-203D01*
G01Y1598399D01*
G03X128868Y1598267I200J0D01*
G02Y1595355I-1664J-1456D01*
G03X128818Y1595223I150J-132D01*
G01Y1593281D01*
G03X128868Y1593149I200J0D01*
G02Y1590237I-1664J-1456D01*
G03X128818Y1590105I150J-132D01*
G01Y1589483D01*
G02X128615Y1589280I-203J0D01*
G01X125795D01*
G02X125592Y1589483I0J203D01*
G01Y1590105D01*
G03X125542Y1590237I-200J0D01*
G02Y1593149I1664J1456D01*
G03X125592Y1593281I-150J132D01*
G01Y1595223D01*
G03X125542Y1595355I-200J0D01*
G02Y1598267I1664J1456D01*
G03X125592Y1598399I-150J132D01*
G01Y1599021D01*
G02X125795Y1599224I203J0D01*
G37*
G36*
G01X143118D02*
X145938D01*
G02X146140Y1599021I-1J-203D01*
G01Y1598401D01*
G03X146190Y1598269I200J0D01*
G02Y1595353I-1661J-1458D01*
G03X146140Y1595221I150J-132D01*
G01Y1593283D01*
G03X146190Y1593151I200J0D01*
G02Y1590235I-1661J-1458D01*
G03X146140Y1590103I150J-132D01*
G01Y1589483D01*
G02X145938Y1589280I-202J-1D01*
G01X143118D01*
G02X142916Y1589483I1J203D01*
G01Y1590103D01*
G03X142866Y1590235I-200J0D01*
G02Y1593151I1661J1458D01*
G03X142916Y1593283I-150J132D01*
G01Y1595221D01*
G03X142866Y1595353I-200J0D01*
G02Y1598269I1661J1458D01*
G03X142916Y1598401I-150J132D01*
G01Y1599021D01*
G02X143118Y1599224I202J1D01*
G37*
G36*
G01X160440D02*
X163260D01*
G02X163462Y1599021I-1J-203D01*
G01Y1598401D01*
G03X163512Y1598269I200J0D01*
G02Y1595353I-1661J-1458D01*
G03X163462Y1595221I150J-132D01*
G01Y1593283D01*
G03X163512Y1593151I200J0D01*
G02Y1590235I-1661J-1458D01*
G03X163462Y1590103I150J-132D01*
G01Y1589483D01*
G02X163260Y1589280I-202J-1D01*
G01X160440D01*
G02X160238Y1589483I1J203D01*
G01Y1590103D01*
G03X160188Y1590235I-200J0D01*
G02Y1593151I1661J1458D01*
G03X160238Y1593283I-150J132D01*
G01Y1595221D01*
G03X160188Y1595353I-200J0D01*
G02Y1598269I1661J1458D01*
G03X160238Y1598401I-150J132D01*
G01Y1599021D01*
G02X160440Y1599224I202J1D01*
G37*
G36*
G01X281700D02*
X284520D01*
G02X284722Y1599021I-1J-203D01*
G01Y1598401D01*
G03X284772Y1598269I200J0D01*
G02Y1595353I-1661J-1458D01*
G03X284722Y1595221I150J-132D01*
G01Y1593283D01*
G03X284772Y1593151I200J0D01*
G02Y1590235I-1661J-1458D01*
G03X284722Y1590103I150J-132D01*
G01Y1589483D01*
G02X284520Y1589280I-202J-1D01*
G01X281700D01*
G02X281498Y1589483I1J203D01*
G01Y1590103D01*
G03X281448Y1590235I-200J0D01*
G02Y1593151I1661J1458D01*
G03X281498Y1593283I-150J132D01*
G01Y1595221D01*
G03X281448Y1595353I-200J0D01*
G02Y1598269I1661J1458D01*
G03X281498Y1598401I-150J132D01*
G01Y1599021D01*
G02X281700Y1599224I202J1D01*
G37*
G36*
G01X299023D02*
X301843D01*
G02X302046Y1599021I0J-203D01*
G01Y1598399D01*
G03X302096Y1598267I200J0D01*
G02Y1595355I-1664J-1456D01*
G03X302046Y1595223I150J-132D01*
G01Y1593281D01*
G03X302096Y1593149I200J0D01*
G02Y1590237I-1664J-1456D01*
G03X302046Y1590105I150J-132D01*
G01Y1589483D01*
G02X301843Y1589280I-203J0D01*
G01X299023D01*
G02X298820Y1589483I0J203D01*
G01Y1590105D01*
G03X298770Y1590237I-200J0D01*
G02Y1593149I1664J1456D01*
G03X298820Y1593281I-150J132D01*
G01Y1595223D01*
G03X298770Y1595355I-200J0D01*
G02Y1598267I1664J1456D01*
G03X298820Y1598399I-150J132D01*
G01Y1599021D01*
G02X299023Y1599224I203J0D01*
G37*
G36*
G01X316346D02*
X319166D01*
G02X319368Y1599021I-1J-203D01*
G01Y1598401D01*
G03X319418Y1598269I200J0D01*
G02Y1595353I-1661J-1458D01*
G03X319368Y1595221I150J-132D01*
G01Y1593283D01*
G03X319418Y1593151I200J0D01*
G02Y1590235I-1661J-1458D01*
G03X319368Y1590103I150J-132D01*
G01Y1589483D01*
G02X319166Y1589280I-202J-1D01*
G01X316346D01*
G02X316144Y1589483I1J203D01*
G01Y1590103D01*
G03X316094Y1590235I-200J0D01*
G02Y1593151I1661J1458D01*
G03X316144Y1593283I-150J132D01*
G01Y1595221D01*
G03X316094Y1595353I-200J0D01*
G02Y1598269I1661J1458D01*
G03X316144Y1598401I-150J132D01*
G01Y1599021D01*
G02X316346Y1599224I202J1D01*
G37*
G36*
G01X333668D02*
X336488D01*
G02X336690Y1599021I-1J-203D01*
G01Y1598401D01*
G03X336740Y1598269I200J0D01*
G02Y1595353I-1661J-1458D01*
G03X336690Y1595221I150J-132D01*
G01Y1593283D01*
G03X336740Y1593151I200J0D01*
G02Y1590235I-1661J-1458D01*
G03X336690Y1590103I150J-132D01*
G01Y1589483D01*
G02X336488Y1589280I-202J-1D01*
G01X333668D01*
G02X333466Y1589483I1J203D01*
G01Y1590103D01*
G03X333416Y1590235I-200J0D01*
G02Y1593151I1661J1458D01*
G03X333466Y1593283I-150J132D01*
G01Y1595221D01*
G03X333416Y1595353I-200J0D01*
G02Y1598269I1661J1458D01*
G03X333466Y1598401I-150J132D01*
G01Y1599021D01*
G02X333668Y1599224I202J1D01*
G37*
G36*
G01X628157D02*
X630977D01*
G02X631180Y1599021I0J-203D01*
G01Y1598399D01*
G03X631230Y1598267I200J0D01*
G02Y1595355I-1664J-1456D01*
G03X631180Y1595223I150J-132D01*
G01Y1593281D01*
G03X631230Y1593149I200J0D01*
G02Y1590237I-1664J-1456D01*
G03X631180Y1590105I150J-132D01*
G01Y1589483D01*
G02X630977Y1589280I-203J0D01*
G01X628157D01*
G02X627954Y1589483I0J203D01*
G01Y1590105D01*
G03X627904Y1590237I-200J0D01*
G02Y1593149I1664J1456D01*
G03X627954Y1593281I-150J132D01*
G01Y1595223D01*
G03X627904Y1595355I-200J0D01*
G02Y1598267I1664J1456D01*
G03X627954Y1598399I-150J132D01*
G01Y1599021D01*
G02X628157Y1599224I203J0D01*
G37*
G36*
G01X645480D02*
X648300D01*
G02X648502Y1599021I-1J-203D01*
G01Y1598401D01*
G03X648552Y1598269I200J0D01*
G02Y1595353I-1661J-1458D01*
G03X648502Y1595221I150J-132D01*
G01Y1593283D01*
G03X648552Y1593151I200J0D01*
G02Y1590235I-1661J-1458D01*
G03X648502Y1590103I150J-132D01*
G01Y1589483D01*
G02X648300Y1589280I-202J-1D01*
G01X645480D01*
G02X645278Y1589483I1J203D01*
G01Y1590103D01*
G03X645228Y1590235I-200J0D01*
G02Y1593151I1661J1458D01*
G03X645278Y1593283I-150J132D01*
G01Y1595221D01*
G03X645228Y1595353I-200J0D01*
G02Y1598269I1661J1458D01*
G03X645278Y1598401I-150J132D01*
G01Y1599021D01*
G02X645480Y1599224I202J1D01*
G37*
G36*
G01X662803D02*
X665623D01*
G02X665826Y1599021I0J-203D01*
G01Y1598399D01*
G03X665876Y1598267I200J0D01*
G02Y1595355I-1664J-1456D01*
G03X665826Y1595223I150J-132D01*
G01Y1593281D01*
G03X665876Y1593149I200J0D01*
G02Y1590237I-1664J-1456D01*
G03X665826Y1590105I150J-132D01*
G01Y1589483D01*
G02X665623Y1589280I-203J0D01*
G01X662803D01*
G02X662600Y1589483I0J203D01*
G01Y1590105D01*
G03X662550Y1590237I-200J0D01*
G02Y1593149I1664J1456D01*
G03X662600Y1593281I-150J132D01*
G01Y1595223D01*
G03X662550Y1595355I-200J0D01*
G02Y1598267I1664J1456D01*
G03X662600Y1598399I-150J132D01*
G01Y1599021D01*
G02X662803Y1599224I203J0D01*
G37*
G36*
G01X680125D02*
X682945D01*
G02X683148Y1599021I0J-203D01*
G01Y1598399D01*
G03X683198Y1598267I200J0D01*
G02Y1595355I-1664J-1456D01*
G03X683148Y1595223I150J-132D01*
G01Y1593281D01*
G03X683198Y1593149I200J0D01*
G02Y1590237I-1664J-1456D01*
G03X683148Y1590105I150J-132D01*
G01Y1589483D01*
G02X682945Y1589280I-203J0D01*
G01X680125D01*
G02X679922Y1589483I0J203D01*
G01Y1590105D01*
G03X679872Y1590237I-200J0D01*
G02Y1593149I1664J1456D01*
G03X679922Y1593281I-150J132D01*
G01Y1595223D01*
G03X679872Y1595355I-200J0D01*
G02Y1598267I1664J1456D01*
G03X679922Y1598399I-150J132D01*
G01Y1599021D01*
G02X680125Y1599224I203J0D01*
G37*
G36*
G01X1130440D02*
X1133260D01*
G02X1133462Y1599021I-1J-203D01*
G01Y1598401D01*
G03X1133512Y1598269I200J0D01*
G02Y1595353I-1661J-1458D01*
G03X1133462Y1595221I150J-132D01*
G01Y1593283D01*
G03X1133512Y1593151I200J0D01*
G02Y1590235I-1661J-1458D01*
G03X1133462Y1590103I150J-132D01*
G01Y1589483D01*
G02X1133260Y1589280I-202J-1D01*
G01X1130440D01*
G02X1130238Y1589483I1J203D01*
G01Y1590103D01*
G03X1130188Y1590235I-200J0D01*
G02Y1593151I1661J1458D01*
G03X1130238Y1593283I-150J132D01*
G01Y1595221D01*
G03X1130188Y1595353I-200J0D01*
G02Y1598269I1661J1458D01*
G03X1130238Y1598401I-150J132D01*
G01Y1599021D01*
G02X1130440Y1599224I202J1D01*
G37*
G36*
G01X1147763D02*
X1150583D01*
G02X1150786Y1599021I0J-203D01*
G01Y1598399D01*
G03X1150836Y1598267I200J0D01*
G02Y1595355I-1664J-1456D01*
G03X1150786Y1595223I150J-132D01*
G01Y1593281D01*
G03X1150836Y1593149I200J0D01*
G02Y1590237I-1664J-1456D01*
G03X1150786Y1590105I150J-132D01*
G01Y1589483D01*
G02X1150583Y1589280I-203J0D01*
G01X1147763D01*
G02X1147560Y1589483I0J203D01*
G01Y1590105D01*
G03X1147510Y1590237I-200J0D01*
G02Y1593149I1664J1456D01*
G03X1147560Y1593281I-150J132D01*
G01Y1595223D01*
G03X1147510Y1595355I-200J0D01*
G02Y1598267I1664J1456D01*
G03X1147560Y1598399I-150J132D01*
G01Y1599021D01*
G02X1147763Y1599224I203J0D01*
G37*
G36*
G01X1165086D02*
X1167906D01*
G02X1168108Y1599021I-1J-203D01*
G01Y1598401D01*
G03X1168158Y1598269I200J0D01*
G02Y1595353I-1661J-1458D01*
G03X1168108Y1595221I150J-132D01*
G01Y1593283D01*
G03X1168158Y1593151I200J0D01*
G02Y1590235I-1661J-1458D01*
G03X1168108Y1590103I150J-132D01*
G01Y1589483D01*
G02X1167906Y1589280I-202J-1D01*
G01X1165086D01*
G02X1164884Y1589483I1J203D01*
G01Y1590103D01*
G03X1164834Y1590235I-200J0D01*
G02Y1593151I1661J1458D01*
G03X1164884Y1593283I-150J132D01*
G01Y1595221D01*
G03X1164834Y1595353I-200J0D01*
G02Y1598269I1661J1458D01*
G03X1164884Y1598401I-150J132D01*
G01Y1599021D01*
G02X1165086Y1599224I202J1D01*
G37*
G36*
G01X1182408D02*
X1185228D01*
G02X1185430Y1599021I-1J-203D01*
G01Y1598401D01*
G03X1185480Y1598269I200J0D01*
G02Y1595353I-1661J-1458D01*
G03X1185430Y1595221I150J-132D01*
G01Y1593283D01*
G03X1185480Y1593151I200J0D01*
G02Y1590235I-1661J-1458D01*
G03X1185430Y1590103I150J-132D01*
G01Y1589483D01*
G02X1185228Y1589280I-202J-1D01*
G01X1182408D01*
G02X1182206Y1589483I1J203D01*
G01Y1590103D01*
G03X1182156Y1590235I-200J0D01*
G02Y1593151I1661J1458D01*
G03X1182206Y1593283I-150J132D01*
G01Y1595221D01*
G03X1182156Y1595353I-200J0D01*
G02Y1598269I1661J1458D01*
G03X1182206Y1598401I-150J132D01*
G01Y1599021D01*
G02X1182408Y1599224I202J1D01*
G37*
G36*
G01X1303669D02*
X1306489D01*
G02X1306692Y1599021I0J-203D01*
G01Y1598399D01*
G03X1306742Y1598267I200J0D01*
G02Y1595355I-1664J-1456D01*
G03X1306692Y1595223I150J-132D01*
G01Y1593281D01*
G03X1306742Y1593149I200J0D01*
G02Y1590237I-1664J-1456D01*
G03X1306692Y1590105I150J-132D01*
G01Y1589483D01*
G02X1306489Y1589280I-203J0D01*
G01X1303669D01*
G02X1303466Y1589483I0J203D01*
G01Y1590105D01*
G03X1303416Y1590237I-200J0D01*
G02Y1593149I1664J1456D01*
G03X1303466Y1593281I-150J132D01*
G01Y1595223D01*
G03X1303416Y1595355I-200J0D01*
G02Y1598267I1664J1456D01*
G03X1303466Y1598399I-150J132D01*
G01Y1599021D01*
G02X1303669Y1599224I203J0D01*
G37*
G36*
G01X1320992D02*
X1323812D01*
G02X1324014Y1599021I-1J-203D01*
G01Y1598401D01*
G03X1324064Y1598269I200J0D01*
G02Y1595353I-1661J-1458D01*
G03X1324014Y1595221I150J-132D01*
G01Y1593283D01*
G03X1324064Y1593151I200J0D01*
G02Y1590235I-1661J-1458D01*
G03X1324014Y1590103I150J-132D01*
G01Y1589483D01*
G02X1323812Y1589280I-202J-1D01*
G01X1320992D01*
G02X1320790Y1589483I1J203D01*
G01Y1590103D01*
G03X1320740Y1590235I-200J0D01*
G02Y1593151I1661J1458D01*
G03X1320790Y1593283I-150J132D01*
G01Y1595221D01*
G03X1320740Y1595353I-200J0D01*
G02Y1598269I1661J1458D01*
G03X1320790Y1598401I-150J132D01*
G01Y1599021D01*
G02X1320992Y1599224I202J1D01*
G37*
G36*
G01X1338315D02*
X1341135D01*
G02X1341338Y1599021I0J-203D01*
G01Y1598399D01*
G03X1341388Y1598267I200J0D01*
G02Y1595355I-1664J-1456D01*
G03X1341338Y1595223I150J-132D01*
G01Y1593281D01*
G03X1341388Y1593149I200J0D01*
G02Y1590237I-1664J-1456D01*
G03X1341338Y1590105I150J-132D01*
G01Y1589483D01*
G02X1341135Y1589280I-203J0D01*
G01X1338315D01*
G02X1338112Y1589483I0J203D01*
G01Y1590105D01*
G03X1338062Y1590237I-200J0D01*
G02Y1593149I1664J1456D01*
G03X1338112Y1593281I-150J132D01*
G01Y1595223D01*
G03X1338062Y1595355I-200J0D01*
G02Y1598267I1664J1456D01*
G03X1338112Y1598399I-150J132D01*
G01Y1599021D01*
G02X1338315Y1599224I203J0D01*
G37*
G36*
G01X1355637D02*
X1358457D01*
G02X1358660Y1599021I0J-203D01*
G01Y1598399D01*
G03X1358710Y1598267I200J0D01*
G02Y1595355I-1664J-1456D01*
G03X1358660Y1595223I150J-132D01*
G01Y1593281D01*
G03X1358710Y1593149I200J0D01*
G02Y1590237I-1664J-1456D01*
G03X1358660Y1590105I150J-132D01*
G01Y1589483D01*
G02X1358457Y1589280I-203J0D01*
G01X1355637D01*
G02X1355434Y1589483I0J203D01*
G01Y1590105D01*
G03X1355384Y1590237I-200J0D01*
G02Y1593149I1664J1456D01*
G03X1355434Y1593281I-150J132D01*
G01Y1595223D01*
G03X1355384Y1595355I-200J0D01*
G02Y1598267I1664J1456D01*
G03X1355434Y1598399I-150J132D01*
G01Y1599021D01*
G02X1355637Y1599224I203J0D01*
G37*
G36*
G01X1476897D02*
X1479717D01*
G02X1479920Y1599021I0J-203D01*
G01Y1598399D01*
G03X1479970Y1598267I200J0D01*
G02Y1595355I-1664J-1456D01*
G03X1479920Y1595223I150J-132D01*
G01Y1593281D01*
G03X1479970Y1593149I200J0D01*
G02Y1590237I-1664J-1456D01*
G03X1479920Y1590105I150J-132D01*
G01Y1589483D01*
G02X1479717Y1589280I-203J0D01*
G01X1476897D01*
G02X1476694Y1589483I0J203D01*
G01Y1590105D01*
G03X1476644Y1590237I-200J0D01*
G02Y1593149I1664J1456D01*
G03X1476694Y1593281I-150J132D01*
G01Y1595223D01*
G03X1476644Y1595355I-200J0D01*
G02Y1598267I1664J1456D01*
G03X1476694Y1598399I-150J132D01*
G01Y1599021D01*
G02X1476897Y1599224I203J0D01*
G37*
G36*
G01X1650125D02*
X1652945D01*
G02X1653148Y1599021I0J-203D01*
G01Y1598399D01*
G03X1653198Y1598267I200J0D01*
G02Y1595355I-1664J-1456D01*
G03X1653148Y1595223I150J-132D01*
G01Y1593281D01*
G03X1653198Y1593149I200J0D01*
G02Y1590237I-1664J-1456D01*
G03X1653148Y1590105I150J-132D01*
G01Y1589483D01*
G02X1652945Y1589280I-203J0D01*
G01X1650125D01*
G02X1649922Y1589483I0J203D01*
G01Y1590105D01*
G03X1649872Y1590237I-200J0D01*
G02Y1593149I1664J1456D01*
G03X1649922Y1593281I-150J132D01*
G01Y1595223D01*
G03X1649872Y1595355I-200J0D01*
G02Y1598267I1664J1456D01*
G03X1649922Y1598399I-150J132D01*
G01Y1599021D01*
G02X1650125Y1599224I203J0D01*
G37*
G36*
G01X1667448D02*
X1670268D01*
G02X1670470Y1599021I-1J-203D01*
G01Y1598401D01*
G03X1670520Y1598269I200J0D01*
G02Y1595353I-1661J-1458D01*
G03X1670470Y1595221I150J-132D01*
G01Y1593283D01*
G03X1670520Y1593151I200J0D01*
G02Y1590235I-1661J-1458D01*
G03X1670470Y1590103I150J-132D01*
G01Y1589483D01*
G02X1670268Y1589280I-202J-1D01*
G01X1667448D01*
G02X1667246Y1589483I1J203D01*
G01Y1590103D01*
G03X1667196Y1590235I-200J0D01*
G02Y1593151I1661J1458D01*
G03X1667246Y1593283I-150J132D01*
G01Y1595221D01*
G03X1667196Y1595353I-200J0D01*
G02Y1598269I1661J1458D01*
G03X1667246Y1598401I-150J132D01*
G01Y1599021D01*
G02X1667448Y1599224I202J1D01*
G37*
G36*
G01X1684771D02*
X1687591D01*
G02X1687794Y1599021I0J-203D01*
G01Y1598399D01*
G03X1687844Y1598267I200J0D01*
G02Y1595355I-1664J-1456D01*
G03X1687794Y1595223I150J-132D01*
G01Y1593281D01*
G03X1687844Y1593149I200J0D01*
G02Y1590237I-1664J-1456D01*
G03X1687794Y1590105I150J-132D01*
G01Y1589483D01*
G02X1687591Y1589280I-203J0D01*
G01X1684771D01*
G02X1684568Y1589483I0J203D01*
G01Y1590105D01*
G03X1684518Y1590237I-200J0D01*
G02Y1593149I1664J1456D01*
G03X1684568Y1593281I-150J132D01*
G01Y1595223D01*
G03X1684518Y1595355I-200J0D01*
G02Y1598267I1664J1456D01*
G03X1684568Y1598399I-150J132D01*
G01Y1599021D01*
G02X1684771Y1599224I203J0D01*
G37*
G36*
G01X1702093D02*
X1704913D01*
G02X1705116Y1599021I0J-203D01*
G01Y1598399D01*
G03X1705166Y1598267I200J0D01*
G02Y1595355I-1664J-1456D01*
G03X1705116Y1595223I150J-132D01*
G01Y1593281D01*
G03X1705166Y1593149I200J0D01*
G02Y1590237I-1664J-1456D01*
G03X1705116Y1590105I150J-132D01*
G01Y1589483D01*
G02X1704913Y1589280I-203J0D01*
G01X1702093D01*
G02X1701890Y1589483I0J203D01*
G01Y1590105D01*
G03X1701840Y1590237I-200J0D01*
G02Y1593149I1664J1456D01*
G03X1701890Y1593281I-150J132D01*
G01Y1595223D01*
G03X1701840Y1595355I-200J0D01*
G02Y1598267I1664J1456D01*
G03X1701890Y1598399I-150J132D01*
G01Y1599021D01*
G02X1702093Y1599224I203J0D01*
G37*
G36*
G01X134456Y1603554D02*
X137276D01*
G02X137478Y1603352I0J-202D01*
G01Y1602732D01*
G03X137528Y1602600I200J0D01*
G02Y1599684I-1661J-1458D01*
G03X137478Y1599552I150J-132D01*
G01Y1597614D01*
G03X137528Y1597482I200J0D01*
G02Y1594566I-1661J-1458D01*
G03X137478Y1594434I150J-132D01*
G01Y1593814D01*
G02X137276Y1593612I-202J0D01*
G01X134456D01*
G02X134254Y1593814I0J202D01*
G01Y1594434D01*
G03X134204Y1594566I-200J0D01*
G02Y1597482I1661J1458D01*
G03X134254Y1597614I-150J132D01*
G01Y1599552D01*
G03X134204Y1599684I-200J0D01*
G02Y1602600I1661J1458D01*
G03X134254Y1602732I-150J132D01*
G01Y1603352D01*
G02X134456Y1603554I202J0D01*
G37*
G36*
G01X169102D02*
X171922D01*
G02X172124Y1603352I0J-202D01*
G01Y1602732D01*
G03X172174Y1602600I200J0D01*
G02Y1599684I-1661J-1458D01*
G03X172124Y1599552I150J-132D01*
G01Y1597614D01*
G03X172174Y1597482I200J0D01*
G02Y1594566I-1661J-1458D01*
G03X172124Y1594434I150J-132D01*
G01Y1593814D01*
G02X171922Y1593612I-202J0D01*
G01X169102D01*
G02X168900Y1593814I0J202D01*
G01Y1594434D01*
G03X168850Y1594566I-200J0D01*
G02Y1597482I1661J1458D01*
G03X168900Y1597614I-150J132D01*
G01Y1599552D01*
G03X168850Y1599684I-200J0D01*
G02Y1602600I1661J1458D01*
G03X168900Y1602732I-150J132D01*
G01Y1603352D01*
G02X169102Y1603554I202J0D01*
G37*
G36*
G01X307684D02*
X310504D01*
G02X310706Y1603352I0J-202D01*
G01Y1602732D01*
G03X310756Y1602600I200J0D01*
G02Y1599684I-1661J-1458D01*
G03X310706Y1599552I150J-132D01*
G01Y1597614D01*
G03X310756Y1597482I200J0D01*
G02Y1594566I-1661J-1458D01*
G03X310706Y1594434I150J-132D01*
G01Y1593814D01*
G02X310504Y1593612I-202J0D01*
G01X307684D01*
G02X307482Y1593814I0J202D01*
G01Y1594434D01*
G03X307432Y1594566I-200J0D01*
G02Y1597482I1661J1458D01*
G03X307482Y1597614I-150J132D01*
G01Y1599552D01*
G03X307432Y1599684I-200J0D01*
G02Y1602600I1661J1458D01*
G03X307482Y1602732I-150J132D01*
G01Y1603352D01*
G02X307684Y1603554I202J0D01*
G37*
G36*
G01X342330D02*
X345150D01*
G02X345352Y1603352I0J-202D01*
G01Y1602732D01*
G03X345402Y1602600I200J0D01*
G02Y1599684I-1661J-1458D01*
G03X345352Y1599552I150J-132D01*
G01Y1597614D01*
G03X345402Y1597482I200J0D01*
G02Y1594566I-1661J-1458D01*
G03X345352Y1594434I150J-132D01*
G01Y1593814D01*
G02X345150Y1593612I-202J0D01*
G01X342330D01*
G02X342128Y1593814I0J202D01*
G01Y1594434D01*
G03X342078Y1594566I-200J0D01*
G02Y1597482I1661J1458D01*
G03X342128Y1597614I-150J132D01*
G01Y1599552D01*
G03X342078Y1599684I-200J0D01*
G02Y1602600I1661J1458D01*
G03X342128Y1602732I-150J132D01*
G01Y1603352D01*
G02X342330Y1603554I202J0D01*
G37*
G36*
G01X636818D02*
X639638D01*
G02X639840Y1603352I0J-202D01*
G01Y1602732D01*
G03X639890Y1602600I200J0D01*
G02Y1599684I-1661J-1458D01*
G03X639840Y1599552I150J-132D01*
G01Y1597614D01*
G03X639890Y1597482I200J0D01*
G02Y1594566I-1661J-1458D01*
G03X639840Y1594434I150J-132D01*
G01Y1593814D01*
G02X639638Y1593612I-202J0D01*
G01X636818D01*
G02X636616Y1593814I0J202D01*
G01Y1594434D01*
G03X636566Y1594566I-200J0D01*
G02Y1597482I1661J1458D01*
G03X636616Y1597614I-150J132D01*
G01Y1599552D01*
G03X636566Y1599684I-200J0D01*
G02Y1602600I1661J1458D01*
G03X636616Y1602732I-150J132D01*
G01Y1603352D01*
G02X636818Y1603554I202J0D01*
G37*
G36*
G01X671464D02*
X674284D01*
G02X674486Y1603352I0J-202D01*
G01Y1602732D01*
G03X674536Y1602600I200J0D01*
G02Y1599684I-1661J-1458D01*
G03X674486Y1599552I150J-132D01*
G01Y1597614D01*
G03X674536Y1597482I200J0D01*
G02Y1594566I-1661J-1458D01*
G03X674486Y1594434I150J-132D01*
G01Y1593814D01*
G02X674284Y1593612I-202J0D01*
G01X671464D01*
G02X671262Y1593814I0J202D01*
G01Y1594434D01*
G03X671212Y1594566I-200J0D01*
G02Y1597482I1661J1458D01*
G03X671262Y1597614I-150J132D01*
G01Y1599552D01*
G03X671212Y1599684I-200J0D01*
G02Y1602600I1661J1458D01*
G03X671262Y1602732I-150J132D01*
G01Y1603352D01*
G02X671464Y1603554I202J0D01*
G37*
G36*
G01X1156424D02*
X1159244D01*
G02X1159446Y1603352I0J-202D01*
G01Y1602732D01*
G03X1159496Y1602600I200J0D01*
G02Y1599684I-1661J-1458D01*
G03X1159446Y1599552I150J-132D01*
G01Y1597614D01*
G03X1159496Y1597482I200J0D01*
G02Y1594566I-1661J-1458D01*
G03X1159446Y1594434I150J-132D01*
G01Y1593814D01*
G02X1159244Y1593612I-202J0D01*
G01X1156424D01*
G02X1156222Y1593814I0J202D01*
G01Y1594434D01*
G03X1156172Y1594566I-200J0D01*
G02Y1597482I1661J1458D01*
G03X1156222Y1597614I-150J132D01*
G01Y1599552D01*
G03X1156172Y1599684I-200J0D01*
G02Y1602600I1661J1458D01*
G03X1156222Y1602732I-150J132D01*
G01Y1603352D01*
G02X1156424Y1603554I202J0D01*
G37*
G36*
G01X1191070D02*
X1193890D01*
G02X1194092Y1603352I0J-202D01*
G01Y1602732D01*
G03X1194142Y1602600I200J0D01*
G02Y1599684I-1661J-1458D01*
G03X1194092Y1599552I150J-132D01*
G01Y1597614D01*
G03X1194142Y1597482I200J0D01*
G02Y1594566I-1661J-1458D01*
G03X1194092Y1594434I150J-132D01*
G01Y1593814D01*
G02X1193890Y1593612I-202J0D01*
G01X1191070D01*
G02X1190868Y1593814I0J202D01*
G01Y1594434D01*
G03X1190818Y1594566I-200J0D01*
G02Y1597482I1661J1458D01*
G03X1190868Y1597614I-150J132D01*
G01Y1599552D01*
G03X1190818Y1599684I-200J0D01*
G02Y1602600I1661J1458D01*
G03X1190868Y1602732I-150J132D01*
G01Y1603352D01*
G02X1191070Y1603554I202J0D01*
G37*
G36*
G01X1312330D02*
X1315150D01*
G02X1315352Y1603352I0J-202D01*
G01Y1602732D01*
G03X1315402Y1602600I200J0D01*
G02Y1599684I-1661J-1458D01*
G03X1315352Y1599552I150J-132D01*
G01Y1597614D01*
G03X1315402Y1597482I200J0D01*
G02Y1594566I-1661J-1458D01*
G03X1315352Y1594434I150J-132D01*
G01Y1593814D01*
G02X1315150Y1593612I-202J0D01*
G01X1312330D01*
G02X1312128Y1593814I0J202D01*
G01Y1594434D01*
G03X1312078Y1594566I-200J0D01*
G02Y1597482I1661J1458D01*
G03X1312128Y1597614I-150J132D01*
G01Y1599552D01*
G03X1312078Y1599684I-200J0D01*
G02Y1602600I1661J1458D01*
G03X1312128Y1602732I-150J132D01*
G01Y1603352D01*
G02X1312330Y1603554I202J0D01*
G37*
G36*
G01X1346976D02*
X1349796D01*
G02X1349998Y1603352I0J-202D01*
G01Y1602732D01*
G03X1350048Y1602600I200J0D01*
G02Y1599684I-1661J-1458D01*
G03X1349998Y1599552I150J-132D01*
G01Y1597614D01*
G03X1350048Y1597482I200J0D01*
G02Y1594566I-1661J-1458D01*
G03X1349998Y1594434I150J-132D01*
G01Y1593814D01*
G02X1349796Y1593612I-202J0D01*
G01X1346976D01*
G02X1346774Y1593814I0J202D01*
G01Y1594434D01*
G03X1346724Y1594566I-200J0D01*
G02Y1597482I1661J1458D01*
G03X1346774Y1597614I-150J132D01*
G01Y1599552D01*
G03X1346724Y1599684I-200J0D01*
G02Y1602600I1661J1458D01*
G03X1346774Y1602732I-150J132D01*
G01Y1603352D01*
G02X1346976Y1603554I202J0D01*
G37*
G36*
G01X1658786D02*
X1661606D01*
G02X1661808Y1603352I0J-202D01*
G01Y1602732D01*
G03X1661858Y1602600I200J0D01*
G02Y1599684I-1661J-1458D01*
G03X1661808Y1599552I150J-132D01*
G01Y1597614D01*
G03X1661858Y1597482I200J0D01*
G02Y1594566I-1661J-1458D01*
G03X1661808Y1594434I150J-132D01*
G01Y1593814D01*
G02X1661606Y1593612I-202J0D01*
G01X1658786D01*
G02X1658584Y1593814I0J202D01*
G01Y1594434D01*
G03X1658534Y1594566I-200J0D01*
G02Y1597482I1661J1458D01*
G03X1658584Y1597614I-150J132D01*
G01Y1599552D01*
G03X1658534Y1599684I-200J0D01*
G02Y1602600I1661J1458D01*
G03X1658584Y1602732I-150J132D01*
G01Y1603352D01*
G02X1658786Y1603554I202J0D01*
G37*
G36*
G01X1693432D02*
X1696252D01*
G02X1696454Y1603352I0J-202D01*
G01Y1602732D01*
G03X1696504Y1602600I200J0D01*
G02Y1599684I-1661J-1458D01*
G03X1696454Y1599552I150J-132D01*
G01Y1597614D01*
G03X1696504Y1597482I200J0D01*
G02Y1594566I-1661J-1458D01*
G03X1696454Y1594434I150J-132D01*
G01Y1593814D01*
G02X1696252Y1593612I-202J0D01*
G01X1693432D01*
G02X1693230Y1593814I0J202D01*
G01Y1594434D01*
G03X1693180Y1594566I-200J0D01*
G02Y1597482I1661J1458D01*
G03X1693230Y1597614I-150J132D01*
G01Y1599552D01*
G03X1693180Y1599684I-200J0D01*
G02Y1602600I1661J1458D01*
G03X1693230Y1602732I-150J132D01*
G01Y1603352D01*
G02X1693432Y1603554I202J0D01*
G37*
G36*
G01X117133D02*
X119953D01*
G02X120156Y1603352I1J-202D01*
G01Y1602730D01*
G03X120206Y1602598I200J0D01*
G02Y1599686I-1664J-1456D01*
G03X120156Y1599554I150J-132D01*
G01Y1597612D01*
G03X120206Y1597480I200J0D01*
G02Y1594568I-1664J-1456D01*
G03X120156Y1594436I150J-132D01*
G01Y1593814D01*
G02X119953Y1593612I-203J1D01*
G01X117133D01*
G02X116930Y1593814I-1J202D01*
G01Y1594436D01*
G03X116880Y1594568I-200J0D01*
G02Y1597480I1664J1456D01*
G03X116930Y1597612I-150J132D01*
G01Y1599554D01*
G03X116880Y1599686I-200J0D01*
G02Y1602598I1664J1456D01*
G03X116930Y1602730I-150J132D01*
G01Y1603352D01*
G02X117133Y1603554I203J-1D01*
G37*
G36*
G01X151779D02*
X154599D01*
G02X154802Y1603352I1J-202D01*
G01Y1602730D01*
G03X154852Y1602598I200J0D01*
G02Y1599686I-1664J-1456D01*
G03X154802Y1599554I150J-132D01*
G01Y1597612D01*
G03X154852Y1597480I200J0D01*
G02Y1594568I-1664J-1456D01*
G03X154802Y1594436I150J-132D01*
G01Y1593814D01*
G02X154599Y1593612I-203J1D01*
G01X151779D01*
G02X151576Y1593814I-1J202D01*
G01Y1594436D01*
G03X151526Y1594568I-200J0D01*
G02Y1597480I1664J1456D01*
G03X151576Y1597612I-150J132D01*
G01Y1599554D01*
G03X151526Y1599686I-200J0D01*
G02Y1602598I1664J1456D01*
G03X151576Y1602730I-150J132D01*
G01Y1603352D01*
G02X151779Y1603554I203J-1D01*
G37*
G36*
G01X186425D02*
X189245D01*
G02X189448Y1603352I1J-202D01*
G01Y1602730D01*
G03X189498Y1602598I200J0D01*
G02Y1599686I-1664J-1456D01*
G03X189448Y1599554I150J-132D01*
G01Y1597612D01*
G03X189498Y1597480I200J0D01*
G02Y1594568I-1664J-1456D01*
G03X189448Y1594436I150J-132D01*
G01Y1593814D01*
G02X189245Y1593612I-203J1D01*
G01X186425D01*
G02X186222Y1593814I-1J202D01*
G01Y1594436D01*
G03X186172Y1594568I-200J0D01*
G02Y1597480I1664J1456D01*
G03X186222Y1597612I-150J132D01*
G01Y1599554D01*
G03X186172Y1599686I-200J0D01*
G02Y1602598I1664J1456D01*
G03X186222Y1602730I-150J132D01*
G01Y1603352D01*
G02X186425Y1603554I203J-1D01*
G37*
G36*
G01X290361D02*
X293181D01*
G02X293384Y1603352I1J-202D01*
G01Y1602730D01*
G03X293434Y1602598I200J0D01*
G02Y1599686I-1664J-1456D01*
G03X293384Y1599554I150J-132D01*
G01Y1597612D01*
G03X293434Y1597480I200J0D01*
G02Y1594568I-1664J-1456D01*
G03X293384Y1594436I150J-132D01*
G01Y1593814D01*
G02X293181Y1593612I-203J1D01*
G01X290361D01*
G02X290158Y1593814I-1J202D01*
G01Y1594436D01*
G03X290108Y1594568I-200J0D01*
G02Y1597480I1664J1456D01*
G03X290158Y1597612I-150J132D01*
G01Y1599554D01*
G03X290108Y1599686I-200J0D01*
G02Y1602598I1664J1456D01*
G03X290158Y1602730I-150J132D01*
G01Y1603352D01*
G02X290361Y1603554I203J-1D01*
G37*
G36*
G01X325007D02*
X327827D01*
G02X328030Y1603352I1J-202D01*
G01Y1602730D01*
G03X328080Y1602598I200J0D01*
G02Y1599686I-1664J-1456D01*
G03X328030Y1599554I150J-132D01*
G01Y1597612D01*
G03X328080Y1597480I200J0D01*
G02Y1594568I-1664J-1456D01*
G03X328030Y1594436I150J-132D01*
G01Y1593814D01*
G02X327827Y1593612I-203J1D01*
G01X325007D01*
G02X324804Y1593814I-1J202D01*
G01Y1594436D01*
G03X324754Y1594568I-200J0D01*
G02Y1597480I1664J1456D01*
G03X324804Y1597612I-150J132D01*
G01Y1599554D01*
G03X324754Y1599686I-200J0D01*
G02Y1602598I1664J1456D01*
G03X324804Y1602730I-150J132D01*
G01Y1603352D01*
G02X325007Y1603554I203J-1D01*
G37*
G36*
G01X359653D02*
X362473D01*
G02X362676Y1603352I1J-202D01*
G01Y1602730D01*
G03X362726Y1602598I200J0D01*
G02Y1599686I-1664J-1456D01*
G03X362676Y1599554I150J-132D01*
G01Y1597612D01*
G03X362726Y1597480I200J0D01*
G02Y1594568I-1664J-1456D01*
G03X362676Y1594436I150J-132D01*
G01Y1593814D01*
G02X362473Y1593612I-203J1D01*
G01X359653D01*
G02X359450Y1593814I-1J202D01*
G01Y1594436D01*
G03X359400Y1594568I-200J0D01*
G02Y1597480I1664J1456D01*
G03X359450Y1597612I-150J132D01*
G01Y1599554D01*
G03X359400Y1599686I-200J0D01*
G02Y1602598I1664J1456D01*
G03X359450Y1602730I-150J132D01*
G01Y1603352D01*
G02X359653Y1603554I203J-1D01*
G37*
G36*
G01X515559D02*
X518379D01*
G02X518582Y1603352I1J-202D01*
G01Y1602730D01*
G03X518632Y1602598I200J0D01*
G02Y1599686I-1664J-1456D01*
G03X518582Y1599554I150J-132D01*
G01Y1597612D01*
G03X518632Y1597480I200J0D01*
G02Y1594568I-1664J-1456D01*
G03X518582Y1594436I150J-132D01*
G01Y1593814D01*
G02X518379Y1593612I-203J1D01*
G01X515559D01*
G02X515356Y1593814I-1J202D01*
G01Y1594436D01*
G03X515306Y1594568I-200J0D01*
G02Y1597480I1664J1456D01*
G03X515356Y1597612I-150J132D01*
G01Y1599554D01*
G03X515306Y1599686I-200J0D01*
G02Y1602598I1664J1456D01*
G03X515356Y1602730I-150J132D01*
G01Y1603352D01*
G02X515559Y1603554I203J-1D01*
G37*
G36*
G01X654141D02*
X656961D01*
G02X657164Y1603352I1J-202D01*
G01Y1602730D01*
G03X657214Y1602598I200J0D01*
G02Y1599686I-1664J-1456D01*
G03X657164Y1599554I150J-132D01*
G01Y1597612D01*
G03X657214Y1597480I200J0D01*
G02Y1594568I-1664J-1456D01*
G03X657164Y1594436I150J-132D01*
G01Y1593814D01*
G02X656961Y1593612I-203J1D01*
G01X654141D01*
G02X653938Y1593814I-1J202D01*
G01Y1594436D01*
G03X653888Y1594568I-200J0D01*
G02Y1597480I1664J1456D01*
G03X653938Y1597612I-150J132D01*
G01Y1599554D01*
G03X653888Y1599686I-200J0D01*
G02Y1602598I1664J1456D01*
G03X653938Y1602730I-150J132D01*
G01Y1603352D01*
G02X654141Y1603554I203J-1D01*
G37*
G36*
G01X688787D02*
X691607D01*
G02X691810Y1603352I1J-202D01*
G01Y1602730D01*
G03X691860Y1602598I200J0D01*
G02Y1599686I-1664J-1456D01*
G03X691810Y1599554I150J-132D01*
G01Y1597612D01*
G03X691860Y1597480I200J0D01*
G02Y1594568I-1664J-1456D01*
G03X691810Y1594436I150J-132D01*
G01Y1593814D01*
G02X691607Y1593612I-203J1D01*
G01X688787D01*
G02X688584Y1593814I-1J202D01*
G01Y1594436D01*
G03X688534Y1594568I-200J0D01*
G02Y1597480I1664J1456D01*
G03X688584Y1597612I-150J132D01*
G01Y1599554D01*
G03X688534Y1599686I-200J0D01*
G02Y1602598I1664J1456D01*
G03X688584Y1602730I-150J132D01*
G01Y1603352D01*
G02X688787Y1603554I203J-1D01*
G37*
G36*
G01X1139101D02*
X1141921D01*
G02X1142124Y1603352I1J-202D01*
G01Y1602730D01*
G03X1142174Y1602598I200J0D01*
G02Y1599686I-1664J-1456D01*
G03X1142124Y1599554I150J-132D01*
G01Y1597612D01*
G03X1142174Y1597480I200J0D01*
G02Y1594568I-1664J-1456D01*
G03X1142124Y1594436I150J-132D01*
G01Y1593814D01*
G02X1141921Y1593612I-203J1D01*
G01X1139101D01*
G02X1138898Y1593814I-1J202D01*
G01Y1594436D01*
G03X1138848Y1594568I-200J0D01*
G02Y1597480I1664J1456D01*
G03X1138898Y1597612I-150J132D01*
G01Y1599554D01*
G03X1138848Y1599686I-200J0D01*
G02Y1602598I1664J1456D01*
G03X1138898Y1602730I-150J132D01*
G01Y1603352D01*
G02X1139101Y1603554I203J-1D01*
G37*
G36*
G01X1173747D02*
X1176567D01*
G02X1176770Y1603352I1J-202D01*
G01Y1602730D01*
G03X1176820Y1602598I200J0D01*
G02Y1599686I-1664J-1456D01*
G03X1176770Y1599554I150J-132D01*
G01Y1597612D01*
G03X1176820Y1597480I200J0D01*
G02Y1594568I-1664J-1456D01*
G03X1176770Y1594436I150J-132D01*
G01Y1593814D01*
G02X1176567Y1593612I-203J1D01*
G01X1173747D01*
G02X1173544Y1593814I-1J202D01*
G01Y1594436D01*
G03X1173494Y1594568I-200J0D01*
G02Y1597480I1664J1456D01*
G03X1173544Y1597612I-150J132D01*
G01Y1599554D01*
G03X1173494Y1599686I-200J0D01*
G02Y1602598I1664J1456D01*
G03X1173544Y1602730I-150J132D01*
G01Y1603352D01*
G02X1173747Y1603554I203J-1D01*
G37*
G36*
G01X1329653D02*
X1332473D01*
G02X1332676Y1603352I1J-202D01*
G01Y1602730D01*
G03X1332726Y1602598I200J0D01*
G02Y1599686I-1664J-1456D01*
G03X1332676Y1599554I150J-132D01*
G01Y1597612D01*
G03X1332726Y1597480I200J0D01*
G02Y1594568I-1664J-1456D01*
G03X1332676Y1594436I150J-132D01*
G01Y1593814D01*
G02X1332473Y1593612I-203J1D01*
G01X1329653D01*
G02X1329450Y1593814I-1J202D01*
G01Y1594436D01*
G03X1329400Y1594568I-200J0D01*
G02Y1597480I1664J1456D01*
G03X1329450Y1597612I-150J132D01*
G01Y1599554D01*
G03X1329400Y1599686I-200J0D01*
G02Y1602598I1664J1456D01*
G03X1329450Y1602730I-150J132D01*
G01Y1603352D01*
G02X1329653Y1603554I203J-1D01*
G37*
G36*
G01X1364299D02*
X1367119D01*
G02X1367322Y1603352I1J-202D01*
G01Y1602730D01*
G03X1367372Y1602598I200J0D01*
G02Y1599686I-1664J-1456D01*
G03X1367322Y1599554I150J-132D01*
G01Y1597612D01*
G03X1367372Y1597480I200J0D01*
G02Y1594568I-1664J-1456D01*
G03X1367322Y1594436I150J-132D01*
G01Y1593814D01*
G02X1367119Y1593612I-203J1D01*
G01X1364299D01*
G02X1364096Y1593814I-1J202D01*
G01Y1594436D01*
G03X1364046Y1594568I-200J0D01*
G02Y1597480I1664J1456D01*
G03X1364096Y1597612I-150J132D01*
G01Y1599554D01*
G03X1364046Y1599686I-200J0D01*
G02Y1602598I1664J1456D01*
G03X1364096Y1602730I-150J132D01*
G01Y1603352D01*
G02X1364299Y1603554I203J-1D01*
G37*
G36*
G01X1676109D02*
X1678929D01*
G02X1679132Y1603352I1J-202D01*
G01Y1602730D01*
G03X1679182Y1602598I200J0D01*
G02Y1599686I-1664J-1456D01*
G03X1679132Y1599554I150J-132D01*
G01Y1597612D01*
G03X1679182Y1597480I200J0D01*
G02Y1594568I-1664J-1456D01*
G03X1679132Y1594436I150J-132D01*
G01Y1593814D01*
G02X1678929Y1593612I-203J1D01*
G01X1676109D01*
G02X1675906Y1593814I-1J202D01*
G01Y1594436D01*
G03X1675856Y1594568I-200J0D01*
G02Y1597480I1664J1456D01*
G03X1675906Y1597612I-150J132D01*
G01Y1599554D01*
G03X1675856Y1599686I-200J0D01*
G02Y1602598I1664J1456D01*
G03X1675906Y1602730I-150J132D01*
G01Y1603352D01*
G02X1676109Y1603554I203J-1D01*
G37*
G36*
G01X1710755D02*
X1713575D01*
G02X1713778Y1603352I1J-202D01*
G01Y1602730D01*
G03X1713828Y1602598I200J0D01*
G02Y1599686I-1664J-1456D01*
G03X1713778Y1599554I150J-132D01*
G01Y1597612D01*
G03X1713828Y1597480I200J0D01*
G02Y1594568I-1664J-1456D01*
G03X1713778Y1594436I150J-132D01*
G01Y1593814D01*
G02X1713575Y1593612I-203J1D01*
G01X1710755D01*
G02X1710552Y1593814I-1J202D01*
G01Y1594436D01*
G03X1710502Y1594568I-200J0D01*
G02Y1597480I1664J1456D01*
G03X1710552Y1597612I-150J132D01*
G01Y1599554D01*
G03X1710502Y1599686I-200J0D01*
G02Y1602598I1664J1456D01*
G03X1710552Y1602730I-150J132D01*
G01Y1603352D01*
G02X1710755Y1603554I203J-1D01*
G37*
G36*
G01X108472Y1614578D02*
X111292D01*
G02X111494Y1614376I0J-202D01*
G01Y1613756D01*
G03X111544Y1613624I200J0D01*
G02Y1610708I-1661J-1458D01*
G03X111494Y1610576I150J-132D01*
G01Y1608638D01*
G03X111544Y1608506I200J0D01*
G02Y1605590I-1661J-1458D01*
G03X111494Y1605458I150J-132D01*
G01Y1604838D01*
G02X111292Y1604636I-202J0D01*
G01X108472D01*
G02X108270Y1604838I0J202D01*
G01Y1605458D01*
G03X108220Y1605590I-200J0D01*
G02Y1608506I1661J1458D01*
G03X108270Y1608638I-150J132D01*
G01Y1610576D01*
G03X108220Y1610708I-200J0D01*
G02Y1613624I1661J1458D01*
G03X108270Y1613756I-150J132D01*
G01Y1614376D01*
G02X108472Y1614578I202J0D01*
G37*
G36*
G01X143118D02*
X145938D01*
G02X146140Y1614376I0J-202D01*
G01Y1613756D01*
G03X146190Y1613624I200J0D01*
G02Y1610708I-1661J-1458D01*
G03X146140Y1610576I150J-132D01*
G01Y1608638D01*
G03X146190Y1608506I200J0D01*
G02Y1605590I-1661J-1458D01*
G03X146140Y1605458I150J-132D01*
G01Y1604838D01*
G02X145938Y1604636I-202J0D01*
G01X143118D01*
G02X142916Y1604838I0J202D01*
G01Y1605458D01*
G03X142866Y1605590I-200J0D01*
G02Y1608506I1661J1458D01*
G03X142916Y1608638I-150J132D01*
G01Y1610576D01*
G03X142866Y1610708I-200J0D01*
G02Y1613624I1661J1458D01*
G03X142916Y1613756I-150J132D01*
G01Y1614376D01*
G02X143118Y1614578I202J0D01*
G37*
G36*
G01X160440D02*
X163260D01*
G02X163462Y1614376I0J-202D01*
G01Y1613756D01*
G03X163512Y1613624I200J0D01*
G02Y1610708I-1661J-1458D01*
G03X163462Y1610576I150J-132D01*
G01Y1608638D01*
G03X163512Y1608506I200J0D01*
G02Y1605590I-1661J-1458D01*
G03X163462Y1605458I150J-132D01*
G01Y1604838D01*
G02X163260Y1604636I-202J0D01*
G01X160440D01*
G02X160238Y1604838I0J202D01*
G01Y1605458D01*
G03X160188Y1605590I-200J0D01*
G02Y1608506I1661J1458D01*
G03X160238Y1608638I-150J132D01*
G01Y1610576D01*
G03X160188Y1610708I-200J0D01*
G02Y1613624I1661J1458D01*
G03X160238Y1613756I-150J132D01*
G01Y1614376D01*
G02X160440Y1614578I202J0D01*
G37*
G36*
G01X281700D02*
X284520D01*
G02X284722Y1614376I0J-202D01*
G01Y1613756D01*
G03X284772Y1613624I200J0D01*
G02Y1610708I-1661J-1458D01*
G03X284722Y1610576I150J-132D01*
G01Y1608638D01*
G03X284772Y1608506I200J0D01*
G02Y1605590I-1661J-1458D01*
G03X284722Y1605458I150J-132D01*
G01Y1604838D01*
G02X284520Y1604636I-202J0D01*
G01X281700D01*
G02X281498Y1604838I0J202D01*
G01Y1605458D01*
G03X281448Y1605590I-200J0D01*
G02Y1608506I1661J1458D01*
G03X281498Y1608638I-150J132D01*
G01Y1610576D01*
G03X281448Y1610708I-200J0D01*
G02Y1613624I1661J1458D01*
G03X281498Y1613756I-150J132D01*
G01Y1614376D01*
G02X281700Y1614578I202J0D01*
G37*
G36*
G01X316346D02*
X319166D01*
G02X319368Y1614376I0J-202D01*
G01Y1613756D01*
G03X319418Y1613624I200J0D01*
G02Y1610708I-1661J-1458D01*
G03X319368Y1610576I150J-132D01*
G01Y1608638D01*
G03X319418Y1608506I200J0D01*
G02Y1605590I-1661J-1458D01*
G03X319368Y1605458I150J-132D01*
G01Y1604838D01*
G02X319166Y1604636I-202J0D01*
G01X316346D01*
G02X316144Y1604838I0J202D01*
G01Y1605458D01*
G03X316094Y1605590I-200J0D01*
G02Y1608506I1661J1458D01*
G03X316144Y1608638I-150J132D01*
G01Y1610576D01*
G03X316094Y1610708I-200J0D01*
G02Y1613624I1661J1458D01*
G03X316144Y1613756I-150J132D01*
G01Y1614376D01*
G02X316346Y1614578I202J0D01*
G37*
G36*
G01X333668D02*
X336488D01*
G02X336690Y1614376I0J-202D01*
G01Y1613756D01*
G03X336740Y1613624I200J0D01*
G02Y1610708I-1661J-1458D01*
G03X336690Y1610576I150J-132D01*
G01Y1608638D01*
G03X336740Y1608506I200J0D01*
G02Y1605590I-1661J-1458D01*
G03X336690Y1605458I150J-132D01*
G01Y1604838D01*
G02X336488Y1604636I-202J0D01*
G01X333668D01*
G02X333466Y1604838I0J202D01*
G01Y1605458D01*
G03X333416Y1605590I-200J0D01*
G02Y1608506I1661J1458D01*
G03X333466Y1608638I-150J132D01*
G01Y1610576D01*
G03X333416Y1610708I-200J0D01*
G02Y1613624I1661J1458D01*
G03X333466Y1613756I-150J132D01*
G01Y1614376D01*
G02X333668Y1614578I202J0D01*
G37*
G36*
G01X645480D02*
X648300D01*
G02X648502Y1614376I0J-202D01*
G01Y1613756D01*
G03X648552Y1613624I200J0D01*
G02Y1610708I-1661J-1458D01*
G03X648502Y1610576I150J-132D01*
G01Y1608638D01*
G03X648552Y1608506I200J0D01*
G02Y1605590I-1661J-1458D01*
G03X648502Y1605458I150J-132D01*
G01Y1604838D01*
G02X648300Y1604636I-202J0D01*
G01X645480D01*
G02X645278Y1604838I0J202D01*
G01Y1605458D01*
G03X645228Y1605590I-200J0D01*
G02Y1608506I1661J1458D01*
G03X645278Y1608638I-150J132D01*
G01Y1610576D01*
G03X645228Y1610708I-200J0D01*
G02Y1613624I1661J1458D01*
G03X645278Y1613756I-150J132D01*
G01Y1614376D01*
G02X645480Y1614578I202J0D01*
G37*
G36*
G01X1130440D02*
X1133260D01*
G02X1133462Y1614376I0J-202D01*
G01Y1613756D01*
G03X1133512Y1613624I200J0D01*
G02Y1610708I-1661J-1458D01*
G03X1133462Y1610576I150J-132D01*
G01Y1608638D01*
G03X1133512Y1608506I200J0D01*
G02Y1605590I-1661J-1458D01*
G03X1133462Y1605458I150J-132D01*
G01Y1604838D01*
G02X1133260Y1604636I-202J0D01*
G01X1130440D01*
G02X1130238Y1604838I0J202D01*
G01Y1605458D01*
G03X1130188Y1605590I-200J0D01*
G02Y1608506I1661J1458D01*
G03X1130238Y1608638I-150J132D01*
G01Y1610576D01*
G03X1130188Y1610708I-200J0D01*
G02Y1613624I1661J1458D01*
G03X1130238Y1613756I-150J132D01*
G01Y1614376D01*
G02X1130440Y1614578I202J0D01*
G37*
G36*
G01X1165086D02*
X1167906D01*
G02X1168108Y1614376I0J-202D01*
G01Y1613756D01*
G03X1168158Y1613624I200J0D01*
G02Y1610708I-1661J-1458D01*
G03X1168108Y1610576I150J-132D01*
G01Y1608638D01*
G03X1168158Y1608506I200J0D01*
G02Y1605590I-1661J-1458D01*
G03X1168108Y1605458I150J-132D01*
G01Y1604838D01*
G02X1167906Y1604636I-202J0D01*
G01X1165086D01*
G02X1164884Y1604838I0J202D01*
G01Y1605458D01*
G03X1164834Y1605590I-200J0D01*
G02Y1608506I1661J1458D01*
G03X1164884Y1608638I-150J132D01*
G01Y1610576D01*
G03X1164834Y1610708I-200J0D01*
G02Y1613624I1661J1458D01*
G03X1164884Y1613756I-150J132D01*
G01Y1614376D01*
G02X1165086Y1614578I202J0D01*
G37*
G36*
G01X1182408D02*
X1185228D01*
G02X1185430Y1614376I0J-202D01*
G01Y1613756D01*
G03X1185480Y1613624I200J0D01*
G02Y1610708I-1661J-1458D01*
G03X1185430Y1610576I150J-132D01*
G01Y1608638D01*
G03X1185480Y1608506I200J0D01*
G02Y1605590I-1661J-1458D01*
G03X1185430Y1605458I150J-132D01*
G01Y1604838D01*
G02X1185228Y1604636I-202J0D01*
G01X1182408D01*
G02X1182206Y1604838I0J202D01*
G01Y1605458D01*
G03X1182156Y1605590I-200J0D01*
G02Y1608506I1661J1458D01*
G03X1182206Y1608638I-150J132D01*
G01Y1610576D01*
G03X1182156Y1610708I-200J0D01*
G02Y1613624I1661J1458D01*
G03X1182206Y1613756I-150J132D01*
G01Y1614376D01*
G02X1182408Y1614578I202J0D01*
G37*
G36*
G01X1320992D02*
X1323812D01*
G02X1324014Y1614376I0J-202D01*
G01Y1613756D01*
G03X1324064Y1613624I200J0D01*
G02Y1610708I-1661J-1458D01*
G03X1324014Y1610576I150J-132D01*
G01Y1608638D01*
G03X1324064Y1608506I200J0D01*
G02Y1605590I-1661J-1458D01*
G03X1324014Y1605458I150J-132D01*
G01Y1604838D01*
G02X1323812Y1604636I-202J0D01*
G01X1320992D01*
G02X1320790Y1604838I0J202D01*
G01Y1605458D01*
G03X1320740Y1605590I-200J0D01*
G02Y1608506I1661J1458D01*
G03X1320790Y1608638I-150J132D01*
G01Y1610576D01*
G03X1320740Y1610708I-200J0D01*
G02Y1613624I1661J1458D01*
G03X1320790Y1613756I-150J132D01*
G01Y1614376D01*
G02X1320992Y1614578I202J0D01*
G37*
G36*
G01X1667448D02*
X1670268D01*
G02X1670470Y1614376I0J-202D01*
G01Y1613756D01*
G03X1670520Y1613624I200J0D01*
G02Y1610708I-1661J-1458D01*
G03X1670470Y1610576I150J-132D01*
G01Y1608638D01*
G03X1670520Y1608506I200J0D01*
G02Y1605590I-1661J-1458D01*
G03X1670470Y1605458I150J-132D01*
G01Y1604838D01*
G02X1670268Y1604636I-202J0D01*
G01X1667448D01*
G02X1667246Y1604838I0J202D01*
G01Y1605458D01*
G03X1667196Y1605590I-200J0D01*
G02Y1608506I1661J1458D01*
G03X1667246Y1608638I-150J132D01*
G01Y1610576D01*
G03X1667196Y1610708I-200J0D01*
G02Y1613624I1661J1458D01*
G03X1667246Y1613756I-150J132D01*
G01Y1614376D01*
G02X1667448Y1614578I202J0D01*
G37*
G36*
G01X125795D02*
X128615D01*
G02X128818Y1614376I1J-202D01*
G01Y1613754D01*
G03X128868Y1613622I200J0D01*
G02Y1610710I-1664J-1456D01*
G03X128818Y1610578I150J-132D01*
G01Y1608636D01*
G03X128868Y1608504I200J0D01*
G02Y1605592I-1664J-1456D01*
G03X128818Y1605460I150J-132D01*
G01Y1604838D01*
G02X128615Y1604636I-203J1D01*
G01X125795D01*
G02X125592Y1604838I-1J202D01*
G01Y1605460D01*
G03X125542Y1605592I-200J0D01*
G02Y1608504I1664J1456D01*
G03X125592Y1608636I-150J132D01*
G01Y1610578D01*
G03X125542Y1610710I-200J0D01*
G02Y1613622I1664J1456D01*
G03X125592Y1613754I-150J132D01*
G01Y1614376D01*
G02X125795Y1614578I203J-1D01*
G37*
G36*
G01X299023D02*
X301843D01*
G02X302046Y1614376I1J-202D01*
G01Y1613754D01*
G03X302096Y1613622I200J0D01*
G02Y1610710I-1664J-1456D01*
G03X302046Y1610578I150J-132D01*
G01Y1608636D01*
G03X302096Y1608504I200J0D01*
G02Y1605592I-1664J-1456D01*
G03X302046Y1605460I150J-132D01*
G01Y1604838D01*
G02X301843Y1604636I-203J1D01*
G01X299023D01*
G02X298820Y1604838I-1J202D01*
G01Y1605460D01*
G03X298770Y1605592I-200J0D01*
G02Y1608504I1664J1456D01*
G03X298820Y1608636I-150J132D01*
G01Y1610578D01*
G03X298770Y1610710I-200J0D01*
G02Y1613622I1664J1456D01*
G03X298820Y1613754I-150J132D01*
G01Y1614376D01*
G02X299023Y1614578I203J-1D01*
G37*
G36*
G01X628157D02*
X630977D01*
G02X631180Y1614376I1J-202D01*
G01Y1613754D01*
G03X631230Y1613622I200J0D01*
G02Y1610710I-1664J-1456D01*
G03X631180Y1610578I150J-132D01*
G01Y1608636D01*
G03X631230Y1608504I200J0D01*
G02Y1605592I-1664J-1456D01*
G03X631180Y1605460I150J-132D01*
G01Y1604838D01*
G02X630977Y1604636I-203J1D01*
G01X628157D01*
G02X627954Y1604838I-1J202D01*
G01Y1605460D01*
G03X627904Y1605592I-200J0D01*
G02Y1608504I1664J1456D01*
G03X627954Y1608636I-150J132D01*
G01Y1610578D01*
G03X627904Y1610710I-200J0D01*
G02Y1613622I1664J1456D01*
G03X627954Y1613754I-150J132D01*
G01Y1614376D01*
G02X628157Y1614578I203J-1D01*
G37*
G36*
G01X662803D02*
X665623D01*
G02X665826Y1614376I1J-202D01*
G01Y1613754D01*
G03X665876Y1613622I200J0D01*
G02Y1610710I-1664J-1456D01*
G03X665826Y1610578I150J-132D01*
G01Y1608636D01*
G03X665876Y1608504I200J0D01*
G02Y1605592I-1664J-1456D01*
G03X665826Y1605460I150J-132D01*
G01Y1604838D01*
G02X665623Y1604636I-203J1D01*
G01X662803D01*
G02X662600Y1604838I-1J202D01*
G01Y1605460D01*
G03X662550Y1605592I-200J0D01*
G02Y1608504I1664J1456D01*
G03X662600Y1608636I-150J132D01*
G01Y1610578D01*
G03X662550Y1610710I-200J0D01*
G02Y1613622I1664J1456D01*
G03X662600Y1613754I-150J132D01*
G01Y1614376D01*
G02X662803Y1614578I203J-1D01*
G37*
G36*
G01X680125D02*
X682945D01*
G02X683148Y1614376I1J-202D01*
G01Y1613754D01*
G03X683198Y1613622I200J0D01*
G02Y1610710I-1664J-1456D01*
G03X683148Y1610578I150J-132D01*
G01Y1608636D01*
G03X683198Y1608504I200J0D01*
G02Y1605592I-1664J-1456D01*
G03X683148Y1605460I150J-132D01*
G01Y1604838D01*
G02X682945Y1604636I-203J1D01*
G01X680125D01*
G02X679922Y1604838I-1J202D01*
G01Y1605460D01*
G03X679872Y1605592I-200J0D01*
G02Y1608504I1664J1456D01*
G03X679922Y1608636I-150J132D01*
G01Y1610578D01*
G03X679872Y1610710I-200J0D01*
G02Y1613622I1664J1456D01*
G03X679922Y1613754I-150J132D01*
G01Y1614376D01*
G02X680125Y1614578I203J-1D01*
G37*
G36*
G01X1147763D02*
X1150583D01*
G02X1150786Y1614376I1J-202D01*
G01Y1613754D01*
G03X1150836Y1613622I200J0D01*
G02Y1610710I-1664J-1456D01*
G03X1150786Y1610578I150J-132D01*
G01Y1608636D01*
G03X1150836Y1608504I200J0D01*
G02Y1605592I-1664J-1456D01*
G03X1150786Y1605460I150J-132D01*
G01Y1604838D01*
G02X1150583Y1604636I-203J1D01*
G01X1147763D01*
G02X1147560Y1604838I-1J202D01*
G01Y1605460D01*
G03X1147510Y1605592I-200J0D01*
G02Y1608504I1664J1456D01*
G03X1147560Y1608636I-150J132D01*
G01Y1610578D01*
G03X1147510Y1610710I-200J0D01*
G02Y1613622I1664J1456D01*
G03X1147560Y1613754I-150J132D01*
G01Y1614376D01*
G02X1147763Y1614578I203J-1D01*
G37*
G36*
G01X1303669D02*
X1306489D01*
G02X1306692Y1614376I1J-202D01*
G01Y1613754D01*
G03X1306742Y1613622I200J0D01*
G02Y1610710I-1664J-1456D01*
G03X1306692Y1610578I150J-132D01*
G01Y1608636D01*
G03X1306742Y1608504I200J0D01*
G02Y1605592I-1664J-1456D01*
G03X1306692Y1605460I150J-132D01*
G01Y1604838D01*
G02X1306489Y1604636I-203J1D01*
G01X1303669D01*
G02X1303466Y1604838I-1J202D01*
G01Y1605460D01*
G03X1303416Y1605592I-200J0D01*
G02Y1608504I1664J1456D01*
G03X1303466Y1608636I-150J132D01*
G01Y1610578D01*
G03X1303416Y1610710I-200J0D01*
G02Y1613622I1664J1456D01*
G03X1303466Y1613754I-150J132D01*
G01Y1614376D01*
G02X1303669Y1614578I203J-1D01*
G37*
G36*
G01X1338315D02*
X1341135D01*
G02X1341338Y1614376I1J-202D01*
G01Y1613754D01*
G03X1341388Y1613622I200J0D01*
G02Y1610710I-1664J-1456D01*
G03X1341338Y1610578I150J-132D01*
G01Y1608636D01*
G03X1341388Y1608504I200J0D01*
G02Y1605592I-1664J-1456D01*
G03X1341338Y1605460I150J-132D01*
G01Y1604838D01*
G02X1341135Y1604636I-203J1D01*
G01X1338315D01*
G02X1338112Y1604838I-1J202D01*
G01Y1605460D01*
G03X1338062Y1605592I-200J0D01*
G02Y1608504I1664J1456D01*
G03X1338112Y1608636I-150J132D01*
G01Y1610578D01*
G03X1338062Y1610710I-200J0D01*
G02Y1613622I1664J1456D01*
G03X1338112Y1613754I-150J132D01*
G01Y1614376D01*
G02X1338315Y1614578I203J-1D01*
G37*
G36*
G01X1355637D02*
X1358457D01*
G02X1358660Y1614376I1J-202D01*
G01Y1613754D01*
G03X1358710Y1613622I200J0D01*
G02Y1610710I-1664J-1456D01*
G03X1358660Y1610578I150J-132D01*
G01Y1608636D01*
G03X1358710Y1608504I200J0D01*
G02Y1605592I-1664J-1456D01*
G03X1358660Y1605460I150J-132D01*
G01Y1604838D01*
G02X1358457Y1604636I-203J1D01*
G01X1355637D01*
G02X1355434Y1604838I-1J202D01*
G01Y1605460D01*
G03X1355384Y1605592I-200J0D01*
G02Y1608504I1664J1456D01*
G03X1355434Y1608636I-150J132D01*
G01Y1610578D01*
G03X1355384Y1610710I-200J0D01*
G02Y1613622I1664J1456D01*
G03X1355434Y1613754I-150J132D01*
G01Y1614376D01*
G02X1355637Y1614578I203J-1D01*
G37*
G36*
G01X1476897D02*
X1479717D01*
G02X1479920Y1614376I1J-202D01*
G01Y1613754D01*
G03X1479970Y1613622I200J0D01*
G02Y1610710I-1664J-1456D01*
G03X1479920Y1610578I150J-132D01*
G01Y1608636D01*
G03X1479970Y1608504I200J0D01*
G02Y1605592I-1664J-1456D01*
G03X1479920Y1605460I150J-132D01*
G01Y1604838D01*
G02X1479717Y1604636I-203J1D01*
G01X1476897D01*
G02X1476694Y1604838I-1J202D01*
G01Y1605460D01*
G03X1476644Y1605592I-200J0D01*
G02Y1608504I1664J1456D01*
G03X1476694Y1608636I-150J132D01*
G01Y1610578D01*
G03X1476644Y1610710I-200J0D01*
G02Y1613622I1664J1456D01*
G03X1476694Y1613754I-150J132D01*
G01Y1614376D01*
G02X1476897Y1614578I203J-1D01*
G37*
G36*
G01X1650125D02*
X1652945D01*
G02X1653148Y1614376I1J-202D01*
G01Y1613754D01*
G03X1653198Y1613622I200J0D01*
G02Y1610710I-1664J-1456D01*
G03X1653148Y1610578I150J-132D01*
G01Y1608636D01*
G03X1653198Y1608504I200J0D01*
G02Y1605592I-1664J-1456D01*
G03X1653148Y1605460I150J-132D01*
G01Y1604838D01*
G02X1652945Y1604636I-203J1D01*
G01X1650125D01*
G02X1649922Y1604838I-1J202D01*
G01Y1605460D01*
G03X1649872Y1605592I-200J0D01*
G02Y1608504I1664J1456D01*
G03X1649922Y1608636I-150J132D01*
G01Y1610578D01*
G03X1649872Y1610710I-200J0D01*
G02Y1613622I1664J1456D01*
G03X1649922Y1613754I-150J132D01*
G01Y1614376D01*
G02X1650125Y1614578I203J-1D01*
G37*
G36*
G01X1684771D02*
X1687591D01*
G02X1687794Y1614376I1J-202D01*
G01Y1613754D01*
G03X1687844Y1613622I200J0D01*
G02Y1610710I-1664J-1456D01*
G03X1687794Y1610578I150J-132D01*
G01Y1608636D01*
G03X1687844Y1608504I200J0D01*
G02Y1605592I-1664J-1456D01*
G03X1687794Y1605460I150J-132D01*
G01Y1604838D01*
G02X1687591Y1604636I-203J1D01*
G01X1684771D01*
G02X1684568Y1604838I-1J202D01*
G01Y1605460D01*
G03X1684518Y1605592I-200J0D01*
G02Y1608504I1664J1456D01*
G03X1684568Y1608636I-150J132D01*
G01Y1610578D01*
G03X1684518Y1610710I-200J0D01*
G02Y1613622I1664J1456D01*
G03X1684568Y1613754I-150J132D01*
G01Y1614376D01*
G02X1684771Y1614578I203J-1D01*
G37*
G36*
G01X1702093D02*
X1704913D01*
G02X1705116Y1614376I1J-202D01*
G01Y1613754D01*
G03X1705166Y1613622I200J0D01*
G02Y1610710I-1664J-1456D01*
G03X1705116Y1610578I150J-132D01*
G01Y1608636D01*
G03X1705166Y1608504I200J0D01*
G02Y1605592I-1664J-1456D01*
G03X1705116Y1605460I150J-132D01*
G01Y1604838D01*
G02X1704913Y1604636I-203J1D01*
G01X1702093D01*
G02X1701890Y1604838I-1J202D01*
G01Y1605460D01*
G03X1701840Y1605592I-200J0D01*
G02Y1608504I1664J1456D01*
G03X1701890Y1608636I-150J132D01*
G01Y1610578D01*
G03X1701840Y1610710I-200J0D01*
G02Y1613622I1664J1456D01*
G03X1701890Y1613754I-150J132D01*
G01Y1614376D01*
G02X1702093Y1614578I203J-1D01*
G37*
G36*
G01X134456Y1618908D02*
X137276D01*
G02X137478Y1618706I0J-202D01*
G01Y1618086D01*
G03X137528Y1617954I200J0D01*
G02Y1615038I-1661J-1458D01*
G03X137478Y1614906I150J-132D01*
G01Y1612968D01*
G03X137528Y1612836I200J0D01*
G02Y1609920I-1661J-1458D01*
G03X137478Y1609788I150J-132D01*
G01Y1609168D01*
G02X137276Y1608966I-202J0D01*
G01X134456D01*
G02X134254Y1609168I0J202D01*
G01Y1609788D01*
G03X134204Y1609920I-200J0D01*
G02Y1612836I1661J1458D01*
G03X134254Y1612968I-150J132D01*
G01Y1614906D01*
G03X134204Y1615038I-200J0D01*
G02Y1617954I1661J1458D01*
G03X134254Y1618086I-150J132D01*
G01Y1618706D01*
G02X134456Y1618908I202J0D01*
G37*
G36*
G01X169102D02*
X171922D01*
G02X172124Y1618706I0J-202D01*
G01Y1618086D01*
G03X172174Y1617954I200J0D01*
G02Y1615038I-1661J-1458D01*
G03X172124Y1614906I150J-132D01*
G01Y1612968D01*
G03X172174Y1612836I200J0D01*
G02Y1609920I-1661J-1458D01*
G03X172124Y1609788I150J-132D01*
G01Y1609168D01*
G02X171922Y1608966I-202J0D01*
G01X169102D01*
G02X168900Y1609168I0J202D01*
G01Y1609788D01*
G03X168850Y1609920I-200J0D01*
G02Y1612836I1661J1458D01*
G03X168900Y1612968I-150J132D01*
G01Y1614906D01*
G03X168850Y1615038I-200J0D01*
G02Y1617954I1661J1458D01*
G03X168900Y1618086I-150J132D01*
G01Y1618706D01*
G02X169102Y1618908I202J0D01*
G37*
G36*
G01X307684D02*
X310504D01*
G02X310706Y1618706I0J-202D01*
G01Y1618086D01*
G03X310756Y1617954I200J0D01*
G02Y1615038I-1661J-1458D01*
G03X310706Y1614906I150J-132D01*
G01Y1612968D01*
G03X310756Y1612836I200J0D01*
G02Y1609920I-1661J-1458D01*
G03X310706Y1609788I150J-132D01*
G01Y1609168D01*
G02X310504Y1608966I-202J0D01*
G01X307684D01*
G02X307482Y1609168I0J202D01*
G01Y1609788D01*
G03X307432Y1609920I-200J0D01*
G02Y1612836I1661J1458D01*
G03X307482Y1612968I-150J132D01*
G01Y1614906D01*
G03X307432Y1615038I-200J0D01*
G02Y1617954I1661J1458D01*
G03X307482Y1618086I-150J132D01*
G01Y1618706D01*
G02X307684Y1618908I202J0D01*
G37*
G36*
G01X342330D02*
X345150D01*
G02X345352Y1618706I0J-202D01*
G01Y1618086D01*
G03X345402Y1617954I200J0D01*
G02Y1615038I-1661J-1458D01*
G03X345352Y1614906I150J-132D01*
G01Y1612968D01*
G03X345402Y1612836I200J0D01*
G02Y1609920I-1661J-1458D01*
G03X345352Y1609788I150J-132D01*
G01Y1609168D01*
G02X345150Y1608966I-202J0D01*
G01X342330D01*
G02X342128Y1609168I0J202D01*
G01Y1609788D01*
G03X342078Y1609920I-200J0D01*
G02Y1612836I1661J1458D01*
G03X342128Y1612968I-150J132D01*
G01Y1614906D01*
G03X342078Y1615038I-200J0D01*
G02Y1617954I1661J1458D01*
G03X342128Y1618086I-150J132D01*
G01Y1618706D01*
G02X342330Y1618908I202J0D01*
G37*
G36*
G01X636818D02*
X639638D01*
G02X639840Y1618706I0J-202D01*
G01Y1618086D01*
G03X639890Y1617954I200J0D01*
G02Y1615038I-1661J-1458D01*
G03X639840Y1614906I150J-132D01*
G01Y1612968D01*
G03X639890Y1612836I200J0D01*
G02Y1609920I-1661J-1458D01*
G03X639840Y1609788I150J-132D01*
G01Y1609168D01*
G02X639638Y1608966I-202J0D01*
G01X636818D01*
G02X636616Y1609168I0J202D01*
G01Y1609788D01*
G03X636566Y1609920I-200J0D01*
G02Y1612836I1661J1458D01*
G03X636616Y1612968I-150J132D01*
G01Y1614906D01*
G03X636566Y1615038I-200J0D01*
G02Y1617954I1661J1458D01*
G03X636616Y1618086I-150J132D01*
G01Y1618706D01*
G02X636818Y1618908I202J0D01*
G37*
G36*
G01X671464D02*
X674284D01*
G02X674486Y1618706I0J-202D01*
G01Y1618086D01*
G03X674536Y1617954I200J0D01*
G02Y1615038I-1661J-1458D01*
G03X674486Y1614906I150J-132D01*
G01Y1612968D01*
G03X674536Y1612836I200J0D01*
G02Y1609920I-1661J-1458D01*
G03X674486Y1609788I150J-132D01*
G01Y1609168D01*
G02X674284Y1608966I-202J0D01*
G01X671464D01*
G02X671262Y1609168I0J202D01*
G01Y1609788D01*
G03X671212Y1609920I-200J0D01*
G02Y1612836I1661J1458D01*
G03X671262Y1612968I-150J132D01*
G01Y1614906D01*
G03X671212Y1615038I-200J0D01*
G02Y1617954I1661J1458D01*
G03X671262Y1618086I-150J132D01*
G01Y1618706D01*
G02X671464Y1618908I202J0D01*
G37*
G36*
G01X1156424D02*
X1159244D01*
G02X1159446Y1618706I0J-202D01*
G01Y1618086D01*
G03X1159496Y1617954I200J0D01*
G02Y1615038I-1661J-1458D01*
G03X1159446Y1614906I150J-132D01*
G01Y1612968D01*
G03X1159496Y1612836I200J0D01*
G02Y1609920I-1661J-1458D01*
G03X1159446Y1609788I150J-132D01*
G01Y1609168D01*
G02X1159244Y1608966I-202J0D01*
G01X1156424D01*
G02X1156222Y1609168I0J202D01*
G01Y1609788D01*
G03X1156172Y1609920I-200J0D01*
G02Y1612836I1661J1458D01*
G03X1156222Y1612968I-150J132D01*
G01Y1614906D01*
G03X1156172Y1615038I-200J0D01*
G02Y1617954I1661J1458D01*
G03X1156222Y1618086I-150J132D01*
G01Y1618706D01*
G02X1156424Y1618908I202J0D01*
G37*
G36*
G01X1191070D02*
X1193890D01*
G02X1194092Y1618706I0J-202D01*
G01Y1618086D01*
G03X1194142Y1617954I200J0D01*
G02Y1615038I-1661J-1458D01*
G03X1194092Y1614906I150J-132D01*
G01Y1612968D01*
G03X1194142Y1612836I200J0D01*
G02Y1609920I-1661J-1458D01*
G03X1194092Y1609788I150J-132D01*
G01Y1609168D01*
G02X1193890Y1608966I-202J0D01*
G01X1191070D01*
G02X1190868Y1609168I0J202D01*
G01Y1609788D01*
G03X1190818Y1609920I-200J0D01*
G02Y1612836I1661J1458D01*
G03X1190868Y1612968I-150J132D01*
G01Y1614906D01*
G03X1190818Y1615038I-200J0D01*
G02Y1617954I1661J1458D01*
G03X1190868Y1618086I-150J132D01*
G01Y1618706D01*
G02X1191070Y1618908I202J0D01*
G37*
G36*
G01X1312330D02*
X1315150D01*
G02X1315352Y1618706I0J-202D01*
G01Y1618086D01*
G03X1315402Y1617954I200J0D01*
G02Y1615038I-1661J-1458D01*
G03X1315352Y1614906I150J-132D01*
G01Y1612968D01*
G03X1315402Y1612836I200J0D01*
G02Y1609920I-1661J-1458D01*
G03X1315352Y1609788I150J-132D01*
G01Y1609168D01*
G02X1315150Y1608966I-202J0D01*
G01X1312330D01*
G02X1312128Y1609168I0J202D01*
G01Y1609788D01*
G03X1312078Y1609920I-200J0D01*
G02Y1612836I1661J1458D01*
G03X1312128Y1612968I-150J132D01*
G01Y1614906D01*
G03X1312078Y1615038I-200J0D01*
G02Y1617954I1661J1458D01*
G03X1312128Y1618086I-150J132D01*
G01Y1618706D01*
G02X1312330Y1618908I202J0D01*
G37*
G36*
G01X1346976D02*
X1349796D01*
G02X1349998Y1618706I0J-202D01*
G01Y1618086D01*
G03X1350048Y1617954I200J0D01*
G02Y1615038I-1661J-1458D01*
G03X1349998Y1614906I150J-132D01*
G01Y1612968D01*
G03X1350048Y1612836I200J0D01*
G02Y1609920I-1661J-1458D01*
G03X1349998Y1609788I150J-132D01*
G01Y1609168D01*
G02X1349796Y1608966I-202J0D01*
G01X1346976D01*
G02X1346774Y1609168I0J202D01*
G01Y1609788D01*
G03X1346724Y1609920I-200J0D01*
G02Y1612836I1661J1458D01*
G03X1346774Y1612968I-150J132D01*
G01Y1614906D01*
G03X1346724Y1615038I-200J0D01*
G02Y1617954I1661J1458D01*
G03X1346774Y1618086I-150J132D01*
G01Y1618706D01*
G02X1346976Y1618908I202J0D01*
G37*
G36*
G01X1658786D02*
X1661606D01*
G02X1661808Y1618706I0J-202D01*
G01Y1618086D01*
G03X1661858Y1617954I200J0D01*
G02Y1615038I-1661J-1458D01*
G03X1661808Y1614906I150J-132D01*
G01Y1612968D01*
G03X1661858Y1612836I200J0D01*
G02Y1609920I-1661J-1458D01*
G03X1661808Y1609788I150J-132D01*
G01Y1609168D01*
G02X1661606Y1608966I-202J0D01*
G01X1658786D01*
G02X1658584Y1609168I0J202D01*
G01Y1609788D01*
G03X1658534Y1609920I-200J0D01*
G02Y1612836I1661J1458D01*
G03X1658584Y1612968I-150J132D01*
G01Y1614906D01*
G03X1658534Y1615038I-200J0D01*
G02Y1617954I1661J1458D01*
G03X1658584Y1618086I-150J132D01*
G01Y1618706D01*
G02X1658786Y1618908I202J0D01*
G37*
G36*
G01X1693432D02*
X1696252D01*
G02X1696454Y1618706I0J-202D01*
G01Y1618086D01*
G03X1696504Y1617954I200J0D01*
G02Y1615038I-1661J-1458D01*
G03X1696454Y1614906I150J-132D01*
G01Y1612968D01*
G03X1696504Y1612836I200J0D01*
G02Y1609920I-1661J-1458D01*
G03X1696454Y1609788I150J-132D01*
G01Y1609168D01*
G02X1696252Y1608966I-202J0D01*
G01X1693432D01*
G02X1693230Y1609168I0J202D01*
G01Y1609788D01*
G03X1693180Y1609920I-200J0D01*
G02Y1612836I1661J1458D01*
G03X1693230Y1612968I-150J132D01*
G01Y1614906D01*
G03X1693180Y1615038I-200J0D01*
G02Y1617954I1661J1458D01*
G03X1693230Y1618086I-150J132D01*
G01Y1618706D01*
G02X1693432Y1618908I202J0D01*
G37*
G36*
G01X117133D02*
X119953D01*
G02X120156Y1618706I1J-202D01*
G01Y1618084D01*
G03X120206Y1617952I200J0D01*
G02Y1615040I-1664J-1456D01*
G03X120156Y1614908I150J-132D01*
G01Y1612966D01*
G03X120206Y1612834I200J0D01*
G02Y1609922I-1664J-1456D01*
G03X120156Y1609790I150J-132D01*
G01Y1609168D01*
G02X119953Y1608966I-203J1D01*
G01X117133D01*
G02X116930Y1609168I-1J202D01*
G01Y1609790D01*
G03X116880Y1609922I-200J0D01*
G02Y1612834I1664J1456D01*
G03X116930Y1612966I-150J132D01*
G01Y1614908D01*
G03X116880Y1615040I-200J0D01*
G02Y1617952I1664J1456D01*
G03X116930Y1618084I-150J132D01*
G01Y1618706D01*
G02X117133Y1618908I203J-1D01*
G37*
G36*
G01X151779D02*
X154599D01*
G02X154802Y1618706I1J-202D01*
G01Y1618084D01*
G03X154852Y1617952I200J0D01*
G02Y1615040I-1664J-1456D01*
G03X154802Y1614908I150J-132D01*
G01Y1612966D01*
G03X154852Y1612834I200J0D01*
G02Y1609922I-1664J-1456D01*
G03X154802Y1609790I150J-132D01*
G01Y1609168D01*
G02X154599Y1608966I-203J1D01*
G01X151779D01*
G02X151576Y1609168I-1J202D01*
G01Y1609790D01*
G03X151526Y1609922I-200J0D01*
G02Y1612834I1664J1456D01*
G03X151576Y1612966I-150J132D01*
G01Y1614908D01*
G03X151526Y1615040I-200J0D01*
G02Y1617952I1664J1456D01*
G03X151576Y1618084I-150J132D01*
G01Y1618706D01*
G02X151779Y1618908I203J-1D01*
G37*
G36*
G01X186425D02*
X189245D01*
G02X189448Y1618706I1J-202D01*
G01Y1618084D01*
G03X189498Y1617952I200J0D01*
G02Y1615040I-1664J-1456D01*
G03X189448Y1614908I150J-132D01*
G01Y1612966D01*
G03X189498Y1612834I200J0D01*
G02Y1609922I-1664J-1456D01*
G03X189448Y1609790I150J-132D01*
G01Y1609168D01*
G02X189245Y1608966I-203J1D01*
G01X186425D01*
G02X186222Y1609168I-1J202D01*
G01Y1609790D01*
G03X186172Y1609922I-200J0D01*
G02Y1612834I1664J1456D01*
G03X186222Y1612966I-150J132D01*
G01Y1614908D01*
G03X186172Y1615040I-200J0D01*
G02Y1617952I1664J1456D01*
G03X186222Y1618084I-150J132D01*
G01Y1618706D01*
G02X186425Y1618908I203J-1D01*
G37*
G36*
G01X290361D02*
X293181D01*
G02X293384Y1618706I1J-202D01*
G01Y1618084D01*
G03X293434Y1617952I200J0D01*
G02Y1615040I-1664J-1456D01*
G03X293384Y1614908I150J-132D01*
G01Y1612966D01*
G03X293434Y1612834I200J0D01*
G02Y1609922I-1664J-1456D01*
G03X293384Y1609790I150J-132D01*
G01Y1609168D01*
G02X293181Y1608966I-203J1D01*
G01X290361D01*
G02X290158Y1609168I-1J202D01*
G01Y1609790D01*
G03X290108Y1609922I-200J0D01*
G02Y1612834I1664J1456D01*
G03X290158Y1612966I-150J132D01*
G01Y1614908D01*
G03X290108Y1615040I-200J0D01*
G02Y1617952I1664J1456D01*
G03X290158Y1618084I-150J132D01*
G01Y1618706D01*
G02X290361Y1618908I203J-1D01*
G37*
G36*
G01X325007D02*
X327827D01*
G02X328030Y1618706I1J-202D01*
G01Y1618084D01*
G03X328080Y1617952I200J0D01*
G02Y1615040I-1664J-1456D01*
G03X328030Y1614908I150J-132D01*
G01Y1612966D01*
G03X328080Y1612834I200J0D01*
G02Y1609922I-1664J-1456D01*
G03X328030Y1609790I150J-132D01*
G01Y1609168D01*
G02X327827Y1608966I-203J1D01*
G01X325007D01*
G02X324804Y1609168I-1J202D01*
G01Y1609790D01*
G03X324754Y1609922I-200J0D01*
G02Y1612834I1664J1456D01*
G03X324804Y1612966I-150J132D01*
G01Y1614908D01*
G03X324754Y1615040I-200J0D01*
G02Y1617952I1664J1456D01*
G03X324804Y1618084I-150J132D01*
G01Y1618706D01*
G02X325007Y1618908I203J-1D01*
G37*
G36*
G01X359653D02*
X362473D01*
G02X362676Y1618706I1J-202D01*
G01Y1618084D01*
G03X362726Y1617952I200J0D01*
G02Y1615040I-1664J-1456D01*
G03X362676Y1614908I150J-132D01*
G01Y1612966D01*
G03X362726Y1612834I200J0D01*
G02Y1609922I-1664J-1456D01*
G03X362676Y1609790I150J-132D01*
G01Y1609168D01*
G02X362473Y1608966I-203J1D01*
G01X359653D01*
G02X359450Y1609168I-1J202D01*
G01Y1609790D01*
G03X359400Y1609922I-200J0D01*
G02Y1612834I1664J1456D01*
G03X359450Y1612966I-150J132D01*
G01Y1614908D01*
G03X359400Y1615040I-200J0D01*
G02Y1617952I1664J1456D01*
G03X359450Y1618084I-150J132D01*
G01Y1618706D01*
G02X359653Y1618908I203J-1D01*
G37*
G36*
G01X515559D02*
X518379D01*
G02X518582Y1618706I1J-202D01*
G01Y1618084D01*
G03X518632Y1617952I200J0D01*
G02Y1615040I-1664J-1456D01*
G03X518582Y1614908I150J-132D01*
G01Y1612966D01*
G03X518632Y1612834I200J0D01*
G02Y1609922I-1664J-1456D01*
G03X518582Y1609790I150J-132D01*
G01Y1609168D01*
G02X518379Y1608966I-203J1D01*
G01X515559D01*
G02X515356Y1609168I-1J202D01*
G01Y1609790D01*
G03X515306Y1609922I-200J0D01*
G02Y1612834I1664J1456D01*
G03X515356Y1612966I-150J132D01*
G01Y1614908D01*
G03X515306Y1615040I-200J0D01*
G02Y1617952I1664J1456D01*
G03X515356Y1618084I-150J132D01*
G01Y1618706D01*
G02X515559Y1618908I203J-1D01*
G37*
G36*
G01X654141D02*
X656961D01*
G02X657164Y1618706I1J-202D01*
G01Y1618084D01*
G03X657214Y1617952I200J0D01*
G02Y1615040I-1664J-1456D01*
G03X657164Y1614908I150J-132D01*
G01Y1612966D01*
G03X657214Y1612834I200J0D01*
G02Y1609922I-1664J-1456D01*
G03X657164Y1609790I150J-132D01*
G01Y1609168D01*
G02X656961Y1608966I-203J1D01*
G01X654141D01*
G02X653938Y1609168I-1J202D01*
G01Y1609790D01*
G03X653888Y1609922I-200J0D01*
G02Y1612834I1664J1456D01*
G03X653938Y1612966I-150J132D01*
G01Y1614908D01*
G03X653888Y1615040I-200J0D01*
G02Y1617952I1664J1456D01*
G03X653938Y1618084I-150J132D01*
G01Y1618706D01*
G02X654141Y1618908I203J-1D01*
G37*
G36*
G01X688787D02*
X691607D01*
G02X691810Y1618706I1J-202D01*
G01Y1618084D01*
G03X691860Y1617952I200J0D01*
G02Y1615040I-1664J-1456D01*
G03X691810Y1614908I150J-132D01*
G01Y1612966D01*
G03X691860Y1612834I200J0D01*
G02Y1609922I-1664J-1456D01*
G03X691810Y1609790I150J-132D01*
G01Y1609168D01*
G02X691607Y1608966I-203J1D01*
G01X688787D01*
G02X688584Y1609168I-1J202D01*
G01Y1609790D01*
G03X688534Y1609922I-200J0D01*
G02Y1612834I1664J1456D01*
G03X688584Y1612966I-150J132D01*
G01Y1614908D01*
G03X688534Y1615040I-200J0D01*
G02Y1617952I1664J1456D01*
G03X688584Y1618084I-150J132D01*
G01Y1618706D01*
G02X688787Y1618908I203J-1D01*
G37*
G36*
G01X1139101D02*
X1141921D01*
G02X1142124Y1618706I1J-202D01*
G01Y1618084D01*
G03X1142174Y1617952I200J0D01*
G02Y1615040I-1664J-1456D01*
G03X1142124Y1614908I150J-132D01*
G01Y1612966D01*
G03X1142174Y1612834I200J0D01*
G02Y1609922I-1664J-1456D01*
G03X1142124Y1609790I150J-132D01*
G01Y1609168D01*
G02X1141921Y1608966I-203J1D01*
G01X1139101D01*
G02X1138898Y1609168I-1J202D01*
G01Y1609790D01*
G03X1138848Y1609922I-200J0D01*
G02Y1612834I1664J1456D01*
G03X1138898Y1612966I-150J132D01*
G01Y1614908D01*
G03X1138848Y1615040I-200J0D01*
G02Y1617952I1664J1456D01*
G03X1138898Y1618084I-150J132D01*
G01Y1618706D01*
G02X1139101Y1618908I203J-1D01*
G37*
G36*
G01X1173747D02*
X1176567D01*
G02X1176770Y1618706I1J-202D01*
G01Y1618084D01*
G03X1176820Y1617952I200J0D01*
G02Y1615040I-1664J-1456D01*
G03X1176770Y1614908I150J-132D01*
G01Y1612966D01*
G03X1176820Y1612834I200J0D01*
G02Y1609922I-1664J-1456D01*
G03X1176770Y1609790I150J-132D01*
G01Y1609168D01*
G02X1176567Y1608966I-203J1D01*
G01X1173747D01*
G02X1173544Y1609168I-1J202D01*
G01Y1609790D01*
G03X1173494Y1609922I-200J0D01*
G02Y1612834I1664J1456D01*
G03X1173544Y1612966I-150J132D01*
G01Y1614908D01*
G03X1173494Y1615040I-200J0D01*
G02Y1617952I1664J1456D01*
G03X1173544Y1618084I-150J132D01*
G01Y1618706D01*
G02X1173747Y1618908I203J-1D01*
G37*
G36*
G01X1329653D02*
X1332473D01*
G02X1332676Y1618706I1J-202D01*
G01Y1618084D01*
G03X1332726Y1617952I200J0D01*
G02Y1615040I-1664J-1456D01*
G03X1332676Y1614908I150J-132D01*
G01Y1612966D01*
G03X1332726Y1612834I200J0D01*
G02Y1609922I-1664J-1456D01*
G03X1332676Y1609790I150J-132D01*
G01Y1609168D01*
G02X1332473Y1608966I-203J1D01*
G01X1329653D01*
G02X1329450Y1609168I-1J202D01*
G01Y1609790D01*
G03X1329400Y1609922I-200J0D01*
G02Y1612834I1664J1456D01*
G03X1329450Y1612966I-150J132D01*
G01Y1614908D01*
G03X1329400Y1615040I-200J0D01*
G02Y1617952I1664J1456D01*
G03X1329450Y1618084I-150J132D01*
G01Y1618706D01*
G02X1329653Y1618908I203J-1D01*
G37*
G36*
G01X1364299D02*
X1367119D01*
G02X1367322Y1618706I1J-202D01*
G01Y1618084D01*
G03X1367372Y1617952I200J0D01*
G02Y1615040I-1664J-1456D01*
G03X1367322Y1614908I150J-132D01*
G01Y1612966D01*
G03X1367372Y1612834I200J0D01*
G02Y1609922I-1664J-1456D01*
G03X1367322Y1609790I150J-132D01*
G01Y1609168D01*
G02X1367119Y1608966I-203J1D01*
G01X1364299D01*
G02X1364096Y1609168I-1J202D01*
G01Y1609790D01*
G03X1364046Y1609922I-200J0D01*
G02Y1612834I1664J1456D01*
G03X1364096Y1612966I-150J132D01*
G01Y1614908D01*
G03X1364046Y1615040I-200J0D01*
G02Y1617952I1664J1456D01*
G03X1364096Y1618084I-150J132D01*
G01Y1618706D01*
G02X1364299Y1618908I203J-1D01*
G37*
G36*
G01X1676109D02*
X1678929D01*
G02X1679132Y1618706I1J-202D01*
G01Y1618084D01*
G03X1679182Y1617952I200J0D01*
G02Y1615040I-1664J-1456D01*
G03X1679132Y1614908I150J-132D01*
G01Y1612966D01*
G03X1679182Y1612834I200J0D01*
G02Y1609922I-1664J-1456D01*
G03X1679132Y1609790I150J-132D01*
G01Y1609168D01*
G02X1678929Y1608966I-203J1D01*
G01X1676109D01*
G02X1675906Y1609168I-1J202D01*
G01Y1609790D01*
G03X1675856Y1609922I-200J0D01*
G02Y1612834I1664J1456D01*
G03X1675906Y1612966I-150J132D01*
G01Y1614908D01*
G03X1675856Y1615040I-200J0D01*
G02Y1617952I1664J1456D01*
G03X1675906Y1618084I-150J132D01*
G01Y1618706D01*
G02X1676109Y1618908I203J-1D01*
G37*
G36*
G01X1710755D02*
X1713575D01*
G02X1713778Y1618706I1J-202D01*
G01Y1618084D01*
G03X1713828Y1617952I200J0D01*
G02Y1615040I-1664J-1456D01*
G03X1713778Y1614908I150J-132D01*
G01Y1612966D01*
G03X1713828Y1612834I200J0D01*
G02Y1609922I-1664J-1456D01*
G03X1713778Y1609790I150J-132D01*
G01Y1609168D01*
G02X1713575Y1608966I-203J1D01*
G01X1710755D01*
G02X1710552Y1609168I-1J202D01*
G01Y1609790D01*
G03X1710502Y1609922I-200J0D01*
G02Y1612834I1664J1456D01*
G03X1710552Y1612966I-150J132D01*
G01Y1614908D01*
G03X1710502Y1615040I-200J0D01*
G02Y1617952I1664J1456D01*
G03X1710552Y1618084I-150J132D01*
G01Y1618706D01*
G02X1710755Y1618908I203J-1D01*
G37*
G36*
G01X1522570Y1409998D02*
X1525970D01*
G02Y1406992I0J-1503D01*
G01X1522570D01*
G02Y1409998I0J1503D01*
G37*
G36*
G01X1559290Y1349690D02*
X1562690D01*
G02Y1346684I0J-1503D01*
G01X1559290D01*
G02Y1349690I0J1503D01*
G37*
G36*
G01X1522570Y1385800D02*
X1525970D01*
G02Y1382794I0J-1503D01*
G01X1522570D01*
G02Y1385800I0J1503D01*
G37*
G36*
G01Y1373888D02*
X1525970D01*
G02Y1370882I0J-1503D01*
G01X1522570D01*
G02Y1373888I0J1503D01*
G37*
G36*
G01Y1398086D02*
X1525970D01*
G02Y1395080I0J-1503D01*
G01X1522570D01*
G02Y1398086I0J1503D01*
G37*
G36*
G01X1510330Y1373888D02*
X1513730D01*
G02Y1370882I0J-1503D01*
G01X1510330D01*
G02Y1373888I0J1503D01*
G37*
G36*
G01X1547050Y1361602D02*
X1550450D01*
G02Y1358596I0J-1503D01*
G01X1547050D01*
G02Y1361602I0J1503D01*
G37*
G36*
G01X1534810D02*
X1538210D01*
G02Y1358596I0J-1503D01*
G01X1534810D01*
G02Y1361602I0J1503D01*
G37*
G36*
G01X1547050Y1349690D02*
X1550450D01*
G02Y1346684I0J-1503D01*
G01X1547050D01*
G02Y1349690I0J1503D01*
G37*
G36*
G01X1534810D02*
X1538210D01*
G02Y1346684I0J-1503D01*
G01X1534810D01*
G02Y1349690I0J1503D01*
G37*
G36*
G01X241623Y1373888D02*
X245023D01*
G02Y1370882I0J-1503D01*
G01X241623D01*
G02Y1373888I0J1503D01*
G37*
G36*
G01Y1361602D02*
X245023D01*
G02Y1358596I0J-1503D01*
G01X241623D01*
G02Y1361602I0J1503D01*
G37*
G36*
G01X1485850Y1409998D02*
X1489250D01*
G02Y1406992I0J-1503D01*
G01X1485850D01*
G02Y1409998I0J1503D01*
G37*
G36*
G01X1510330Y1349690D02*
X1513730D01*
G02Y1346684I0J-1503D01*
G01X1510330D01*
G02Y1349690I0J1503D01*
G37*
G36*
G01X364023Y1398086D02*
X367423D01*
G02Y1395080I0J-1503D01*
G01X364023D01*
G02Y1398086I0J1503D01*
G37*
G36*
G01X1485850Y1385800D02*
X1489250D01*
G02Y1382794I0J-1503D01*
G01X1485850D01*
G02Y1385800I0J1503D01*
G37*
G36*
G01X1473610D02*
X1477010D01*
G02Y1382794I0J-1503D01*
G01X1473610D01*
G02Y1385800I0J1503D01*
G37*
G36*
G01Y1361602D02*
X1477010D01*
G02Y1358596I0J-1503D01*
G01X1473610D01*
G02Y1361602I0J1503D01*
G37*
G36*
G01Y1349690D02*
X1477010D01*
G02Y1346684I0J-1503D01*
G01X1473610D01*
G02Y1349690I0J1503D01*
G37*
G36*
G01X1461370Y1385800D02*
X1464770D01*
G02Y1382794I0J-1503D01*
G01X1461370D01*
G02Y1385800I0J1503D01*
G37*
G36*
G01Y1373888D02*
X1464770D01*
G02Y1370882I0J-1503D01*
G01X1461370D01*
G02Y1373888I0J1503D01*
G37*
G36*
G01Y1361602D02*
X1464770D01*
G02Y1358596I0J-1503D01*
G01X1461370D01*
G02Y1361602I0J1503D01*
G37*
G36*
G01Y1349690D02*
X1464770D01*
G02Y1346684I0J-1503D01*
G01X1461370D01*
G02Y1349690I0J1503D01*
G37*
G36*
G01X1485850Y1373888D02*
X1489250D01*
G02Y1370882I0J-1503D01*
G01X1485850D01*
G02Y1373888I0J1503D01*
G37*
G36*
G01X1498090Y1361602D02*
X1501490D01*
G02Y1358596I0J-1503D01*
G01X1498090D01*
G02Y1361602I0J1503D01*
G37*
G36*
G01X1485850D02*
X1489250D01*
G02Y1358596I0J-1503D01*
G01X1485850D01*
G02Y1361602I0J1503D01*
G37*
G36*
G01X253863Y1409998D02*
X257263D01*
G02Y1406992I0J-1503D01*
G01X253863D01*
G02Y1409998I0J1503D01*
G37*
G36*
G01X266103Y1373888D02*
X269503D01*
G02Y1370882I0J-1503D01*
G01X266103D01*
G02Y1373888I0J1503D01*
G37*
G36*
G01X290583Y1361602D02*
X293983D01*
G02Y1358596I0J-1503D01*
G01X290583D01*
G02Y1361602I0J1503D01*
G37*
G36*
G01X327303Y1349690D02*
X330703D01*
G02Y1346684I0J-1503D01*
G01X327303D01*
G02Y1349690I0J1503D01*
G37*
G36*
G01X290583Y1385800D02*
X293983D01*
G02Y1382794I0J-1503D01*
G01X290583D01*
G02Y1385800I0J1503D01*
G37*
G36*
G01Y1409998D02*
X293983D01*
G02Y1406992I0J-1503D01*
G01X290583D01*
G02Y1409998I0J1503D01*
G37*
G36*
G01X253863Y1398086D02*
X257263D01*
G02Y1395080I0J-1503D01*
G01X253863D01*
G02Y1398086I0J1503D01*
G37*
G36*
G01X364023Y1361602D02*
X367423D01*
G02Y1358596I0J-1503D01*
G01X364023D01*
G02Y1361602I0J1503D01*
G37*
G36*
G01X339543Y1349690D02*
X342943D01*
G02Y1346684I0J-1503D01*
G01X339543D01*
G02Y1349690I0J1503D01*
G37*
G36*
G01X241623D02*
X245023D01*
G02Y1346684I0J-1503D01*
G01X241623D01*
G02Y1349690I0J1503D01*
G37*
G36*
G01X339543Y1361602D02*
X342943D01*
G02Y1358596I0J-1503D01*
G01X339543D01*
G02Y1361602I0J1503D01*
G37*
G36*
G01X302823Y1409998D02*
X306223D01*
G02Y1406992I0J-1503D01*
G01X302823D01*
G02Y1409998I0J1503D01*
G37*
G36*
G01X364023Y1385800D02*
X367423D01*
G02Y1382794I0J-1503D01*
G01X364023D01*
G02Y1385800I0J1503D01*
G37*
G36*
G01X290583Y1398086D02*
X293983D01*
G02Y1395080I0J-1503D01*
G01X290583D01*
G02Y1398086I0J1503D01*
G37*
G36*
G01X112832D02*
X116232D01*
G02Y1395080I0J-1503D01*
G01X112832D01*
G02Y1398086I0J1503D01*
G37*
G36*
G01X364023Y1373888D02*
X367423D01*
G02Y1370882I0J-1503D01*
G01X364023D01*
G02Y1373888I0J1503D01*
G37*
G36*
G01X302823Y1361602D02*
X306223D01*
G02Y1358596I0J-1503D01*
G01X302823D01*
G02Y1361602I0J1503D01*
G37*
G36*
G01X1534810Y1409998D02*
X1538210D01*
G02Y1406992I0J-1503D01*
G01X1534810D01*
G02Y1409998I0J1503D01*
G37*
G36*
G01X1510330Y1385800D02*
X1513730D01*
G02Y1382794I0J-1503D01*
G01X1510330D01*
G02Y1385800I0J1503D01*
G37*
G36*
G01X1534810Y1398086D02*
X1538210D01*
G02Y1395080I0J-1503D01*
G01X1534810D01*
G02Y1398086I0J1503D01*
G37*
G36*
G01X302823Y1349690D02*
X306223D01*
G02Y1346684I0J-1503D01*
G01X302823D01*
G02Y1349690I0J1503D01*
G37*
G36*
G01X88352Y1373888D02*
X91752D01*
G02Y1370882I0J-1503D01*
G01X88352D01*
G02Y1373888I0J1503D01*
G37*
G36*
G01X339543Y1385800D02*
X342943D01*
G02Y1382794I0J-1503D01*
G01X339543D01*
G02Y1385800I0J1503D01*
G37*
G36*
G01X327303Y1373888D02*
X330703D01*
G02Y1370882I0J-1503D01*
G01X327303D01*
G02Y1373888I0J1503D01*
G37*
G36*
G01Y1409998D02*
X330703D01*
G02Y1406992I0J-1503D01*
G01X327303D01*
G02Y1409998I0J1503D01*
G37*
G36*
G01X278343Y1398086D02*
X281743D01*
G02Y1395080I0J-1503D01*
G01X278343D01*
G02Y1398086I0J1503D01*
G37*
G36*
G01X351783Y1349690D02*
X355183D01*
G02Y1346684I0J-1503D01*
G01X351783D01*
G02Y1349690I0J1503D01*
G37*
G36*
G01X186272Y1385800D02*
X189672D01*
G02Y1382794I0J-1503D01*
G01X186272D01*
G02Y1385800I0J1503D01*
G37*
G36*
G01Y1373888D02*
X189672D01*
G02Y1370882I0J-1503D01*
G01X186272D01*
G02Y1373888I0J1503D01*
G37*
G36*
G01X315063Y1361602D02*
X318463D01*
G02Y1358596I0J-1503D01*
G01X315063D01*
G02Y1361602I0J1503D01*
G37*
G36*
G01X327303D02*
X330703D01*
G02Y1358596I0J-1503D01*
G01X327303D01*
G02Y1361602I0J1503D01*
G37*
G36*
G01X315063Y1349690D02*
X318463D01*
G02Y1346684I0J-1503D01*
G01X315063D01*
G02Y1349690I0J1503D01*
G37*
G36*
G01X174032Y1398086D02*
X177432D01*
G02Y1395080I0J-1503D01*
G01X174032D01*
G02Y1398086I0J1503D01*
G37*
G36*
G01X266103Y1349690D02*
X269503D01*
G02Y1346684I0J-1503D01*
G01X266103D01*
G02Y1349690I0J1503D01*
G37*
G36*
G01X1054713Y1361602D02*
X1058113D01*
G02Y1358596I0J-1503D01*
G01X1054713D01*
G02Y1361602I0J1503D01*
G37*
G36*
G01Y1349690D02*
X1058113D01*
G02Y1346684I0J-1503D01*
G01X1054713D01*
G02Y1349690I0J1503D01*
G37*
G36*
G01Y1385800D02*
X1058113D01*
G02Y1382794I0J-1503D01*
G01X1054713D01*
G02Y1385800I0J1503D01*
G37*
G36*
G01Y1373888D02*
X1058113D01*
G02Y1370882I0J-1503D01*
G01X1054713D01*
G02Y1373888I0J1503D01*
G37*
G36*
G01X1177113Y1409998D02*
X1180513D01*
G02Y1406992I0J-1503D01*
G01X1177113D01*
G02Y1409998I0J1503D01*
G37*
G36*
G01Y1398086D02*
X1180513D01*
G02Y1395080I0J-1503D01*
G01X1177113D01*
G02Y1398086I0J1503D01*
G37*
G36*
G01Y1373888D02*
X1180513D01*
G02Y1370882I0J-1503D01*
G01X1177113D01*
G02Y1373888I0J1503D01*
G37*
G36*
G01Y1385800D02*
X1180513D01*
G02Y1382794I0J-1503D01*
G01X1177113D01*
G02Y1385800I0J1503D01*
G37*
G36*
G01Y1361602D02*
X1180513D01*
G02Y1358596I0J-1503D01*
G01X1177113D01*
G02Y1361602I0J1503D01*
G37*
G36*
G01Y1349690D02*
X1180513D01*
G02Y1346684I0J-1503D01*
G01X1177113D01*
G02Y1349690I0J1503D01*
G37*
G36*
G01X1164873Y1409998D02*
X1168273D01*
G02Y1406992I0J-1503D01*
G01X1164873D01*
G02Y1409998I0J1503D01*
G37*
G36*
G01Y1398086D02*
X1168273D01*
G02Y1395080I0J-1503D01*
G01X1164873D01*
G02Y1398086I0J1503D01*
G37*
G36*
G01Y1385800D02*
X1168273D01*
G02Y1382794I0J-1503D01*
G01X1164873D01*
G02Y1385800I0J1503D01*
G37*
G36*
G01Y1373888D02*
X1168273D01*
G02Y1370882I0J-1503D01*
G01X1164873D01*
G02Y1373888I0J1503D01*
G37*
G36*
G01Y1361602D02*
X1168273D01*
G02Y1358596I0J-1503D01*
G01X1164873D01*
G02Y1361602I0J1503D01*
G37*
G36*
G01Y1349690D02*
X1168273D01*
G02Y1346684I0J-1503D01*
G01X1164873D01*
G02Y1349690I0J1503D01*
G37*
G36*
G01X1152633Y1409998D02*
X1156033D01*
G02Y1406992I0J-1503D01*
G01X1152633D01*
G02Y1409998I0J1503D01*
G37*
G36*
G01Y1398086D02*
X1156033D01*
G02Y1395080I0J-1503D01*
G01X1152633D01*
G02Y1398086I0J1503D01*
G37*
G36*
G01Y1373888D02*
X1156033D01*
G02Y1370882I0J-1503D01*
G01X1152633D01*
G02Y1373888I0J1503D01*
G37*
G36*
G01Y1385800D02*
X1156033D01*
G02Y1382794I0J-1503D01*
G01X1152633D01*
G02Y1385800I0J1503D01*
G37*
G36*
G01Y1361602D02*
X1156033D01*
G02Y1358596I0J-1503D01*
G01X1152633D01*
G02Y1361602I0J1503D01*
G37*
G36*
G01Y1349690D02*
X1156033D01*
G02Y1346684I0J-1503D01*
G01X1152633D01*
G02Y1349690I0J1503D01*
G37*
G36*
G01X1128153Y1409998D02*
X1131553D01*
G02Y1406992I0J-1503D01*
G01X1128153D01*
G02Y1409998I0J1503D01*
G37*
G36*
G01X1140393D02*
X1143793D01*
G02Y1406992I0J-1503D01*
G01X1140393D01*
G02Y1409998I0J1503D01*
G37*
G36*
G01X1128153Y1398086D02*
X1131553D01*
G02Y1395080I0J-1503D01*
G01X1128153D01*
G02Y1398086I0J1503D01*
G37*
G36*
G01X1140393D02*
X1143793D01*
G02Y1395080I0J-1503D01*
G01X1140393D01*
G02Y1398086I0J1503D01*
G37*
G36*
G01X1128153Y1373888D02*
X1131553D01*
G02Y1370882I0J-1503D01*
G01X1128153D01*
G02Y1373888I0J1503D01*
G37*
G36*
G01Y1385800D02*
X1131553D01*
G02Y1382794I0J-1503D01*
G01X1128153D01*
G02Y1385800I0J1503D01*
G37*
G36*
G01X1140393D02*
X1143793D01*
G02Y1382794I0J-1503D01*
G01X1140393D01*
G02Y1385800I0J1503D01*
G37*
G36*
G01Y1373888D02*
X1143793D01*
G02Y1370882I0J-1503D01*
G01X1140393D01*
G02Y1373888I0J1503D01*
G37*
G36*
G01X1128153Y1361602D02*
X1131553D01*
G02Y1358596I0J-1503D01*
G01X1128153D01*
G02Y1361602I0J1503D01*
G37*
G36*
G01X1140393D02*
X1143793D01*
G02Y1358596I0J-1503D01*
G01X1140393D01*
G02Y1361602I0J1503D01*
G37*
G36*
G01X1128153Y1349690D02*
X1131553D01*
G02Y1346684I0J-1503D01*
G01X1128153D01*
G02Y1349690I0J1503D01*
G37*
G36*
G01X1140393D02*
X1143793D01*
G02Y1346684I0J-1503D01*
G01X1140393D01*
G02Y1349690I0J1503D01*
G37*
G36*
G01X1115913Y1409998D02*
X1119313D01*
G02Y1406992I0J-1503D01*
G01X1115913D01*
G02Y1409998I0J1503D01*
G37*
G36*
G01Y1398086D02*
X1119313D01*
G02Y1395080I0J-1503D01*
G01X1115913D01*
G02Y1398086I0J1503D01*
G37*
G36*
G01Y1373888D02*
X1119313D01*
G02Y1370882I0J-1503D01*
G01X1115913D01*
G02Y1373888I0J1503D01*
G37*
G36*
G01Y1385800D02*
X1119313D01*
G02Y1382794I0J-1503D01*
G01X1115913D01*
G02Y1385800I0J1503D01*
G37*
G36*
G01Y1361602D02*
X1119313D01*
G02Y1358596I0J-1503D01*
G01X1115913D01*
G02Y1361602I0J1503D01*
G37*
G36*
G01Y1349690D02*
X1119313D01*
G02Y1346684I0J-1503D01*
G01X1115913D01*
G02Y1349690I0J1503D01*
G37*
G36*
G01X1103673Y1409998D02*
X1107073D01*
G02Y1406992I0J-1503D01*
G01X1103673D01*
G02Y1409998I0J1503D01*
G37*
G36*
G01Y1398086D02*
X1107073D01*
G02Y1395080I0J-1503D01*
G01X1103673D01*
G02Y1398086I0J1503D01*
G37*
G36*
G01Y1385800D02*
X1107073D01*
G02Y1382794I0J-1503D01*
G01X1103673D01*
G02Y1385800I0J1503D01*
G37*
G36*
G01Y1373888D02*
X1107073D01*
G02Y1370882I0J-1503D01*
G01X1103673D01*
G02Y1373888I0J1503D01*
G37*
G36*
G01Y1361602D02*
X1107073D01*
G02Y1358596I0J-1503D01*
G01X1103673D01*
G02Y1361602I0J1503D01*
G37*
G36*
G01Y1349690D02*
X1107073D01*
G02Y1346684I0J-1503D01*
G01X1103673D01*
G02Y1349690I0J1503D01*
G37*
G36*
G01X1079193Y1409998D02*
X1082593D01*
G02Y1406992I0J-1503D01*
G01X1079193D01*
G02Y1409998I0J1503D01*
G37*
G36*
G01X1091433D02*
X1094833D01*
G02Y1406992I0J-1503D01*
G01X1091433D01*
G02Y1409998I0J1503D01*
G37*
G36*
G01X1079193Y1398086D02*
X1082593D01*
G02Y1395080I0J-1503D01*
G01X1079193D01*
G02Y1398086I0J1503D01*
G37*
G36*
G01X1091433D02*
X1094833D01*
G02Y1395080I0J-1503D01*
G01X1091433D01*
G02Y1398086I0J1503D01*
G37*
G36*
G01X1079193Y1385800D02*
X1082593D01*
G02Y1382794I0J-1503D01*
G01X1079193D01*
G02Y1385800I0J1503D01*
G37*
G36*
G01Y1373888D02*
X1082593D01*
G02Y1370882I0J-1503D01*
G01X1079193D01*
G02Y1373888I0J1503D01*
G37*
G36*
G01X1091433Y1385800D02*
X1094833D01*
G02Y1382794I0J-1503D01*
G01X1091433D01*
G02Y1385800I0J1503D01*
G37*
G36*
G01Y1373888D02*
X1094833D01*
G02Y1370882I0J-1503D01*
G01X1091433D01*
G02Y1373888I0J1503D01*
G37*
G36*
G01X1079193Y1361602D02*
X1082593D01*
G02Y1358596I0J-1503D01*
G01X1079193D01*
G02Y1361602I0J1503D01*
G37*
G36*
G01X1091433D02*
X1094833D01*
G02Y1358596I0J-1503D01*
G01X1091433D01*
G02Y1361602I0J1503D01*
G37*
G36*
G01X1079193Y1349690D02*
X1082593D01*
G02Y1346684I0J-1503D01*
G01X1079193D01*
G02Y1349690I0J1503D01*
G37*
G36*
G01X1091433D02*
X1094833D01*
G02Y1346684I0J-1503D01*
G01X1091433D01*
G02Y1349690I0J1503D01*
G37*
G36*
G01X1066953Y1409998D02*
X1070353D01*
G02Y1406992I0J-1503D01*
G01X1066953D01*
G02Y1409998I0J1503D01*
G37*
G36*
G01Y1398086D02*
X1070353D01*
G02Y1395080I0J-1503D01*
G01X1066953D01*
G02Y1398086I0J1503D01*
G37*
G36*
G01X290583Y1349690D02*
X293983D01*
G02Y1346684I0J-1503D01*
G01X290583D01*
G02Y1349690I0J1503D01*
G37*
G36*
G01X241623Y1385800D02*
X245023D01*
G02Y1382794I0J-1503D01*
G01X241623D01*
G02Y1385800I0J1503D01*
G37*
G36*
G01X253863Y1361602D02*
X257263D01*
G02Y1358596I0J-1503D01*
G01X253863D01*
G02Y1361602I0J1503D01*
G37*
G36*
G01Y1349690D02*
X257263D01*
G02Y1346684I0J-1503D01*
G01X253863D01*
G02Y1349690I0J1503D01*
G37*
G36*
G01X1547050Y1409998D02*
X1550450D01*
G02Y1406992I0J-1503D01*
G01X1547050D01*
G02Y1409998I0J1503D01*
G37*
G36*
G01X1559290Y1385800D02*
X1562690D01*
G02Y1382794I0J-1503D01*
G01X1559290D01*
G02Y1385800I0J1503D01*
G37*
G36*
G01X1230326Y1349690D02*
X1233726D01*
G02Y1346684I0J-1503D01*
G01X1230326D01*
G02Y1349690I0J1503D01*
G37*
G36*
G01Y1361602D02*
X1233726D01*
G02Y1358596I0J-1503D01*
G01X1230326D01*
G02Y1361602I0J1503D01*
G37*
G36*
G01Y1373888D02*
X1233726D01*
G02Y1370882I0J-1503D01*
G01X1230326D01*
G02Y1373888I0J1503D01*
G37*
G36*
G01Y1385800D02*
X1233726D01*
G02Y1382794I0J-1503D01*
G01X1230326D01*
G02Y1385800I0J1503D01*
G37*
G36*
G01X1242566Y1349690D02*
X1245966D01*
G02Y1346684I0J-1503D01*
G01X1242566D01*
G02Y1349690I0J1503D01*
G37*
G36*
G01Y1361602D02*
X1245966D01*
G02Y1358596I0J-1503D01*
G01X1242566D01*
G02Y1361602I0J1503D01*
G37*
G36*
G01Y1385800D02*
X1245966D01*
G02Y1382794I0J-1503D01*
G01X1242566D01*
G02Y1385800I0J1503D01*
G37*
G36*
G01Y1373888D02*
X1245966D01*
G02Y1370882I0J-1503D01*
G01X1242566D01*
G02Y1373888I0J1503D01*
G37*
G36*
G01Y1398086D02*
X1245966D01*
G02Y1395080I0J-1503D01*
G01X1242566D01*
G02Y1398086I0J1503D01*
G37*
G36*
G01Y1409998D02*
X1245966D01*
G02Y1406992I0J-1503D01*
G01X1242566D01*
G02Y1409998I0J1503D01*
G37*
G36*
G01X1267046Y1349690D02*
X1270446D01*
G02Y1346684I0J-1503D01*
G01X1267046D01*
G02Y1349690I0J1503D01*
G37*
G36*
G01X1254806D02*
X1258206D01*
G02Y1346684I0J-1503D01*
G01X1254806D01*
G02Y1349690I0J1503D01*
G37*
G36*
G01X1267046Y1361602D02*
X1270446D01*
G02Y1358596I0J-1503D01*
G01X1267046D01*
G02Y1361602I0J1503D01*
G37*
G36*
G01X1254806D02*
X1258206D01*
G02Y1358596I0J-1503D01*
G01X1254806D01*
G02Y1361602I0J1503D01*
G37*
G36*
G01X1267046Y1385800D02*
X1270446D01*
G02Y1382794I0J-1503D01*
G01X1267046D01*
G02Y1385800I0J1503D01*
G37*
G36*
G01Y1373888D02*
X1270446D01*
G02Y1370882I0J-1503D01*
G01X1267046D01*
G02Y1373888I0J1503D01*
G37*
G36*
G01X1254806D02*
X1258206D01*
G02Y1370882I0J-1503D01*
G01X1254806D01*
G02Y1373888I0J1503D01*
G37*
G36*
G01Y1385800D02*
X1258206D01*
G02Y1382794I0J-1503D01*
G01X1254806D01*
G02Y1385800I0J1503D01*
G37*
G36*
G01X1267046Y1398086D02*
X1270446D01*
G02Y1395080I0J-1503D01*
G01X1267046D01*
G02Y1398086I0J1503D01*
G37*
G36*
G01X1254806D02*
X1258206D01*
G02Y1395080I0J-1503D01*
G01X1254806D01*
G02Y1398086I0J1503D01*
G37*
G36*
G01X1267046Y1409998D02*
X1270446D01*
G02Y1406992I0J-1503D01*
G01X1267046D01*
G02Y1409998I0J1503D01*
G37*
G36*
G01X1254806D02*
X1258206D01*
G02Y1406992I0J-1503D01*
G01X1254806D01*
G02Y1409998I0J1503D01*
G37*
G36*
G01X1279286Y1349690D02*
X1282686D01*
G02Y1346684I0J-1503D01*
G01X1279286D01*
G02Y1349690I0J1503D01*
G37*
G36*
G01Y1361602D02*
X1282686D01*
G02Y1358596I0J-1503D01*
G01X1279286D01*
G02Y1361602I0J1503D01*
G37*
G36*
G01X1510330D02*
X1513730D01*
G02Y1358596I0J-1503D01*
G01X1510330D01*
G02Y1361602I0J1503D01*
G37*
G36*
G01X1279286Y1373888D02*
X1282686D01*
G02Y1370882I0J-1503D01*
G01X1279286D01*
G02Y1373888I0J1503D01*
G37*
G36*
G01Y1385800D02*
X1282686D01*
G02Y1382794I0J-1503D01*
G01X1279286D01*
G02Y1385800I0J1503D01*
G37*
G36*
G01X1648118Y1409998D02*
X1651518D01*
G02Y1406992I0J-1503D01*
G01X1648118D01*
G02Y1409998I0J1503D01*
G37*
G36*
G01X1279286Y1398086D02*
X1282686D01*
G02Y1395080I0J-1503D01*
G01X1279286D01*
G02Y1398086I0J1503D01*
G37*
G36*
G01Y1409998D02*
X1282686D01*
G02Y1406992I0J-1503D01*
G01X1279286D01*
G02Y1409998I0J1503D01*
G37*
G36*
G01X1291526Y1349690D02*
X1294926D01*
G02Y1346684I0J-1503D01*
G01X1291526D01*
G02Y1349690I0J1503D01*
G37*
G36*
G01X1559290Y1398086D02*
X1562690D01*
G02Y1395080I0J-1503D01*
G01X1559290D01*
G02Y1398086I0J1503D01*
G37*
G36*
G01X161792Y1409998D02*
X165192D01*
G02Y1406992I0J-1503D01*
G01X161792D01*
G02Y1409998I0J1503D01*
G37*
G36*
G01X186272Y1349690D02*
X189672D01*
G02Y1346684I0J-1503D01*
G01X186272D01*
G02Y1349690I0J1503D01*
G37*
G36*
G01X315063Y1409998D02*
X318463D01*
G02Y1406992I0J-1503D01*
G01X315063D01*
G02Y1409998I0J1503D01*
G37*
G36*
G01X1534810Y1373888D02*
X1538210D01*
G02Y1370882I0J-1503D01*
G01X1534810D01*
G02Y1373888I0J1503D01*
G37*
G36*
G01X1559290Y1409998D02*
X1562690D01*
G02Y1406992I0J-1503D01*
G01X1559290D01*
G02Y1409998I0J1503D01*
G37*
G36*
G01X351783Y1361602D02*
X355183D01*
G02Y1358596I0J-1503D01*
G01X351783D01*
G02Y1361602I0J1503D01*
G37*
G36*
G01X198512Y1385800D02*
X201912D01*
G02Y1382794I0J-1503D01*
G01X198512D01*
G02Y1385800I0J1503D01*
G37*
G36*
G01X1291526Y1361602D02*
X1294926D01*
G02Y1358596I0J-1503D01*
G01X1291526D01*
G02Y1361602I0J1503D01*
G37*
G36*
G01X1635878Y1349690D02*
X1639278D01*
G02Y1346684I0J-1503D01*
G01X1635878D01*
G02Y1349690I0J1503D01*
G37*
G36*
G01Y1361602D02*
X1639278D01*
G02Y1358596I0J-1503D01*
G01X1635878D01*
G02Y1361602I0J1503D01*
G37*
G36*
G01X1291526Y1385800D02*
X1294926D01*
G02Y1382794I0J-1503D01*
G01X1291526D01*
G02Y1385800I0J1503D01*
G37*
G36*
G01Y1373888D02*
X1294926D01*
G02Y1370882I0J-1503D01*
G01X1291526D01*
G02Y1373888I0J1503D01*
G37*
G36*
G01X1635878Y1385800D02*
X1639278D01*
G02Y1382794I0J-1503D01*
G01X1635878D01*
G02Y1385800I0J1503D01*
G37*
G36*
G01Y1373888D02*
X1639278D01*
G02Y1370882I0J-1503D01*
G01X1635878D01*
G02Y1373888I0J1503D01*
G37*
G36*
G01Y1398086D02*
X1639278D01*
G02Y1395080I0J-1503D01*
G01X1635878D01*
G02Y1398086I0J1503D01*
G37*
G36*
G01X1623638Y1349690D02*
X1627038D01*
G02Y1346684I0J-1503D01*
G01X1623638D01*
G02Y1349690I0J1503D01*
G37*
G36*
G01X1611398D02*
X1614798D01*
G02Y1346684I0J-1503D01*
G01X1611398D01*
G02Y1349690I0J1503D01*
G37*
G36*
G01X1623638Y1361602D02*
X1627038D01*
G02Y1358596I0J-1503D01*
G01X1623638D01*
G02Y1361602I0J1503D01*
G37*
G36*
G01X1291526Y1398086D02*
X1294926D01*
G02Y1395080I0J-1503D01*
G01X1291526D01*
G02Y1398086I0J1503D01*
G37*
G36*
G01Y1409998D02*
X1294926D01*
G02Y1406992I0J-1503D01*
G01X1291526D01*
G02Y1409998I0J1503D01*
G37*
G36*
G01X1316006Y1349690D02*
X1319406D01*
G02Y1346684I0J-1503D01*
G01X1316006D01*
G02Y1349690I0J1503D01*
G37*
G36*
G01X1303766D02*
X1307166D01*
G02Y1346684I0J-1503D01*
G01X1303766D01*
G02Y1349690I0J1503D01*
G37*
G36*
G01X1316006Y1361602D02*
X1319406D01*
G02Y1358596I0J-1503D01*
G01X1316006D01*
G02Y1361602I0J1503D01*
G37*
G36*
G01X1303766D02*
X1307166D01*
G02Y1358596I0J-1503D01*
G01X1303766D01*
G02Y1361602I0J1503D01*
G37*
G36*
G01X1316006Y1385800D02*
X1319406D01*
G02Y1382794I0J-1503D01*
G01X1316006D01*
G02Y1385800I0J1503D01*
G37*
G36*
G01X1611398Y1373888D02*
X1614798D01*
G02Y1370882I0J-1503D01*
G01X1611398D01*
G02Y1373888I0J1503D01*
G37*
G36*
G01Y1385800D02*
X1614798D01*
G02Y1382794I0J-1503D01*
G01X1611398D01*
G02Y1385800I0J1503D01*
G37*
G36*
G01X1623638Y1398086D02*
X1627038D01*
G02Y1395080I0J-1503D01*
G01X1623638D01*
G02Y1398086I0J1503D01*
G37*
G36*
G01X1316006Y1373888D02*
X1319406D01*
G02Y1370882I0J-1503D01*
G01X1316006D01*
G02Y1373888I0J1503D01*
G37*
G36*
G01X1303766D02*
X1307166D01*
G02Y1370882I0J-1503D01*
G01X1303766D01*
G02Y1373888I0J1503D01*
G37*
G36*
G01Y1385800D02*
X1307166D01*
G02Y1382794I0J-1503D01*
G01X1303766D01*
G02Y1385800I0J1503D01*
G37*
G36*
G01X1316006Y1398086D02*
X1319406D01*
G02Y1395080I0J-1503D01*
G01X1316006D01*
G02Y1398086I0J1503D01*
G37*
G36*
G01X1303766D02*
X1307166D01*
G02Y1395080I0J-1503D01*
G01X1303766D01*
G02Y1398086I0J1503D01*
G37*
G36*
G01X1316006Y1409998D02*
X1319406D01*
G02Y1406992I0J-1503D01*
G01X1316006D01*
G02Y1409998I0J1503D01*
G37*
G36*
G01X1303766D02*
X1307166D01*
G02Y1406992I0J-1503D01*
G01X1303766D01*
G02Y1409998I0J1503D01*
G37*
G36*
G01X1623638D02*
X1627038D01*
G02Y1406992I0J-1503D01*
G01X1623638D01*
G02Y1409998I0J1503D01*
G37*
G36*
G01X1328246Y1349690D02*
X1331646D01*
G02Y1346684I0J-1503D01*
G01X1328246D01*
G02Y1349690I0J1503D01*
G37*
G36*
G01Y1361602D02*
X1331646D01*
G02Y1358596I0J-1503D01*
G01X1328246D01*
G02Y1361602I0J1503D01*
G37*
G36*
G01X1648118Y1398086D02*
X1651518D01*
G02Y1395080I0J-1503D01*
G01X1648118D01*
G02Y1398086I0J1503D01*
G37*
G36*
G01Y1373888D02*
X1651518D01*
G02Y1370882I0J-1503D01*
G01X1648118D01*
G02Y1373888I0J1503D01*
G37*
G36*
G01Y1385800D02*
X1651518D01*
G02Y1382794I0J-1503D01*
G01X1648118D01*
G02Y1385800I0J1503D01*
G37*
G36*
G01X1328246Y1373888D02*
X1331646D01*
G02Y1370882I0J-1503D01*
G01X1328246D01*
G02Y1373888I0J1503D01*
G37*
G36*
G01X1648118Y1361602D02*
X1651518D01*
G02Y1358596I0J-1503D01*
G01X1648118D01*
G02Y1361602I0J1503D01*
G37*
G36*
G01Y1349690D02*
X1651518D01*
G02Y1346684I0J-1503D01*
G01X1648118D01*
G02Y1349690I0J1503D01*
G37*
G36*
G01X1635878Y1409998D02*
X1639278D01*
G02Y1406992I0J-1503D01*
G01X1635878D01*
G02Y1409998I0J1503D01*
G37*
G36*
G01X1660358D02*
X1663758D01*
G02Y1406992I0J-1503D01*
G01X1660358D01*
G02Y1409998I0J1503D01*
G37*
G36*
G01X1672598D02*
X1675998D01*
G02Y1406992I0J-1503D01*
G01X1672598D01*
G02Y1409998I0J1503D01*
G37*
G36*
G01X1660358Y1398086D02*
X1663758D01*
G02Y1395080I0J-1503D01*
G01X1660358D01*
G02Y1398086I0J1503D01*
G37*
G36*
G01X1672598D02*
X1675998D01*
G02Y1395080I0J-1503D01*
G01X1672598D01*
G02Y1398086I0J1503D01*
G37*
G36*
G01X1660358Y1373888D02*
X1663758D01*
G02Y1370882I0J-1503D01*
G01X1660358D01*
G02Y1373888I0J1503D01*
G37*
G36*
G01Y1385800D02*
X1663758D01*
G02Y1382794I0J-1503D01*
G01X1660358D01*
G02Y1385800I0J1503D01*
G37*
G36*
G01X1672598Y1373888D02*
X1675998D01*
G02Y1370882I0J-1503D01*
G01X1672598D01*
G02Y1373888I0J1503D01*
G37*
G36*
G01X1328246Y1385800D02*
X1331646D01*
G02Y1382794I0J-1503D01*
G01X1328246D01*
G02Y1385800I0J1503D01*
G37*
G36*
G01X1672598D02*
X1675998D01*
G02Y1382794I0J-1503D01*
G01X1672598D01*
G02Y1385800I0J1503D01*
G37*
G36*
G01X174032Y1409998D02*
X177432D01*
G02Y1406992I0J-1503D01*
G01X174032D01*
G02Y1409998I0J1503D01*
G37*
G36*
G01X266103Y1385800D02*
X269503D01*
G02Y1382794I0J-1503D01*
G01X266103D01*
G02Y1385800I0J1503D01*
G37*
G36*
G01X315063D02*
X318463D01*
G02Y1382794I0J-1503D01*
G01X315063D01*
G02Y1385800I0J1503D01*
G37*
G36*
G01X278343Y1409998D02*
X281743D01*
G02Y1406992I0J-1503D01*
G01X278343D01*
G02Y1409998I0J1503D01*
G37*
G36*
G01X1328246Y1398086D02*
X1331646D01*
G02Y1395080I0J-1503D01*
G01X1328246D01*
G02Y1398086I0J1503D01*
G37*
G36*
G01X364023Y1409998D02*
X367423D01*
G02Y1406992I0J-1503D01*
G01X364023D01*
G02Y1409998I0J1503D01*
G37*
G36*
G01X266103D02*
X269503D01*
G02Y1406992I0J-1503D01*
G01X266103D01*
G02Y1409998I0J1503D01*
G37*
G36*
G01X1733798Y1385800D02*
X1737198D01*
G02Y1382794I0J-1503D01*
G01X1733798D01*
G02Y1385800I0J1503D01*
G37*
G36*
G01Y1373888D02*
X1737198D01*
G02Y1370882I0J-1503D01*
G01X1733798D01*
G02Y1373888I0J1503D01*
G37*
G36*
G01Y1398086D02*
X1737198D01*
G02Y1395080I0J-1503D01*
G01X1733798D01*
G02Y1398086I0J1503D01*
G37*
G36*
G01X1721558Y1373888D02*
X1724958D01*
G02Y1370882I0J-1503D01*
G01X1721558D01*
G02Y1373888I0J1503D01*
G37*
G36*
G01X290583D02*
X293983D01*
G02Y1370882I0J-1503D01*
G01X290583D01*
G02Y1373888I0J1503D01*
G37*
G36*
G01X1328246Y1409998D02*
X1331646D01*
G02Y1406992I0J-1503D01*
G01X1328246D01*
G02Y1409998I0J1503D01*
G37*
G36*
G01X1340486Y1349690D02*
X1343886D01*
G02Y1346684I0J-1503D01*
G01X1340486D01*
G02Y1349690I0J1503D01*
G37*
G36*
G01X1583770Y1373888D02*
X1587170D01*
G02Y1370882I0J-1503D01*
G01X1583770D01*
G02Y1373888I0J1503D01*
G37*
G36*
G01X1485850Y1349690D02*
X1489250D01*
G02Y1346684I0J-1503D01*
G01X1485850D01*
G02Y1349690I0J1503D01*
G37*
G36*
G01X1340486Y1361602D02*
X1343886D01*
G02Y1358596I0J-1503D01*
G01X1340486D01*
G02Y1361602I0J1503D01*
G37*
G36*
G01X1733798Y1409998D02*
X1737198D01*
G02Y1406992I0J-1503D01*
G01X1733798D01*
G02Y1409998I0J1503D01*
G37*
G36*
G01X278343Y1373888D02*
X281743D01*
G02Y1370882I0J-1503D01*
G01X278343D01*
G02Y1373888I0J1503D01*
G37*
G36*
G01X266103Y1398086D02*
X269503D01*
G02Y1395080I0J-1503D01*
G01X266103D01*
G02Y1398086I0J1503D01*
G37*
G36*
G01X1733798Y1349690D02*
X1737198D01*
G02Y1346684I0J-1503D01*
G01X1733798D01*
G02Y1349690I0J1503D01*
G37*
G36*
G01X137312Y1385800D02*
X140712D01*
G02Y1382794I0J-1503D01*
G01X137312D01*
G02Y1385800I0J1503D01*
G37*
G36*
G01X1721558Y1398086D02*
X1724958D01*
G02Y1395080I0J-1503D01*
G01X1721558D01*
G02Y1398086I0J1503D01*
G37*
G36*
G01X1340486Y1385800D02*
X1343886D01*
G02Y1382794I0J-1503D01*
G01X1340486D01*
G02Y1385800I0J1503D01*
G37*
G36*
G01Y1373888D02*
X1343886D01*
G02Y1370882I0J-1503D01*
G01X1340486D01*
G02Y1373888I0J1503D01*
G37*
G36*
G01X1721558Y1385800D02*
X1724958D01*
G02Y1382794I0J-1503D01*
G01X1721558D01*
G02Y1385800I0J1503D01*
G37*
G36*
G01X339543Y1398086D02*
X342943D01*
G02Y1395080I0J-1503D01*
G01X339543D01*
G02Y1398086I0J1503D01*
G37*
G36*
G01X327303Y1385800D02*
X330703D01*
G02Y1382794I0J-1503D01*
G01X327303D01*
G02Y1385800I0J1503D01*
G37*
G36*
G01X315063Y1373888D02*
X318463D01*
G02Y1370882I0J-1503D01*
G01X315063D01*
G02Y1373888I0J1503D01*
G37*
G36*
G01X339543D02*
X342943D01*
G02Y1370882I0J-1503D01*
G01X339543D01*
G02Y1373888I0J1503D01*
G37*
G36*
G01X351783Y1385800D02*
X355183D01*
G02Y1382794I0J-1503D01*
G01X351783D01*
G02Y1385800I0J1503D01*
G37*
G36*
G01Y1373888D02*
X355183D01*
G02Y1370882I0J-1503D01*
G01X351783D01*
G02Y1373888I0J1503D01*
G37*
G36*
G01Y1398086D02*
X355183D01*
G02Y1395080I0J-1503D01*
G01X351783D01*
G02Y1398086I0J1503D01*
G37*
G36*
G01Y1409998D02*
X355183D01*
G02Y1406992I0J-1503D01*
G01X351783D01*
G02Y1409998I0J1503D01*
G37*
G36*
G01X315063Y1398086D02*
X318463D01*
G02Y1395080I0J-1503D01*
G01X315063D01*
G02Y1398086I0J1503D01*
G37*
G36*
G01X278343Y1361602D02*
X281743D01*
G02Y1358596I0J-1503D01*
G01X278343D01*
G02Y1361602I0J1503D01*
G37*
G36*
G01X1498090Y1349690D02*
X1501490D01*
G02Y1346684I0J-1503D01*
G01X1498090D01*
G02Y1349690I0J1503D01*
G37*
G36*
G01X266103Y1361602D02*
X269503D01*
G02Y1358596I0J-1503D01*
G01X266103D01*
G02Y1361602I0J1503D01*
G37*
G36*
G01X35825Y1466648D02*
X39225D01*
G02Y1463044I0J-1802D01*
G01X35825D01*
G02Y1466648I0J1802D01*
G37*
G36*
G01X942699Y344560D02*
X939299D01*
G02Y348166I0J1803D01*
G01X942699D01*
G02Y344560I0J-1803D01*
G37*
G36*
G01X942730Y322242D02*
X939330D01*
G02Y325846I0J1802D01*
G01X942730D01*
G02Y322242I0J-1802D01*
G37*
G36*
G01X927963Y342238D02*
X924563D01*
G02Y345844I0J1803D01*
G01X927963D01*
G02Y342238I0J-1803D01*
G37*
G36*
G01X919353Y342348D02*
X915953D01*
G02Y345952I0J1802D01*
G01X919353D01*
G02Y342348I0J-1802D01*
G37*
G36*
G01X302823Y1398086D02*
X306223D01*
G02Y1395080I0J-1503D01*
G01X302823D01*
G02Y1398086I0J1503D01*
G37*
G36*
G01X389015Y794228D02*
X392415D01*
G02Y791222I0J-1503D01*
G01X389015D01*
G02Y794228I0J1503D01*
G37*
G36*
G01X302823Y1373888D02*
X306223D01*
G02Y1370882I0J-1503D01*
G01X302823D01*
G02Y1373888I0J1503D01*
G37*
G36*
G01X1534810Y1385800D02*
X1538210D01*
G02Y1382794I0J-1503D01*
G01X1534810D01*
G02Y1385800I0J1503D01*
G37*
G36*
G01X327303Y1398086D02*
X330703D01*
G02Y1395080I0J-1503D01*
G01X327303D01*
G02Y1398086I0J1503D01*
G37*
G36*
G01X339543Y1409998D02*
X342943D01*
G02Y1406992I0J-1503D01*
G01X339543D01*
G02Y1409998I0J1503D01*
G37*
G36*
G01X302823Y1385800D02*
X306223D01*
G02Y1382794I0J-1503D01*
G01X302823D01*
G02Y1385800I0J1503D01*
G37*
G36*
G01X278343D02*
X281743D01*
G02Y1382794I0J-1503D01*
G01X278343D01*
G02Y1385800I0J1503D01*
G37*
G36*
G01X1340486Y1398086D02*
X1343886D01*
G02Y1395080I0J-1503D01*
G01X1340486D01*
G02Y1398086I0J1503D01*
G37*
G36*
G01Y1409998D02*
X1343886D01*
G02Y1406992I0J-1503D01*
G01X1340486D01*
G02Y1409998I0J1503D01*
G37*
G36*
G01X1583770Y1385800D02*
X1587170D01*
G02Y1382794I0J-1503D01*
G01X1583770D01*
G02Y1385800I0J1503D01*
G37*
G36*
G01X1571530Y1349690D02*
X1574930D01*
G02Y1346684I0J-1503D01*
G01X1571530D01*
G02Y1349690I0J1503D01*
G37*
G36*
G01Y1373888D02*
X1574930D01*
G02Y1370882I0J-1503D01*
G01X1571530D01*
G02Y1373888I0J1503D01*
G37*
G36*
G01Y1385800D02*
X1574930D01*
G02Y1382794I0J-1503D01*
G01X1571530D01*
G02Y1385800I0J1503D01*
G37*
G36*
G01X1473610Y1398086D02*
X1477010D01*
G02Y1395080I0J-1503D01*
G01X1473610D01*
G02Y1398086I0J1503D01*
G37*
G36*
G01Y1409998D02*
X1477010D01*
G02Y1406992I0J-1503D01*
G01X1473610D01*
G02Y1409998I0J1503D01*
G37*
G36*
G01X1583770Y1398086D02*
X1587170D01*
G02Y1395080I0J-1503D01*
G01X1583770D01*
G02Y1398086I0J1503D01*
G37*
G36*
G01Y1409998D02*
X1587170D01*
G02Y1406992I0J-1503D01*
G01X1583770D01*
G02Y1409998I0J1503D01*
G37*
G36*
G01X1485850Y1398086D02*
X1489250D01*
G02Y1395080I0J-1503D01*
G01X1485850D01*
G02Y1398086I0J1503D01*
G37*
G36*
G01X1498090Y1373888D02*
X1501490D01*
G02Y1370882I0J-1503D01*
G01X1498090D01*
G02Y1373888I0J1503D01*
G37*
G36*
G01X1522570Y1361602D02*
X1525970D01*
G02Y1358596I0J-1503D01*
G01X1522570D01*
G02Y1361602I0J1503D01*
G37*
G36*
G01X1498090Y1409998D02*
X1501490D01*
G02Y1406992I0J-1503D01*
G01X1498090D01*
G02Y1409998I0J1503D01*
G37*
G36*
G01X1352726Y1349690D02*
X1356126D01*
G02Y1346684I0J-1503D01*
G01X1352726D01*
G02Y1349690I0J1503D01*
G37*
G36*
G01X1510330Y1398086D02*
X1513730D01*
G02Y1395080I0J-1503D01*
G01X1510330D01*
G02Y1398086I0J1503D01*
G37*
G36*
G01X1611398Y1361602D02*
X1614798D01*
G02Y1358596I0J-1503D01*
G01X1611398D01*
G02Y1361602I0J1503D01*
G37*
G36*
G01X1623638Y1373888D02*
X1627038D01*
G02Y1370882I0J-1503D01*
G01X1623638D01*
G02Y1373888I0J1503D01*
G37*
G36*
G01X1547050D02*
X1550450D01*
G02Y1370882I0J-1503D01*
G01X1547050D01*
G02Y1373888I0J1503D01*
G37*
G36*
G01X1352726Y1361602D02*
X1356126D01*
G02Y1358596I0J-1503D01*
G01X1352726D01*
G02Y1361602I0J1503D01*
G37*
G36*
G01Y1385800D02*
X1356126D01*
G02Y1382794I0J-1503D01*
G01X1352726D01*
G02Y1385800I0J1503D01*
G37*
G36*
G01Y1373888D02*
X1356126D01*
G02Y1370882I0J-1503D01*
G01X1352726D01*
G02Y1373888I0J1503D01*
G37*
G36*
G01X1684838Y1409998D02*
X1688238D01*
G02Y1406992I0J-1503D01*
G01X1684838D01*
G02Y1409998I0J1503D01*
G37*
G36*
G01X1709318Y1373888D02*
X1712718D01*
G02Y1370882I0J-1503D01*
G01X1709318D01*
G02Y1373888I0J1503D01*
G37*
G36*
G01Y1385800D02*
X1712718D01*
G02Y1382794I0J-1503D01*
G01X1709318D01*
G02Y1385800I0J1503D01*
G37*
G36*
G01X1733798Y1361602D02*
X1737198D01*
G02Y1358596I0J-1503D01*
G01X1733798D01*
G02Y1361602I0J1503D01*
G37*
G36*
G01X1697078Y1373888D02*
X1700478D01*
G02Y1370882I0J-1503D01*
G01X1697078D01*
G02Y1373888I0J1503D01*
G37*
G36*
G01X1709318Y1409998D02*
X1712718D01*
G02Y1406992I0J-1503D01*
G01X1709318D01*
G02Y1409998I0J1503D01*
G37*
G36*
G01X1697078Y1398086D02*
X1700478D01*
G02Y1395080I0J-1503D01*
G01X1697078D01*
G02Y1398086I0J1503D01*
G37*
G36*
G01X1709318D02*
X1712718D01*
G02Y1395080I0J-1503D01*
G01X1709318D01*
G02Y1398086I0J1503D01*
G37*
G36*
G01X1721558Y1349690D02*
X1724958D01*
G02Y1346684I0J-1503D01*
G01X1721558D01*
G02Y1349690I0J1503D01*
G37*
G36*
G01Y1361602D02*
X1724958D01*
G02Y1358596I0J-1503D01*
G01X1721558D01*
G02Y1361602I0J1503D01*
G37*
G36*
G01Y1409998D02*
X1724958D01*
G02Y1406992I0J-1503D01*
G01X1721558D01*
G02Y1409998I0J1503D01*
G37*
G36*
G01X1352726Y1398086D02*
X1356126D01*
G02Y1395080I0J-1503D01*
G01X1352726D01*
G02Y1398086I0J1503D01*
G37*
G36*
G01X174032Y1361602D02*
X177432D01*
G02Y1358596I0J-1503D01*
G01X174032D01*
G02Y1361602I0J1503D01*
G37*
G36*
G01X198512Y1349690D02*
X201912D01*
G02Y1346684I0J-1503D01*
G01X198512D01*
G02Y1349690I0J1503D01*
G37*
G36*
G01Y1398086D02*
X201912D01*
G02Y1395080I0J-1503D01*
G01X198512D01*
G02Y1398086I0J1503D01*
G37*
G36*
G01X186272D02*
X189672D01*
G02Y1395080I0J-1503D01*
G01X186272D01*
G02Y1398086I0J1503D01*
G37*
G36*
G01X161792Y1349690D02*
X165192D01*
G02Y1346684I0J-1503D01*
G01X161792D01*
G02Y1349690I0J1503D01*
G37*
G36*
G01X186272Y1361602D02*
X189672D01*
G02Y1358596I0J-1503D01*
G01X186272D01*
G02Y1361602I0J1503D01*
G37*
G36*
G01X100592Y1349690D02*
X103992D01*
G02Y1346684I0J-1503D01*
G01X100592D01*
G02Y1349690I0J1503D01*
G37*
G36*
G01X112832D02*
X116232D01*
G02Y1346684I0J-1503D01*
G01X112832D01*
G02Y1349690I0J1503D01*
G37*
G36*
G01X149552Y1398086D02*
X152952D01*
G02Y1395080I0J-1503D01*
G01X149552D01*
G02Y1398086I0J1503D01*
G37*
G36*
G01X161792D02*
X165192D01*
G02Y1395080I0J-1503D01*
G01X161792D01*
G02Y1398086I0J1503D01*
G37*
G36*
G01Y1373888D02*
X165192D01*
G02Y1370882I0J-1503D01*
G01X161792D01*
G02Y1373888I0J1503D01*
G37*
G36*
G01Y1385800D02*
X165192D01*
G02Y1382794I0J-1503D01*
G01X161792D01*
G02Y1385800I0J1503D01*
G37*
G36*
G01X198512Y1361602D02*
X201912D01*
G02Y1358596I0J-1503D01*
G01X198512D01*
G02Y1361602I0J1503D01*
G37*
G36*
G01X137312D02*
X140712D01*
G02Y1358596I0J-1503D01*
G01X137312D01*
G02Y1361602I0J1503D01*
G37*
G36*
G01X161792D02*
X165192D01*
G02Y1358596I0J-1503D01*
G01X161792D01*
G02Y1361602I0J1503D01*
G37*
G36*
G01X149552Y1349690D02*
X152952D01*
G02Y1346684I0J-1503D01*
G01X149552D01*
G02Y1349690I0J1503D01*
G37*
G36*
G01X137312D02*
X140712D01*
G02Y1346684I0J-1503D01*
G01X137312D01*
G02Y1349690I0J1503D01*
G37*
G36*
G01X76112Y1361602D02*
X79512D01*
G02Y1358596I0J-1503D01*
G01X76112D01*
G02Y1361602I0J1503D01*
G37*
G36*
G01X174032Y1385800D02*
X177432D01*
G02Y1382794I0J-1503D01*
G01X174032D01*
G02Y1385800I0J1503D01*
G37*
G36*
G01X125072Y1409998D02*
X128472D01*
G02Y1406992I0J-1503D01*
G01X125072D01*
G02Y1409998I0J1503D01*
G37*
G36*
G01Y1398086D02*
X128472D01*
G02Y1395080I0J-1503D01*
G01X125072D01*
G02Y1398086I0J1503D01*
G37*
G36*
G01Y1373888D02*
X128472D01*
G02Y1370882I0J-1503D01*
G01X125072D01*
G02Y1373888I0J1503D01*
G37*
G36*
G01Y1385800D02*
X128472D01*
G02Y1382794I0J-1503D01*
G01X125072D01*
G02Y1385800I0J1503D01*
G37*
G36*
G01X1571530Y1361602D02*
X1574930D01*
G02Y1358596I0J-1503D01*
G01X1571530D01*
G02Y1361602I0J1503D01*
G37*
G36*
G01X100592Y1385800D02*
X103992D01*
G02Y1382794I0J-1503D01*
G01X100592D01*
G02Y1385800I0J1503D01*
G37*
G36*
G01X76112Y1373888D02*
X79512D01*
G02Y1370882I0J-1503D01*
G01X76112D01*
G02Y1373888I0J1503D01*
G37*
G36*
G01X88352Y1409998D02*
X91752D01*
G02Y1406992I0J-1503D01*
G01X88352D01*
G02Y1409998I0J1503D01*
G37*
G36*
G01X149552D02*
X152952D01*
G02Y1406992I0J-1503D01*
G01X149552D01*
G02Y1409998I0J1503D01*
G37*
G36*
G01X137312Y1373888D02*
X140712D01*
G02Y1370882I0J-1503D01*
G01X137312D01*
G02Y1373888I0J1503D01*
G37*
G36*
G01X253863Y1385800D02*
X257263D01*
G02Y1382794I0J-1503D01*
G01X253863D01*
G02Y1385800I0J1503D01*
G37*
G36*
G01X186272Y1409998D02*
X189672D01*
G02Y1406992I0J-1503D01*
G01X186272D01*
G02Y1409998I0J1503D01*
G37*
G36*
G01X125072Y1361602D02*
X128472D01*
G02Y1358596I0J-1503D01*
G01X125072D01*
G02Y1361602I0J1503D01*
G37*
G36*
G01Y1349690D02*
X128472D01*
G02Y1346684I0J-1503D01*
G01X125072D01*
G02Y1349690I0J1503D01*
G37*
G36*
G01X149552Y1373888D02*
X152952D01*
G02Y1370882I0J-1503D01*
G01X149552D01*
G02Y1373888I0J1503D01*
G37*
G36*
G01X174032Y1349690D02*
X177432D01*
G02Y1346684I0J-1503D01*
G01X174032D01*
G02Y1349690I0J1503D01*
G37*
G36*
G01Y1373888D02*
X177432D01*
G02Y1370882I0J-1503D01*
G01X174032D01*
G02Y1373888I0J1503D01*
G37*
G36*
G01X76112Y1385800D02*
X79512D01*
G02Y1382794I0J-1503D01*
G01X76112D01*
G02Y1385800I0J1503D01*
G37*
G36*
G01X1583770Y1349690D02*
X1587170D01*
G02Y1346684I0J-1503D01*
G01X1583770D01*
G02Y1349690I0J1503D01*
G37*
G36*
G01X1697078Y1385800D02*
X1700478D01*
G02Y1382794I0J-1503D01*
G01X1697078D01*
G02Y1385800I0J1503D01*
G37*
G36*
G01X88352Y1361602D02*
X91752D01*
G02Y1358596I0J-1503D01*
G01X88352D01*
G02Y1361602I0J1503D01*
G37*
G36*
G01Y1349690D02*
X91752D01*
G02Y1346684I0J-1503D01*
G01X88352D01*
G02Y1349690I0J1503D01*
G37*
G36*
G01X1697078Y1409998D02*
X1700478D01*
G02Y1406992I0J-1503D01*
G01X1697078D01*
G02Y1409998I0J1503D01*
G37*
G36*
G01X112832Y1373888D02*
X116232D01*
G02Y1370882I0J-1503D01*
G01X112832D01*
G02Y1373888I0J1503D01*
G37*
G36*
G01Y1409998D02*
X116232D01*
G02Y1406992I0J-1503D01*
G01X112832D01*
G02Y1409998I0J1503D01*
G37*
G36*
G01X100592D02*
X103992D01*
G02Y1406992I0J-1503D01*
G01X100592D01*
G02Y1409998I0J1503D01*
G37*
G36*
G01X724208Y1385800D02*
X727608D01*
G02Y1382794I0J-1503D01*
G01X724208D01*
G02Y1385800I0J1503D01*
G37*
G36*
G01X88352D02*
X91752D01*
G02Y1382794I0J-1503D01*
G01X88352D01*
G02Y1385800I0J1503D01*
G37*
G36*
G01X760928Y1361602D02*
X764328D01*
G02Y1358596I0J-1503D01*
G01X760928D01*
G02Y1361602I0J1503D01*
G37*
G36*
G01X100592Y1373888D02*
X103992D01*
G02Y1370882I0J-1503D01*
G01X100592D01*
G02Y1373888I0J1503D01*
G37*
G36*
G01X137312Y1398086D02*
X140712D01*
G02Y1395080I0J-1503D01*
G01X137312D01*
G02Y1398086I0J1503D01*
G37*
G36*
G01Y1409998D02*
X140712D01*
G02Y1406992I0J-1503D01*
G01X137312D01*
G02Y1409998I0J1503D01*
G37*
G36*
G01X112832Y1385800D02*
X116232D01*
G02Y1382794I0J-1503D01*
G01X112832D01*
G02Y1385800I0J1503D01*
G37*
G36*
G01X663008Y1361602D02*
X666408D01*
G02Y1358596I0J-1503D01*
G01X663008D01*
G02Y1361602I0J1503D01*
G37*
G36*
G01X100592Y1398086D02*
X103992D01*
G02Y1395080I0J-1503D01*
G01X100592D01*
G02Y1398086I0J1503D01*
G37*
G36*
G01X748688Y1385800D02*
X752088D01*
G02Y1382794I0J-1503D01*
G01X748688D01*
G02Y1385800I0J1503D01*
G37*
G36*
G01X1352726Y1409998D02*
X1356126D01*
G02Y1406992I0J-1503D01*
G01X1352726D01*
G02Y1409998I0J1503D01*
G37*
G36*
G01X100592Y1361602D02*
X103992D01*
G02Y1358596I0J-1503D01*
G01X100592D01*
G02Y1361602I0J1503D01*
G37*
G36*
G01X112832D02*
X116232D01*
G02Y1358596I0J-1503D01*
G01X112832D01*
G02Y1361602I0J1503D01*
G37*
G36*
G01X88352Y1398086D02*
X91752D01*
G02Y1395080I0J-1503D01*
G01X88352D01*
G02Y1398086I0J1503D01*
G37*
G36*
G01X1660358Y1361602D02*
X1663758D01*
G02Y1358596I0J-1503D01*
G01X1660358D01*
G02Y1361602I0J1503D01*
G37*
G36*
G01X1066953Y1349690D02*
X1070353D01*
G02Y1346684I0J-1503D01*
G01X1066953D01*
G02Y1349690I0J1503D01*
G37*
G36*
G01X663008D02*
X666408D01*
G02Y1346684I0J-1503D01*
G01X663008D01*
G02Y1349690I0J1503D01*
G37*
G36*
G01X1583770Y1361602D02*
X1587170D01*
G02Y1358596I0J-1503D01*
G01X1583770D01*
G02Y1361602I0J1503D01*
G37*
G36*
G01X1571530Y1398086D02*
X1574930D01*
G02Y1395080I0J-1503D01*
G01X1571530D01*
G02Y1398086I0J1503D01*
G37*
G36*
G01X1559290Y1361602D02*
X1562690D01*
G02Y1358596I0J-1503D01*
G01X1559290D01*
G02Y1361602I0J1503D01*
G37*
G36*
G01Y1373888D02*
X1562690D01*
G02Y1370882I0J-1503D01*
G01X1559290D01*
G02Y1373888I0J1503D01*
G37*
G36*
G01X1623638Y1385800D02*
X1627038D01*
G02Y1382794I0J-1503D01*
G01X1623638D01*
G02Y1385800I0J1503D01*
G37*
G36*
G01X76112Y1349690D02*
X79512D01*
G02Y1346684I0J-1503D01*
G01X76112D01*
G02Y1349690I0J1503D01*
G37*
G36*
G01X1066953Y1361602D02*
X1070353D01*
G02Y1358596I0J-1503D01*
G01X1066953D01*
G02Y1361602I0J1503D01*
G37*
G36*
G01X1547050Y1385800D02*
X1550450D01*
G02Y1382794I0J-1503D01*
G01X1547050D01*
G02Y1385800I0J1503D01*
G37*
G36*
G01X1672598Y1349690D02*
X1675998D01*
G02Y1346684I0J-1503D01*
G01X1672598D01*
G02Y1349690I0J1503D01*
G37*
G36*
G01X1660358D02*
X1663758D01*
G02Y1346684I0J-1503D01*
G01X1660358D01*
G02Y1349690I0J1503D01*
G37*
G36*
G01X1672598Y1361602D02*
X1675998D01*
G02Y1358596I0J-1503D01*
G01X1672598D01*
G02Y1361602I0J1503D01*
G37*
G36*
G01X1709318Y1349690D02*
X1712718D01*
G02Y1346684I0J-1503D01*
G01X1709318D01*
G02Y1349690I0J1503D01*
G37*
G36*
G01X1697078D02*
X1700478D01*
G02Y1346684I0J-1503D01*
G01X1697078D01*
G02Y1349690I0J1503D01*
G37*
G36*
G01X1684838Y1385800D02*
X1688238D01*
G02Y1382794I0J-1503D01*
G01X1684838D01*
G02Y1385800I0J1503D01*
G37*
G36*
G01X1709318Y1361602D02*
X1712718D01*
G02Y1358596I0J-1503D01*
G01X1709318D01*
G02Y1361602I0J1503D01*
G37*
G36*
G01X1697078D02*
X1700478D01*
G02Y1358596I0J-1503D01*
G01X1697078D01*
G02Y1361602I0J1503D01*
G37*
G36*
G01X1684838D02*
X1688238D01*
G02Y1358596I0J-1503D01*
G01X1684838D01*
G02Y1361602I0J1503D01*
G37*
G36*
G01Y1373888D02*
X1688238D01*
G02Y1370882I0J-1503D01*
G01X1684838D01*
G02Y1373888I0J1503D01*
G37*
G36*
G01Y1398086D02*
X1688238D01*
G02Y1395080I0J-1503D01*
G01X1684838D01*
G02Y1398086I0J1503D01*
G37*
G36*
G01X1066953Y1373888D02*
X1070353D01*
G02Y1370882I0J-1503D01*
G01X1066953D01*
G02Y1373888I0J1503D01*
G37*
G36*
G01Y1385800D02*
X1070353D01*
G02Y1382794I0J-1503D01*
G01X1066953D01*
G02Y1385800I0J1503D01*
G37*
G36*
G01X1547050Y1398086D02*
X1550450D01*
G02Y1395080I0J-1503D01*
G01X1547050D01*
G02Y1398086I0J1503D01*
G37*
G36*
G01X549168Y783102D02*
G02Y780098I0J-1502D01*
G01X545813D01*
X545808D01*
G02X545944Y783092I-38J1502D01*
G01X545956Y783090D01*
X548978D01*
X548990Y783092D01*
G02X549168Y783102I173J-1492D01*
G37*
G36*
G01X278343Y1349690D02*
X281743D01*
G02Y1346684I0J-1503D01*
G01X278343D01*
G02Y1349690I0J1503D01*
G37*
G36*
G01X945982Y888540D02*
X949382D01*
G02Y884936I0J-1802D01*
G01X945982D01*
G02Y888540I0J1802D01*
G37*
G36*
G01X1684838Y1349690D02*
X1688238D01*
G02Y1346684I0J-1503D01*
G01X1684838D01*
G02Y1349690I0J1503D01*
G37*
G36*
G01X1571530Y1409998D02*
X1574930D01*
G02Y1406992I0J-1503D01*
G01X1571530D01*
G02Y1409998I0J1503D01*
G37*
G36*
G01X1473610Y1373888D02*
X1477010D01*
G02Y1370882I0J-1503D01*
G01X1473610D01*
G02Y1373888I0J1503D01*
G37*
G36*
G01X1498090Y1398086D02*
X1501490D01*
G02Y1395080I0J-1503D01*
G01X1498090D01*
G02Y1398086I0J1503D01*
G37*
G36*
G01Y1385800D02*
X1501490D01*
G02Y1382794I0J-1503D01*
G01X1498090D01*
G02Y1385800I0J1503D01*
G37*
G36*
G01X1510330Y1409998D02*
X1513730D01*
G02Y1406992I0J-1503D01*
G01X1510330D01*
G02Y1409998I0J1503D01*
G37*
G36*
G01X1522570Y1349690D02*
X1525970D01*
G02Y1346684I0J-1503D01*
G01X1522570D01*
G02Y1349690I0J1503D01*
G37*
G36*
G01X146948Y1135604D02*
X143208D01*
G02Y1138210I0J1303D01*
G01X146948D01*
G02Y1135604I0J-1303D01*
G37*
G36*
G01X165649Y1131864D02*
X161909D01*
G02Y1134470I0J1303D01*
G01X165649D01*
G02Y1131864I0J-1303D01*
G37*
G36*
G01X154429D02*
X150689D01*
G02Y1134470I0J1303D01*
G01X154429D01*
G02Y1131864I0J-1303D01*
G37*
G36*
G01X173129Y1135604D02*
X169389D01*
G02Y1138210I0J1303D01*
G01X173129D01*
G02Y1135604I0J-1303D01*
G37*
G36*
G01X440402Y1361602D02*
X443802D01*
G02Y1358596I0J-1503D01*
G01X440402D01*
G02Y1361602I0J1503D01*
G37*
G36*
G01Y1349690D02*
X443802D01*
G02Y1346684I0J-1503D01*
G01X440402D01*
G02Y1349690I0J1503D01*
G37*
G36*
G01X452642Y1361602D02*
X456042D01*
G02Y1358596I0J-1503D01*
G01X452642D01*
G02Y1361602I0J1503D01*
G37*
G36*
G01Y1349690D02*
X456042D01*
G02Y1346684I0J-1503D01*
G01X452642D01*
G02Y1349690I0J1503D01*
G37*
G36*
G01X501602Y1385800D02*
X505002D01*
G02Y1382794I0J-1503D01*
G01X501602D01*
G02Y1385800I0J1503D01*
G37*
G36*
G01X513842D02*
X517242D01*
G02Y1382794I0J-1503D01*
G01X513842D01*
G02Y1385800I0J1503D01*
G37*
G36*
G01Y1373888D02*
X517242D01*
G02Y1370882I0J-1503D01*
G01X513842D01*
G02Y1373888I0J1503D01*
G37*
G36*
G01X501602D02*
X505002D01*
G02Y1370882I0J-1503D01*
G01X501602D01*
G02Y1373888I0J1503D01*
G37*
G36*
G01X464882Y1349690D02*
X468282D01*
G02Y1346684I0J-1503D01*
G01X464882D01*
G02Y1349690I0J1503D01*
G37*
G36*
G01X477122D02*
X480522D01*
G02Y1346684I0J-1503D01*
G01X477122D01*
G02Y1349690I0J1503D01*
G37*
G36*
G01X526082Y1385800D02*
X529482D01*
G02Y1382794I0J-1503D01*
G01X526082D01*
G02Y1385800I0J1503D01*
G37*
G36*
G01X538322D02*
X541722D01*
G02Y1382794I0J-1503D01*
G01X538322D01*
G02Y1385800I0J1503D01*
G37*
G36*
G01X526082Y1373888D02*
X529482D01*
G02Y1370882I0J-1503D01*
G01X526082D01*
G02Y1373888I0J1503D01*
G37*
G36*
G01X538322D02*
X541722D01*
G02Y1370882I0J-1503D01*
G01X538322D01*
G02Y1373888I0J1503D01*
G37*
G36*
G01X464882Y1361602D02*
X468282D01*
G02Y1358596I0J-1503D01*
G01X464882D01*
G02Y1361602I0J1503D01*
G37*
G36*
G01X477122D02*
X480522D01*
G02Y1358596I0J-1503D01*
G01X477122D01*
G02Y1361602I0J1503D01*
G37*
G36*
G01X489362Y1349690D02*
X492762D01*
G02Y1346684I0J-1503D01*
G01X489362D01*
G02Y1349690I0J1503D01*
G37*
G36*
G01X440402Y1373888D02*
X443802D01*
G02Y1370882I0J-1503D01*
G01X440402D01*
G02Y1373888I0J1503D01*
G37*
G36*
G01X550562Y1385800D02*
X553962D01*
G02Y1382794I0J-1503D01*
G01X550562D01*
G02Y1385800I0J1503D01*
G37*
G36*
G01Y1373888D02*
X553962D01*
G02Y1370882I0J-1503D01*
G01X550562D01*
G02Y1373888I0J1503D01*
G37*
G36*
G01X489362Y1361602D02*
X492762D01*
G02Y1358596I0J-1503D01*
G01X489362D01*
G02Y1361602I0J1503D01*
G37*
G36*
G01X440402Y1385800D02*
X443802D01*
G02Y1382794I0J-1503D01*
G01X440402D01*
G02Y1385800I0J1503D01*
G37*
G36*
G01X452642Y1373888D02*
X456042D01*
G02Y1370882I0J-1503D01*
G01X452642D01*
G02Y1373888I0J1503D01*
G37*
G36*
G01X562802Y1385800D02*
X566202D01*
G02Y1382794I0J-1503D01*
G01X562802D01*
G02Y1385800I0J1503D01*
G37*
G36*
G01X452642Y1409998D02*
X456042D01*
G02Y1406992I0J-1503D01*
G01X452642D01*
G02Y1409998I0J1503D01*
G37*
G36*
G01Y1398086D02*
X456042D01*
G02Y1395080I0J-1503D01*
G01X452642D01*
G02Y1398086I0J1503D01*
G37*
G36*
G01X562802Y1373888D02*
X566202D01*
G02Y1370882I0J-1503D01*
G01X562802D01*
G02Y1373888I0J1503D01*
G37*
G36*
G01X452642Y1385800D02*
X456042D01*
G02Y1382794I0J-1503D01*
G01X452642D01*
G02Y1385800I0J1503D01*
G37*
G36*
G01X464882Y1409998D02*
X468282D01*
G02Y1406992I0J-1503D01*
G01X464882D01*
G02Y1409998I0J1503D01*
G37*
G36*
G01Y1398086D02*
X468282D01*
G02Y1395080I0J-1503D01*
G01X464882D01*
G02Y1398086I0J1503D01*
G37*
G36*
G01Y1385800D02*
X468282D01*
G02Y1382794I0J-1503D01*
G01X464882D01*
G02Y1385800I0J1503D01*
G37*
G36*
G01X477122D02*
X480522D01*
G02Y1382794I0J-1503D01*
G01X477122D01*
G02Y1385800I0J1503D01*
G37*
G36*
G01Y1373888D02*
X480522D01*
G02Y1370882I0J-1503D01*
G01X477122D01*
G02Y1373888I0J1503D01*
G37*
G36*
G01X464882D02*
X468282D01*
G02Y1370882I0J-1503D01*
G01X464882D01*
G02Y1373888I0J1503D01*
G37*
G36*
G01X489362D02*
X492762D01*
G02Y1370882I0J-1503D01*
G01X489362D01*
G02Y1373888I0J1503D01*
G37*
G36*
G01Y1409998D02*
X492762D01*
G02Y1406992I0J-1503D01*
G01X489362D01*
G02Y1409998I0J1503D01*
G37*
G36*
G01Y1398086D02*
X492762D01*
G02Y1395080I0J-1503D01*
G01X489362D01*
G02Y1398086I0J1503D01*
G37*
G36*
G01X477122Y1409998D02*
X480522D01*
G02Y1406992I0J-1503D01*
G01X477122D01*
G02Y1409998I0J1503D01*
G37*
G36*
G01Y1398086D02*
X480522D01*
G02Y1395080I0J-1503D01*
G01X477122D01*
G02Y1398086I0J1503D01*
G37*
G36*
G01X489362Y1385800D02*
X492762D01*
G02Y1382794I0J-1503D01*
G01X489362D01*
G02Y1385800I0J1503D01*
G37*
G36*
G01X501602Y1361602D02*
X505002D01*
G02Y1358596I0J-1503D01*
G01X501602D01*
G02Y1361602I0J1503D01*
G37*
G36*
G01X513842D02*
X517242D01*
G02Y1358596I0J-1503D01*
G01X513842D01*
G02Y1361602I0J1503D01*
G37*
G36*
G01X501602Y1349690D02*
X505002D01*
G02Y1346684I0J-1503D01*
G01X501602D01*
G02Y1349690I0J1503D01*
G37*
G36*
G01X513842D02*
X517242D01*
G02Y1346684I0J-1503D01*
G01X513842D01*
G02Y1349690I0J1503D01*
G37*
G36*
G01X501602Y1398086D02*
X505002D01*
G02Y1395080I0J-1503D01*
G01X501602D01*
G02Y1398086I0J1503D01*
G37*
G36*
G01Y1409998D02*
X505002D01*
G02Y1406992I0J-1503D01*
G01X501602D01*
G02Y1409998I0J1503D01*
G37*
G36*
G01X526082Y1361602D02*
X529482D01*
G02Y1358596I0J-1503D01*
G01X526082D01*
G02Y1361602I0J1503D01*
G37*
G36*
G01Y1349690D02*
X529482D01*
G02Y1346684I0J-1503D01*
G01X526082D01*
G02Y1349690I0J1503D01*
G37*
G36*
G01X513842Y1398086D02*
X517242D01*
G02Y1395080I0J-1503D01*
G01X513842D01*
G02Y1398086I0J1503D01*
G37*
G36*
G01X526082Y1409998D02*
X529482D01*
G02Y1406992I0J-1503D01*
G01X526082D01*
G02Y1409998I0J1503D01*
G37*
G36*
G01X513842D02*
X517242D01*
G02Y1406992I0J-1503D01*
G01X513842D01*
G02Y1409998I0J1503D01*
G37*
G36*
G01X526082Y1398086D02*
X529482D01*
G02Y1395080I0J-1503D01*
G01X526082D01*
G02Y1398086I0J1503D01*
G37*
G36*
G01X538322Y1361602D02*
X541722D01*
G02Y1358596I0J-1503D01*
G01X538322D01*
G02Y1361602I0J1503D01*
G37*
G36*
G01X550562D02*
X553962D01*
G02Y1358596I0J-1503D01*
G01X550562D01*
G02Y1361602I0J1503D01*
G37*
G36*
G01X538322Y1349690D02*
X541722D01*
G02Y1346684I0J-1503D01*
G01X538322D01*
G02Y1349690I0J1503D01*
G37*
G36*
G01X550562D02*
X553962D01*
G02Y1346684I0J-1503D01*
G01X550562D01*
G02Y1349690I0J1503D01*
G37*
G36*
G01X538322Y1398086D02*
X541722D01*
G02Y1395080I0J-1503D01*
G01X538322D01*
G02Y1398086I0J1503D01*
G37*
G36*
G01Y1409998D02*
X541722D01*
G02Y1406992I0J-1503D01*
G01X538322D01*
G02Y1409998I0J1503D01*
G37*
G36*
G01X562802Y1361602D02*
X566202D01*
G02Y1358596I0J-1503D01*
G01X562802D01*
G02Y1361602I0J1503D01*
G37*
G36*
G01Y1349690D02*
X566202D01*
G02Y1346684I0J-1503D01*
G01X562802D01*
G02Y1349690I0J1503D01*
G37*
G36*
G01X550562Y1398086D02*
X553962D01*
G02Y1395080I0J-1503D01*
G01X550562D01*
G02Y1398086I0J1503D01*
G37*
G36*
G01X562802D02*
X566202D01*
G02Y1395080I0J-1503D01*
G01X562802D01*
G02Y1398086I0J1503D01*
G37*
G36*
G01X550562Y1409998D02*
X553962D01*
G02Y1406992I0J-1503D01*
G01X550562D01*
G02Y1409998I0J1503D01*
G37*
G36*
G01X562802D02*
X566202D01*
G02Y1406992I0J-1503D01*
G01X562802D01*
G02Y1409998I0J1503D01*
G37*
G36*
G01X650768Y1361602D02*
X654168D01*
G02Y1358596I0J-1503D01*
G01X650768D01*
G02Y1361602I0J1503D01*
G37*
G36*
G01Y1349690D02*
X654168D01*
G02Y1346684I0J-1503D01*
G01X650768D01*
G02Y1349690I0J1503D01*
G37*
G36*
G01X626288Y1409998D02*
X629688D01*
G02Y1406992I0J-1503D01*
G01X626288D01*
G02Y1409998I0J1503D01*
G37*
G36*
G01X638528Y1385800D02*
X641928D01*
G02Y1382794I0J-1503D01*
G01X638528D01*
G02Y1385800I0J1503D01*
G37*
G36*
G01Y1373888D02*
X641928D01*
G02Y1370882I0J-1503D01*
G01X638528D01*
G02Y1373888I0J1503D01*
G37*
G36*
G01X626288Y1398086D02*
X629688D01*
G02Y1395080I0J-1503D01*
G01X626288D01*
G02Y1398086I0J1503D01*
G37*
G36*
G01X675248Y1361602D02*
X678648D01*
G02Y1358596I0J-1503D01*
G01X675248D01*
G02Y1361602I0J1503D01*
G37*
G36*
G01X650768Y1385800D02*
X654168D01*
G02Y1382794I0J-1503D01*
G01X650768D01*
G02Y1385800I0J1503D01*
G37*
G36*
G01X675248Y1349690D02*
X678648D01*
G02Y1346684I0J-1503D01*
G01X675248D01*
G02Y1349690I0J1503D01*
G37*
G36*
G01X650768Y1373888D02*
X654168D01*
G02Y1370882I0J-1503D01*
G01X650768D01*
G02Y1373888I0J1503D01*
G37*
G36*
G01X638528Y1409998D02*
X641928D01*
G02Y1406992I0J-1503D01*
G01X638528D01*
G02Y1409998I0J1503D01*
G37*
G36*
G01Y1398086D02*
X641928D01*
G02Y1395080I0J-1503D01*
G01X638528D01*
G02Y1398086I0J1503D01*
G37*
G36*
G01X687488Y1361602D02*
X690888D01*
G02Y1358596I0J-1503D01*
G01X687488D01*
G02Y1361602I0J1503D01*
G37*
G36*
G01Y1349690D02*
X690888D01*
G02Y1346684I0J-1503D01*
G01X687488D01*
G02Y1349690I0J1503D01*
G37*
G36*
G01X663008Y1385800D02*
X666408D01*
G02Y1382794I0J-1503D01*
G01X663008D01*
G02Y1385800I0J1503D01*
G37*
G36*
G01X650768Y1409998D02*
X654168D01*
G02Y1406992I0J-1503D01*
G01X650768D01*
G02Y1409998I0J1503D01*
G37*
G36*
G01X663008Y1373888D02*
X666408D01*
G02Y1370882I0J-1503D01*
G01X663008D01*
G02Y1373888I0J1503D01*
G37*
G36*
G01X650768Y1398086D02*
X654168D01*
G02Y1395080I0J-1503D01*
G01X650768D01*
G02Y1398086I0J1503D01*
G37*
G36*
G01X699728Y1361602D02*
X703128D01*
G02Y1358596I0J-1503D01*
G01X699728D01*
G02Y1361602I0J1503D01*
G37*
G36*
G01X687488Y1385800D02*
X690888D01*
G02Y1382794I0J-1503D01*
G01X687488D01*
G02Y1385800I0J1503D01*
G37*
G36*
G01X699728Y1349690D02*
X703128D01*
G02Y1346684I0J-1503D01*
G01X699728D01*
G02Y1349690I0J1503D01*
G37*
G36*
G01X687488Y1373888D02*
X690888D01*
G02Y1370882I0J-1503D01*
G01X687488D01*
G02Y1373888I0J1503D01*
G37*
G36*
G01X675248Y1385800D02*
X678648D01*
G02Y1382794I0J-1503D01*
G01X675248D01*
G02Y1385800I0J1503D01*
G37*
G36*
G01Y1373888D02*
X678648D01*
G02Y1370882I0J-1503D01*
G01X675248D01*
G02Y1373888I0J1503D01*
G37*
G36*
G01X711968Y1349690D02*
X715368D01*
G02Y1346684I0J-1503D01*
G01X711968D01*
G02Y1349690I0J1503D01*
G37*
G36*
G01Y1361602D02*
X715368D01*
G02Y1358596I0J-1503D01*
G01X711968D01*
G02Y1361602I0J1503D01*
G37*
G36*
G01X663008Y1409998D02*
X666408D01*
G02Y1406992I0J-1503D01*
G01X663008D01*
G02Y1409998I0J1503D01*
G37*
G36*
G01X699728Y1385800D02*
X703128D01*
G02Y1382794I0J-1503D01*
G01X699728D01*
G02Y1385800I0J1503D01*
G37*
G36*
G01Y1373888D02*
X703128D01*
G02Y1370882I0J-1503D01*
G01X699728D01*
G02Y1373888I0J1503D01*
G37*
G36*
G01X663008Y1398086D02*
X666408D01*
G02Y1395080I0J-1503D01*
G01X663008D01*
G02Y1398086I0J1503D01*
G37*
G36*
G01X724208Y1397992D02*
X727608D01*
G02Y1394986I0J-1503D01*
G01X724208D01*
G02Y1397992I0J1503D01*
G37*
G36*
G01Y1349690D02*
X727608D01*
G02Y1346684I0J-1503D01*
G01X724208D01*
G02Y1349690I0J1503D01*
G37*
G36*
G01X675248Y1409998D02*
X678648D01*
G02Y1406992I0J-1503D01*
G01X675248D01*
G02Y1409998I0J1503D01*
G37*
G36*
G01Y1398086D02*
X678648D01*
G02Y1395080I0J-1503D01*
G01X675248D01*
G02Y1398086I0J1503D01*
G37*
G36*
G01X724208Y1361602D02*
X727608D01*
G02Y1358596I0J-1503D01*
G01X724208D01*
G02Y1361602I0J1503D01*
G37*
G36*
G01Y1409904D02*
X727608D01*
G02Y1406898I0J-1503D01*
G01X724208D01*
G02Y1409904I0J1503D01*
G37*
G36*
G01X736448Y1349690D02*
X739848D01*
G02Y1346684I0J-1503D01*
G01X736448D01*
G02Y1349690I0J1503D01*
G37*
G36*
G01X711968Y1373888D02*
X715368D01*
G02Y1370882I0J-1503D01*
G01X711968D01*
G02Y1373888I0J1503D01*
G37*
G36*
G01X736448Y1361602D02*
X739848D01*
G02Y1358596I0J-1503D01*
G01X736448D01*
G02Y1361602I0J1503D01*
G37*
G36*
G01X711968Y1385800D02*
X715368D01*
G02Y1382794I0J-1503D01*
G01X711968D01*
G02Y1385800I0J1503D01*
G37*
G36*
G01X687488Y1409998D02*
X690888D01*
G02Y1406992I0J-1503D01*
G01X687488D01*
G02Y1409998I0J1503D01*
G37*
G36*
G01Y1398086D02*
X690888D01*
G02Y1395080I0J-1503D01*
G01X687488D01*
G02Y1398086I0J1503D01*
G37*
G36*
G01X736448Y1373888D02*
X739848D01*
G02Y1370882I0J-1503D01*
G01X736448D01*
G02Y1373888I0J1503D01*
G37*
G36*
G01X748688Y1349690D02*
X752088D01*
G02Y1346684I0J-1503D01*
G01X748688D01*
G02Y1349690I0J1503D01*
G37*
G36*
G01X724208Y1373888D02*
X727608D01*
G02Y1370882I0J-1503D01*
G01X724208D01*
G02Y1373888I0J1503D01*
G37*
G36*
G01X736448Y1385800D02*
X739848D01*
G02Y1382794I0J-1503D01*
G01X736448D01*
G02Y1385800I0J1503D01*
G37*
G36*
G01X748688Y1361602D02*
X752088D01*
G02Y1358596I0J-1503D01*
G01X748688D01*
G02Y1361602I0J1503D01*
G37*
G36*
G01X736448Y1409904D02*
X739848D01*
G02Y1406898I0J-1503D01*
G01X736448D01*
G02Y1409904I0J1503D01*
G37*
G36*
G01Y1397992D02*
X739848D01*
G02Y1394986I0J-1503D01*
G01X736448D01*
G02Y1397992I0J1503D01*
G37*
G36*
G01X699728Y1409998D02*
X703128D01*
G02Y1406992I0J-1503D01*
G01X699728D01*
G02Y1409998I0J1503D01*
G37*
G36*
G01Y1398086D02*
X703128D01*
G02Y1395080I0J-1503D01*
G01X699728D01*
G02Y1398086I0J1503D01*
G37*
G36*
G01X748688Y1373888D02*
X752088D01*
G02Y1370882I0J-1503D01*
G01X748688D01*
G02Y1373888I0J1503D01*
G37*
G36*
G01X773168Y1349690D02*
X776568D01*
G02Y1346684I0J-1503D01*
G01X773168D01*
G02Y1349690I0J1503D01*
G37*
G36*
G01X760928D02*
X764328D01*
G02Y1346684I0J-1503D01*
G01X760928D01*
G02Y1349690I0J1503D01*
G37*
G36*
G01X711968Y1409998D02*
X715368D01*
G02Y1406992I0J-1503D01*
G01X711968D01*
G02Y1409998I0J1503D01*
G37*
G36*
G01Y1398086D02*
X715368D01*
G02Y1395080I0J-1503D01*
G01X711968D01*
G02Y1398086I0J1503D01*
G37*
G36*
G01X773168Y1361602D02*
X776568D01*
G02Y1358596I0J-1503D01*
G01X773168D01*
G02Y1361602I0J1503D01*
G37*
G36*
G01X760928Y1373888D02*
X764328D01*
G02Y1370882I0J-1503D01*
G01X760928D01*
G02Y1373888I0J1503D01*
G37*
G36*
G01Y1385800D02*
X764328D01*
G02Y1382794I0J-1503D01*
G01X760928D01*
G02Y1385800I0J1503D01*
G37*
G36*
G01X149552D02*
X152952D01*
G02Y1382794I0J-1503D01*
G01X149552D01*
G02Y1385800I0J1503D01*
G37*
G36*
G01Y1361602D02*
X152952D01*
G02Y1358596I0J-1503D01*
G01X149552D01*
G02Y1361602I0J1503D01*
G37*
G36*
G01X253863Y1373888D02*
X257263D01*
G02Y1370882I0J-1503D01*
G01X253863D01*
G02Y1373888I0J1503D01*
G37*
G36*
G01X198512D02*
X201912D01*
G02Y1370882I0J-1503D01*
G01X198512D01*
G02Y1373888I0J1503D01*
G37*
G36*
G01Y1409998D02*
X201912D01*
G02Y1406992I0J-1503D01*
G01X198512D01*
G02Y1409998I0J1503D01*
G37*
G36*
G01X364023Y1349690D02*
X367423D01*
G02Y1346684I0J-1503D01*
G01X364023D01*
G02Y1349690I0J1503D01*
G37*
G54D76*
X978614Y1210568D03*
Y1214838D03*
X914637Y1210568D03*
Y1214838D03*
X70947Y1201565D03*
Y1205835D03*
X1822594Y1211054D03*
Y1215324D03*
G54D80*
X970071Y1409152D03*
Y1365652D03*
G54D73*
X743337Y374862D03*
G54D66*
X1819042Y-27188D03*
Y-37188D03*
Y-47188D03*
X1753686Y-85978D03*
Y-75978D03*
Y-65978D03*
X1564906Y-27086D03*
Y-47086D03*
Y-37086D03*
X1574906Y-66006D03*
Y-86006D03*
Y-76006D03*
X1534542Y-27058D03*
Y-37058D03*
Y-47058D03*
X1499186Y-65978D03*
Y-75978D03*
Y-85978D03*
X1280406Y-26956D03*
Y-46956D03*
Y-36956D03*
X1320406Y-86006D03*
Y-66006D03*
Y-76006D03*
X1248042Y-26928D03*
X1242686Y-65978D03*
Y-75978D03*
Y-85978D03*
X993906Y-26826D03*
Y-46826D03*
Y-36826D03*
X1063906Y-66006D03*
Y-86006D03*
Y-76006D03*
X964542Y-26798D03*
Y-36798D03*
X939542D03*
Y-26798D03*
X989386Y-65978D03*
Y-75978D03*
X964386D03*
Y-65978D03*
X710406Y-26826D03*
Y-36826D03*
X735406D03*
Y-26826D03*
X830406Y-66006D03*
Y-76006D03*
X855406D03*
Y-66006D03*
X1248042Y-36928D03*
Y-46928D03*
X1018906Y-36826D03*
Y-46826D03*
X1217686Y-65978D03*
Y-75978D03*
X1305406Y-36956D03*
Y-46956D03*
Y-26956D03*
X1018906Y-26826D03*
X1217686Y-85978D03*
X1223042Y-26928D03*
Y-36928D03*
X1088906Y-76006D03*
Y-86006D03*
X1345406D03*
Y-76006D03*
Y-66006D03*
X1088906D03*
X1223042Y-46928D03*
X1474186Y-65978D03*
Y-75978D03*
Y-85978D03*
X1509542Y-27058D03*
Y-37058D03*
Y-47058D03*
X1794042Y-27188D03*
Y-37188D03*
Y-47188D03*
X1728686Y-65978D03*
Y-75978D03*
Y-85978D03*
X1589906Y-37086D03*
Y-47086D03*
Y-27086D03*
X1599906Y-76006D03*
Y-86006D03*
Y-66006D03*
G54D79*
X909360Y230906D03*
Y274606D03*
G54D74*
X1729390Y144095D03*
X1627028D03*
X1169941D03*
X1067579D03*
X965217D03*
X815217D03*
G54D72*
X640522Y630650D03*
X1657510Y374862D03*
X1554695Y630650D03*
X1200423Y374862D03*
X1097608Y630650D03*
X286250Y374862D03*
X183435Y630650D03*
G54D78*
X51043Y144095D03*
X57933Y66811D03*
X153405Y144095D03*
X160295Y66811D03*
X255767Y144095D03*
X262657Y66811D03*
X358129Y144095D03*
X365019Y66811D03*
X508130Y144095D03*
X515020Y66811D03*
X610492Y144095D03*
X617382Y66811D03*
X712854Y144095D03*
X719744Y66811D03*
X822106D03*
X972106D03*
X1074468D03*
X1176830D03*
X1272302Y144095D03*
X1279192Y66811D03*
X1422303Y144095D03*
X1429193Y66811D03*
X1524665Y144095D03*
X1531555Y66811D03*
X1633917D03*
X1736279D03*
G54D71*
X736447Y630650D03*
X1650620D03*
X1561585Y374862D03*
X1193533Y630650D03*
X1104498Y374862D03*
X279360Y630650D03*
X190325Y374862D03*
G54D70*
X1817323Y56693D03*
G54D69*
X924650Y1326119D03*
X370202Y1313064D03*
X559070Y686509D03*
X561570Y694509D03*
X559070Y702509D03*
X561570Y710509D03*
X559070Y718509D03*
X460950Y326485D03*
X463950Y334359D03*
X460950Y342233D03*
X463950Y350107D03*
X937000Y313983D03*
X66856Y105949D03*
X169218D03*
X271580D03*
X373942D03*
X893284Y235040D03*
X899352Y310261D03*
X1079748Y321042D03*
X1209184Y461917D03*
X1302896Y342096D03*
X1438116Y105949D03*
X1540478D03*
X1642840D03*
X1745202D03*
X1089096Y543562D03*
X1754906Y822634D03*
X917882Y326517D03*
X212980Y485254D03*
X205680Y478168D03*
X138290Y485260D03*
X148692Y478199D03*
X788482Y476118D03*
X778080Y483179D03*
X721092Y483210D03*
X713792Y476124D03*
X1245568Y476118D03*
X1235166Y483179D03*
X1178178Y483210D03*
X1170878Y476124D03*
X1584240Y485254D03*
X1576940Y478168D03*
X1519952Y478199D03*
X1509550Y485260D03*
X35688Y127128D03*
X28388Y120042D03*
Y134215D03*
X35688Y112955D03*
X130750Y120042D03*
Y134215D03*
X148692Y421047D03*
X138290Y413987D03*
X140690Y399813D03*
X148692Y406874D03*
Y392701D03*
X138050Y127128D03*
Y112955D03*
X138290Y471087D03*
Y442333D03*
Y428160D03*
X148692Y435221D03*
X205680Y399782D03*
X212980Y406868D03*
Y392695D03*
Y471081D03*
Y435215D03*
X205680Y442302D03*
Y428128D03*
Y413955D03*
X212980Y421041D03*
X233112Y134215D03*
Y120042D03*
X240412Y127128D03*
Y112955D03*
X342774Y127128D03*
X335474Y134215D03*
Y120042D03*
X342774Y112955D03*
X533092Y127096D03*
Y112923D03*
X543494Y134209D03*
Y120035D03*
X635454Y127096D03*
Y112923D03*
X645856Y134209D03*
Y120035D03*
X748218Y134209D03*
X737816Y127096D03*
X748218Y120035D03*
X737816Y112923D03*
X721092Y469037D03*
X778080Y469006D03*
X840178Y127096D03*
Y112923D03*
X850580Y134209D03*
Y120035D03*
X990178Y127096D03*
Y112923D03*
X1000580Y134209D03*
Y120035D03*
X1092540Y127096D03*
Y112923D03*
X1102942Y134209D03*
Y120035D03*
X1178178Y469037D03*
X1205304Y134209D03*
X1194902Y127096D03*
X1205304Y120035D03*
X1194902Y112923D03*
X1235166Y469006D03*
X1297264Y127096D03*
Y112923D03*
X1307666Y134209D03*
Y120035D03*
X1399648Y120042D03*
Y134215D03*
X1406948Y127128D03*
Y112955D03*
X1509310D03*
X1509550Y428160D03*
Y413987D03*
X1511950Y399813D03*
X1502010Y134215D03*
X1509310Y127128D03*
X1502010Y120042D03*
X1519952Y421047D03*
Y406874D03*
Y392701D03*
X1509550Y471087D03*
Y442333D03*
X1519952Y435221D03*
X1576940Y442302D03*
Y428128D03*
Y413955D03*
Y399782D03*
X1584240Y421041D03*
Y406868D03*
Y392695D03*
X1604372Y134215D03*
X1611672Y127128D03*
X1604372Y120042D03*
X1611672Y112955D03*
X1584240Y471081D03*
Y435215D03*
X1706734Y134215D03*
Y120042D03*
X1714034Y127128D03*
Y112955D03*
X148692Y536506D03*
Y522333D03*
X138290Y515221D03*
X148692Y492373D03*
X138290Y529394D03*
X205680Y492341D03*
Y536475D03*
X212980Y529388D03*
Y515215D03*
X205680Y522302D03*
X713792Y612817D03*
Y598644D03*
Y584471D03*
Y570297D03*
Y534431D03*
Y520258D03*
Y490297D03*
X721092Y591557D03*
Y577384D03*
Y563210D03*
Y527344D03*
Y513171D03*
Y605730D03*
X778080Y563179D03*
Y527313D03*
Y513139D03*
Y591525D03*
Y605699D03*
Y577352D03*
X788482Y570291D03*
Y534425D03*
Y520252D03*
Y490291D03*
Y612811D03*
Y598638D03*
Y584465D03*
X1170878Y612817D03*
Y598644D03*
Y584471D03*
Y570297D03*
Y534431D03*
Y520258D03*
Y490297D03*
X1178178Y563210D03*
Y527344D03*
Y513171D03*
Y605730D03*
Y591557D03*
Y577384D03*
X1235166Y527313D03*
Y513139D03*
Y605699D03*
Y591525D03*
Y577352D03*
Y563179D03*
X1245568Y570291D03*
Y534425D03*
Y520252D03*
Y490291D03*
Y612811D03*
Y598638D03*
Y584465D03*
X1509550Y529394D03*
Y515221D03*
X1519952Y536506D03*
Y522333D03*
Y492373D03*
X1576940Y536475D03*
Y522302D03*
Y492341D03*
X1584240Y529388D03*
Y515215D03*
X7982Y1527335D03*
G54D67*
X1592187Y-71006D03*
Y-81006D03*
X1582187Y-32086D03*
Y-42086D03*
X1736405Y-80978D03*
Y-70978D03*
X1801761Y-42188D03*
Y-32188D03*
X1517261Y-42058D03*
Y-32058D03*
X1481905Y-80978D03*
Y-70978D03*
X1230761Y-41928D03*
X1081187Y-71006D03*
X1337687D03*
Y-81006D03*
X1081187D03*
X1230761Y-31928D03*
X1225405Y-80978D03*
X1011187Y-31826D03*
X1297687Y-31956D03*
Y-41956D03*
X1225405Y-70978D03*
X1011187Y-41826D03*
X213969Y1460153D03*
Y1449153D03*
X227249Y1460153D03*
Y1449153D03*
G54D81*
X1817323Y1567323D03*
G54D68*
X1009333Y1344993D03*
X1015659Y681354D03*
X933725Y587636D03*
X933741Y596387D03*
X486837Y703006D03*
X394883Y340077D03*
X217907Y1428752D03*
X415203Y1497818D03*
X397267Y1516347D03*
X295011Y461917D03*
X523943Y105949D03*
X626305D03*
X728667D03*
X752097Y461917D03*
X831029Y105949D03*
X981029D03*
X1083391D03*
X1080351Y329955D03*
X1185753Y105949D03*
X1288115D03*
X1366535Y353200D03*
Y337452D03*
X1363535Y345326D03*
Y329578D03*
X1666271Y461919D03*
X174923Y543562D03*
X632009D03*
X1546183Y543564D03*
X385091Y1299153D03*
X454385Y1303545D03*
X940997Y333613D03*
X256705Y476124D03*
X264005Y483210D03*
X605779Y478199D03*
X595377Y485260D03*
X331395Y476118D03*
X320993Y483179D03*
X670067Y485254D03*
X662767Y478168D03*
X1127153Y485254D03*
X1119853Y478168D03*
X1062865Y478199D03*
X1052463Y485260D03*
X1702655Y476118D03*
X1692253Y483179D03*
X1635265Y483210D03*
X1627965Y476124D03*
X76005Y127096D03*
Y112923D03*
X86407Y120035D03*
Y134209D03*
X178367Y127096D03*
Y112923D03*
X188769Y134209D03*
Y120035D03*
X264005Y469037D03*
X291131Y134209D03*
Y120035D03*
X280729Y127096D03*
Y112923D03*
X320993Y469005D03*
X393493Y134209D03*
X383091Y127096D03*
X393493Y120035D03*
X383091Y112923D03*
X485475Y134215D03*
Y120042D03*
X492775Y127128D03*
Y112955D03*
X587837Y134215D03*
Y120042D03*
X597777Y399813D03*
X595137Y127128D03*
Y112955D03*
X595377Y471087D03*
Y442333D03*
Y428160D03*
Y413987D03*
X605779Y435221D03*
Y421047D03*
Y406874D03*
Y392701D03*
X670067Y435215D03*
X662767Y442302D03*
Y428128D03*
Y413955D03*
X670067Y421041D03*
X662767Y399782D03*
X670067Y406868D03*
Y392695D03*
Y471081D03*
X690199Y120042D03*
X697499Y127128D03*
X690199Y134215D03*
X697499Y112955D03*
X799861D03*
Y127128D03*
X792561Y120042D03*
Y134215D03*
X949861Y112955D03*
X942561Y120042D03*
Y134215D03*
X949861Y127128D03*
X1044923Y134215D03*
X1052223Y127128D03*
X1044923Y120042D03*
X1052223Y112955D03*
X1052463Y471087D03*
Y442333D03*
Y428160D03*
Y413987D03*
X1054863Y399813D03*
X1062865Y435221D03*
Y421047D03*
Y406874D03*
Y392701D03*
X1119853Y399782D03*
Y442302D03*
Y428128D03*
Y413955D03*
X1154585Y112955D03*
X1127153Y471081D03*
Y435215D03*
Y421041D03*
Y406868D03*
Y392695D03*
X1154585Y127128D03*
X1147285Y134215D03*
Y120042D03*
X1249647Y134215D03*
Y120042D03*
X1256947Y127128D03*
Y112955D03*
X1447265Y127096D03*
Y112923D03*
X1457667Y134209D03*
Y120035D03*
X1560029Y134209D03*
X1549627Y127096D03*
X1560029Y120035D03*
X1549627Y112923D03*
X1651989Y127096D03*
Y112923D03*
X1635265Y469037D03*
X1662391Y134209D03*
Y120035D03*
X1692253Y469006D03*
X1754351Y127096D03*
Y112923D03*
X1764753Y134209D03*
Y120035D03*
X264005Y513171D03*
X256705Y520258D03*
Y490297D03*
Y612817D03*
X264005Y591557D03*
Y605730D03*
X256705Y598644D03*
X264005Y577384D03*
X256705Y584471D03*
Y570297D03*
X264005Y563210D03*
X256705Y534431D03*
X264005Y527344D03*
X320993Y513139D03*
Y591525D03*
Y605699D03*
Y577352D03*
Y563179D03*
Y527313D03*
X331395Y490291D03*
Y612811D03*
Y598638D03*
Y584465D03*
Y570291D03*
Y534425D03*
Y520252D03*
X595377Y529394D03*
Y515221D03*
X605779Y536506D03*
Y522333D03*
Y492373D03*
X670067Y529388D03*
X662767Y536475D03*
Y522302D03*
X670067Y515215D03*
X662767Y492341D03*
X1052463Y529394D03*
Y515221D03*
X1062865Y536506D03*
Y522333D03*
Y492373D03*
X1119853Y536475D03*
Y522302D03*
Y492341D03*
X1127153Y529388D03*
Y515215D03*
X1627965Y584471D03*
Y570297D03*
Y534431D03*
Y520258D03*
Y490297D03*
Y612817D03*
Y598644D03*
X1635265Y527344D03*
Y513171D03*
Y605730D03*
Y591557D03*
Y577384D03*
Y563210D03*
X1692253Y605699D03*
Y591525D03*
Y577352D03*
Y563179D03*
Y527313D03*
Y513139D03*
X1702655Y534425D03*
Y520252D03*
Y490291D03*
Y612811D03*
Y598638D03*
Y584465D03*
Y570291D03*
G54D77*
X770472Y1490945D03*
X820079Y388583D03*
X1020866D03*
X1070472Y1490945D03*
G54D65*
X19685Y-83298D03*
X1821260D03*
X26789Y1373669D03*
X1796847Y1517889D03*
X1809883Y120792D03*
X184851Y334492D03*
X19685Y1801195D03*
X1821260D03*
G54D75*
X1030905Y1066535D03*
Y1263386D03*
X810038Y1066535D03*
Y1263386D03*
X573818Y1066535D03*
Y1263386D03*
X352952Y1066535D03*
Y1263386D03*
X116731Y1066535D03*
Y1263386D03*
X1724212Y1066535D03*
Y1263386D03*
X1487991Y1066535D03*
Y1263386D03*
X1267125Y1066535D03*
Y1263386D03*
%LPC*%
G75*
G36*
G01X940026Y1577634D02*
G03X940910Y1577268I884J885D01*
G01X956342D01*
G02X956484Y1577209I0J-200D01*
G01X959830Y1573863D01*
G02X959889Y1573721I-141J-142D01*
G01Y1543680D01*
G03X960255Y1542796I1251J0D01*
G01X964295Y1538756D01*
G03X965179Y1538390I884J885D01*
G01X1019906D01*
G02X1020048Y1538331I0J-200D01*
G01X1031515Y1526864D01*
G02X1031574Y1526722I-141J-142D01*
G01Y1492904D01*
G02X1031515Y1492762I-200J0D01*
G01X1031368Y1492615D01*
G02X1031226Y1492556I-142J141D01*
G01X947183D01*
G02X947041Y1492615I0J200D01*
G01X944876Y1494780D01*
G03X943992Y1495146I-884J-885D01*
G01X933579D01*
G03X932695Y1494780I0J-1251D01*
G01X917141Y1479226D01*
G03X916775Y1478342I885J-884D01*
G01Y1465020D01*
G02X916716Y1464878I-200J0D01*
G01X914188Y1462350D01*
G03X913822Y1461466I885J-884D01*
G01Y1460928D01*
G02X913763Y1460786I-200J0D01*
G01X913527Y1460550D01*
G03X913161Y1459666I885J-884D01*
G01Y1446448D01*
G02X913102Y1446306I-200J0D01*
G01X912955Y1446159D01*
G02X912813Y1446100I-142J141D01*
G01X900559D01*
G02X900417Y1446159I0J200D01*
G01X900270Y1446306D01*
G02X900211Y1446448I141J142D01*
G01Y1459640D01*
G03X899845Y1460524I-1251J0D01*
G01X899532Y1460837D01*
G02X899473Y1460979I141J142D01*
G01Y1462024D01*
G03X899107Y1462908I-1251J0D01*
G01X894403Y1467612D01*
G02X894344Y1467754I141J142D01*
G01Y1473096D01*
G03X893978Y1473980I-1251J0D01*
G01X888953Y1479005D01*
G03X888069Y1479371I-884J-885D01*
G01X880504D01*
G03X879620Y1479005I0J-1251D01*
G01X872265Y1471650D01*
G03X871899Y1470766I885J-884D01*
G01Y1460991D01*
G02X871840Y1460849I-200J0D01*
G01X871502Y1460511D01*
G03X871136Y1459627I885J-884D01*
G01Y1446423D01*
G02X871077Y1446281I-200J0D01*
G01X870968Y1446172D01*
G02X870826Y1446113I-142J141D01*
G01X858702D01*
G02X858560Y1446172I0J200D01*
G01X858139Y1446593D01*
G02X858080Y1446735I141J142D01*
G01Y1459524D01*
G03X857714Y1460408I-1251J0D01*
G01X853660Y1464462D01*
G03X852776Y1464828I-884J-885D01*
G01X828441D01*
G03X827557Y1464462I0J-1251D01*
G01X827039Y1463944D01*
G03X826673Y1463060I885J-884D01*
G01Y1461847D01*
G02X826614Y1461705I-200J0D01*
G01X826571Y1461662D01*
G02X826429Y1461603I-142J141D01*
G01X825036D01*
G03X824152Y1461237I0J-1251D01*
G01X821533Y1458618D01*
G02X821391Y1458559I-142J141D01*
G01X820451D01*
G03X819567Y1458193I0J-1251D01*
G01X819360Y1457986D01*
G03X818994Y1457102I885J-884D01*
G01Y1446462D01*
G02X818935Y1446320I-200J0D01*
G01X818826Y1446211D01*
G02X818684Y1446152I-142J141D01*
G01X806393D01*
G02X806251Y1446211I0J200D01*
G01X806063Y1446399D01*
G02X806004Y1446541I141J142D01*
G01Y1459828D01*
G02X806063Y1459970I200J0D01*
G01X806195Y1460102D01*
G03X806561Y1460986I-885J884D01*
G01Y1474310D01*
G02X806615Y1474447I200J0D01*
G03X806950Y1475299I-916J852D01*
G01Y1523715D01*
G02X807009Y1523857I200J0D01*
G01X816830Y1533678D01*
G03X817196Y1534562I-885J884D01*
G01Y1620853D01*
G02X817255Y1620995I200J0D01*
G01X822528Y1626268D01*
G02X822670Y1626327I142J-141D01*
G01X927565D01*
G02X927707Y1626268I0J-200D01*
G01X932114Y1621861D01*
G02X932173Y1621719I-141J-142D01*
G01Y1586005D01*
G03X932539Y1585121I1251J0D01*
G01X940026Y1577634D01*
G37*
G36*
G01X953110Y1480583D02*
G03X953130Y1480563I894J874D01*
G02X953192Y1480419I-138J-145D01*
G01Y1451442D01*
G02X953133Y1451300I-200J0D01*
G01X952668Y1450835D01*
G02X952526Y1450776I-142J141D01*
G01X930592D01*
G02X930450Y1450835I0J200D01*
G01X929621Y1451664D01*
G02X929562Y1451806I141J142D01*
G01Y1480891D01*
G02X929621Y1481033I200J0D01*
G01X930418Y1481830D01*
G02X930560Y1481889I142J-141D01*
G01X951737D01*
G02X951894Y1481812I-1J-200D01*
G03X951995Y1481698I984J770D01*
G01X953110Y1480583D01*
G37*
G36*
G01X955751Y1485453D02*
X957168Y1486870D01*
G02X957310Y1486929I142J-141D01*
G01X1045732D01*
G02X1045874Y1486870I0J-200D01*
G01X1046659Y1486085D01*
G02X1046718Y1485943I-141J-142D01*
G01Y1452303D01*
G02X1046659Y1452161I-200J0D01*
G01X1045333Y1450835D01*
G02X1045191Y1450776I-142J141D01*
G01X956304D01*
G02X956162Y1450835I0J200D01*
G01X955751Y1451246D01*
G02X955692Y1451388I141J142D01*
G01Y1485311D01*
G02X955751Y1485453I200J0D01*
G37*
%LPD*%
G75*
G54D15*
X7271Y70981D03*
X11011Y79720D03*
X8786Y88425D03*
X14264Y94236D03*
X10292D03*
X12786Y87903D03*
X18000Y90000D03*
X18298Y102141D03*
X8000Y102500D03*
X10131Y115473D03*
X15143Y115581D03*
X14996Y133034D03*
X11442Y132719D03*
X19855Y133000D03*
X9082Y135789D03*
X19855Y141362D03*
X11999Y141415D03*
X15948Y141267D03*
X10966Y162073D03*
Y159073D03*
X16909Y153263D03*
X12247Y166341D03*
X17313Y166937D03*
X21909Y153263D03*
X22335Y166721D03*
X16709Y175943D03*
X19572Y219470D03*
Y221970D03*
X10259Y218085D03*
X13059D03*
X19638Y226320D03*
X16859Y216385D03*
X19572Y216970D03*
X22599Y228646D03*
X18206Y244571D03*
X15586Y249108D03*
X13715Y259381D03*
X8970Y254871D03*
X18206Y264571D03*
X7036Y272371D03*
X8335Y280663D03*
X14807Y282181D03*
X15586Y269108D03*
X15499Y288542D03*
X17033Y1006819D03*
X14357Y1009906D03*
X20216Y1009748D03*
X14197Y1014205D03*
Y1017759D03*
X20197Y1014205D03*
Y1017759D03*
X12599Y1438143D03*
X16304Y1468196D03*
X15889Y1494254D03*
X10089D03*
X6489Y1501334D03*
X19745Y1508846D03*
X19735Y1530499D03*
X19859Y1520657D03*
X6951Y1538547D03*
X18879Y1534334D03*
X10367Y1553080D03*
X32350Y67562D03*
X28442Y55340D03*
X32350Y59562D03*
Y63562D03*
X26588Y97667D03*
X35442D03*
X35048Y103411D03*
X22439Y102495D03*
X35207Y106561D03*
X22935Y162073D03*
Y159073D03*
X26565Y177448D03*
X32507Y180517D03*
X30567Y195176D03*
X28067D03*
X25567D03*
X33067D03*
X29585Y199248D03*
X32585D03*
X29921Y206806D03*
X32585Y202048D03*
X25648Y210509D03*
X28148D03*
X29585Y201748D03*
X27421Y206806D03*
X27340Y230556D03*
X36185Y230117D03*
X31595Y227824D03*
X32201Y238714D03*
X23844Y239299D03*
X21556Y232971D03*
X31682Y246874D03*
X33902Y244297D03*
X26325Y262078D03*
X25549Y256394D03*
X31682Y266874D03*
X29116Y281129D03*
X37117Y279991D03*
X25549Y276394D03*
X34845Y291756D03*
X26629Y295619D03*
X35650Y491982D03*
Y495982D03*
X30177Y534211D03*
X34359Y541135D03*
X34732Y534909D03*
X25819Y527726D03*
Y548726D03*
X34425Y546553D03*
X34448Y552726D03*
X25819Y544726D03*
X30123Y611071D03*
X27686Y621311D03*
X36494Y616905D03*
X36306Y622285D03*
X27686Y629311D03*
Y625311D03*
X36692Y633724D03*
X36575Y627713D03*
X35293Y662952D03*
X35250Y671508D03*
X34565Y699082D03*
X36529Y1006321D03*
X30479Y1006509D03*
X24456Y1006401D03*
X32093Y1009748D03*
X26155Y1009985D03*
X29197Y1014205D03*
X32197Y1017759D03*
X26197D03*
X35197Y1014205D03*
X21196Y1065529D03*
Y1063029D03*
X36089Y1062601D03*
Y1065101D03*
X35925Y1075663D03*
X33425D03*
X28996Y1065529D03*
X23796D03*
X26396D03*
Y1063029D03*
X23796D03*
X28996D03*
X28606Y1082678D03*
X23406D03*
X26006D03*
Y1080178D03*
X23406D03*
X28606D03*
X20806Y1082678D03*
Y1080178D03*
X21321Y1098769D03*
X26521D03*
X29121D03*
X23921D03*
Y1101335D03*
X29121D03*
X26521D03*
X21321D03*
X32574Y1111633D03*
X29874D03*
X27274D03*
X24674D03*
Y1121333D03*
X27274D03*
X29874D03*
X32574D03*
X24674Y1130333D03*
X21974D03*
X21209Y1138705D03*
X23709D03*
X31631Y1198651D03*
X29860Y1438552D03*
X23603Y1449735D03*
X29880Y1441702D03*
X33189Y1501373D03*
X22381Y1554152D03*
X26231Y1554167D03*
X45988Y90512D03*
X51550Y90615D03*
X48476Y180812D03*
X48643Y442919D03*
X48596Y451419D03*
X45643Y472905D03*
X41643Y473419D03*
X49643Y472905D03*
Y464419D03*
X41643Y464919D03*
X48390Y485128D03*
X51239Y485138D03*
X40009Y481467D03*
X43948Y492108D03*
X44563Y482165D03*
X39801Y504825D03*
X42301D03*
X44801D03*
X43804Y500202D03*
X45256Y495993D03*
X45293Y522569D03*
X39742Y517401D03*
X42242D03*
X44742D03*
X46993Y529169D03*
X41408Y531882D03*
X43908D03*
X45293Y525369D03*
X46408Y531882D03*
X38358Y531948D03*
X52869Y537958D03*
X46643Y555194D03*
X52869Y540458D03*
X43843Y555194D03*
X46643Y571194D03*
X43843D03*
Y563194D03*
X46643D03*
X51000Y581222D03*
X45400D03*
X48200D03*
X51000Y591215D03*
X45400D03*
X48200D03*
X51172Y607762D03*
X48372D03*
X45572D03*
Y610562D03*
X48372D03*
X51172D03*
X40362Y610548D03*
X54192Y633473D03*
X42172Y633716D03*
X49192Y628078D03*
X47179Y633736D03*
X37847Y662910D03*
X39549Y682108D03*
X36910D03*
X37804Y671508D03*
X40165Y699082D03*
X37365D03*
X49249Y837718D03*
X52349D03*
X46049D03*
X53549Y843118D03*
X52077Y905295D03*
X48429Y916430D03*
X47264Y919649D03*
X48683Y1006510D03*
X42470Y1006738D03*
X50541Y1009589D03*
X44999Y1009510D03*
X38823Y1009273D03*
X47197Y1014205D03*
X41197D03*
X44197Y1017759D03*
X38197D03*
X48704Y1017982D03*
X43889Y1062601D03*
X38689D03*
X41289D03*
Y1065101D03*
X38689D03*
X43889D03*
X47314Y1072228D03*
X41172Y1079064D03*
X46166Y1093757D03*
X39659Y1105100D03*
X42259D03*
X44859D03*
X47559D03*
X48585Y1123867D03*
X47559Y1114800D03*
X44859D03*
X42259D03*
X39659D03*
X48547Y1133688D03*
X51047D03*
X55188Y1205179D03*
X51023Y1201416D03*
X48842Y1211109D03*
X53479Y1216256D03*
X43198Y1254055D03*
X45698D03*
X48198D03*
X45698Y1251555D03*
X43198D03*
X48198D03*
X47621Y1343672D03*
X48089Y1501387D03*
X39095Y1501361D03*
X47074Y1555923D03*
X40951Y1555932D03*
X64785Y79993D03*
Y82593D03*
Y85193D03*
Y74793D03*
Y77393D03*
X64829Y92874D03*
X55871Y99961D03*
X55921Y95236D03*
X66856Y104249D03*
Y107649D03*
X66478Y162368D03*
X63878D03*
X69261Y211695D03*
Y208695D03*
X65189Y210713D03*
Y213213D03*
Y208213D03*
X54733Y212978D03*
Y215478D03*
Y207978D03*
Y210478D03*
X65189Y215713D03*
X57987Y258880D03*
X60562Y264180D03*
X58062D03*
X66956Y267526D03*
Y270026D03*
X54167Y457339D03*
X56667D03*
X65737Y445603D03*
X57857Y446071D03*
X56667Y459839D03*
X54167D03*
Y462339D03*
X56667D03*
X62224Y473045D03*
X67670Y464818D03*
X58224Y465004D03*
X63154Y462371D03*
X55124Y478625D03*
X53739Y485138D03*
X56239D03*
X56824Y482425D03*
X55124Y475825D03*
X62700Y491214D03*
X66403Y495487D03*
X62700Y493714D03*
X66403Y492987D03*
X68202Y537877D03*
X56572Y539731D03*
X68202Y542877D03*
Y545377D03*
Y540377D03*
X61330Y544895D03*
X56572Y542231D03*
X64130Y541895D03*
Y544895D03*
X61630Y541895D03*
X68188Y548358D03*
X64408Y582747D03*
X63859Y590801D03*
X67684Y597232D03*
X63684Y597130D03*
X67684Y605637D03*
X61854Y617853D03*
Y620653D03*
X53972Y607762D03*
Y610562D03*
X59684Y605443D03*
X63684D03*
X66530Y625013D03*
X58181Y627908D03*
X64692Y642184D03*
X56049Y827218D03*
X68649D03*
X69049Y847718D03*
X65549Y850718D03*
X68598Y859415D03*
X68778Y873821D03*
X63969Y869475D03*
X63930Y874694D03*
X68100Y910122D03*
X71528Y913190D03*
X64632Y901500D03*
X59962Y910251D03*
X53197Y1014205D03*
Y1017759D03*
X55699Y1072761D03*
X61588Y1074481D03*
X62109Y1087656D03*
Y1084656D03*
Y1079656D03*
Y1091656D03*
X60269Y1198820D03*
X63094Y1207604D03*
X55596Y1210466D03*
X68245Y1212054D03*
X58443Y1272257D03*
X54843Y1501625D03*
X60227Y1514751D03*
X60277Y1528395D03*
X55862Y1541791D03*
X65478Y1541980D03*
X60303Y1534436D03*
X60747Y1555890D03*
X64747D03*
X60864Y1583484D03*
X58064D03*
X55264D03*
X69816Y1592527D03*
X60554Y1615152D03*
X73110Y98551D03*
X77804Y95879D03*
X76660Y103783D03*
X75194Y141247D03*
X71422Y147540D03*
X82661Y143740D03*
X80041Y148277D03*
X73578Y165393D03*
Y162793D03*
Y170493D03*
Y167993D03*
X80502Y177616D03*
X81083Y172190D03*
X72575Y181426D03*
X75786Y181366D03*
X78581Y181009D03*
X83756Y168697D03*
X84844Y191941D03*
X75400Y184012D03*
X72783Y184221D03*
X72061Y208695D03*
X71761Y211695D03*
X76819Y213859D03*
Y211359D03*
X80522Y213132D03*
Y215632D03*
X80766Y256303D03*
X75438Y265701D03*
X85541Y266114D03*
X80525Y265896D03*
X72256Y267526D03*
X69756D03*
Y270026D03*
X72256D03*
X83014Y281982D03*
X77073Y281716D03*
X71130Y462152D03*
Y459652D03*
Y464652D03*
X73630Y459652D03*
Y462152D03*
Y464652D03*
X78033Y491133D03*
X71461Y498151D03*
Y495151D03*
X73961D03*
X78033Y498633D03*
Y496133D03*
Y493633D03*
X73961Y498151D03*
X78133Y553297D03*
Y555897D03*
X75688Y548358D03*
X73188D03*
X70688D03*
X78133Y558497D03*
Y566597D03*
Y563697D03*
Y561097D03*
X72128Y570686D03*
X74923Y570478D03*
X75340Y576484D03*
X74983Y573689D03*
X72337Y573303D03*
X78733Y578405D03*
X84159Y578986D03*
X83684Y596729D03*
X72515Y596089D03*
X77734Y596782D03*
X81740Y619758D03*
Y616958D03*
Y614158D03*
X69670Y619513D03*
Y616713D03*
Y613913D03*
X79684Y605443D03*
X82648Y670679D03*
X73914Y660107D03*
X79043Y667391D03*
X84845Y659857D03*
X84314Y686107D03*
X82562Y680037D03*
X78735Y683426D03*
X72149Y827318D03*
X74349Y824718D03*
Y821918D03*
X74700Y842890D03*
X84367Y878286D03*
X76528Y878533D03*
X74028Y889065D03*
X83079Y888515D03*
X72035Y898346D03*
X80339Y897943D03*
X76203Y897910D03*
X80593Y946082D03*
X78167Y949261D03*
X76332Y953421D03*
X87632Y1007522D03*
X70059Y1075656D03*
X70302Y1067656D03*
X77734Y1095676D03*
X70947Y1201565D03*
Y1205835D03*
X71006Y1228684D03*
X71020Y1224323D03*
X74909Y1593009D03*
X71910Y1625009D03*
X78291Y1625743D03*
X83689Y1624736D03*
X82291Y1633801D03*
X78291D03*
X70291D03*
X91224Y141247D03*
X92337Y144172D03*
X95711Y143518D03*
X94811Y152373D03*
X97961Y152562D03*
X103456Y157370D03*
X98826Y172665D03*
X98763Y178560D03*
X98653Y183834D03*
X99639Y186629D03*
X98943Y200864D03*
X92898Y192490D03*
X98173Y190185D03*
X89353Y206767D03*
X86853D03*
X91853D03*
X98966Y207037D03*
X99032Y212455D03*
X89483Y221708D03*
X86983D03*
X86398Y224421D03*
X88098Y231021D03*
Y228221D03*
X96333Y221642D03*
X91983Y221708D03*
X103841Y228631D03*
X93649Y236189D03*
X91149D03*
X88649D03*
X91090Y248765D03*
X88590D03*
X93590D03*
X97747Y265897D03*
X100247D03*
X94087Y270695D03*
X91287D03*
X88787D03*
Y268195D03*
X91287D03*
X94087D03*
X98255Y374510D03*
X100120Y377898D03*
X100066Y381976D03*
X86788Y581659D03*
X87684Y605443D03*
X95973Y655660D03*
X92897Y658359D03*
X95917Y658374D03*
X95539Y664443D03*
X86289Y822088D03*
X86367Y848086D03*
X90000Y871389D03*
X103770Y868206D03*
X103692Y900295D03*
X91387Y905295D03*
X100058Y977651D03*
X99836Y980330D03*
X103836Y988813D03*
X100200Y988800D03*
X95836Y988813D03*
X85706Y998507D03*
X94398Y1006648D03*
X101025Y1009655D03*
X94586Y1023900D03*
X91765Y1018307D03*
X88007Y1013678D03*
X88479Y1023731D03*
X88287Y1026537D03*
X97609Y1018469D03*
X90450Y1033542D03*
X93496Y1547768D03*
X107364Y116594D03*
X118307Y110784D03*
X113307D03*
X107364Y119594D03*
X117886Y124663D03*
X112864Y124879D03*
X107798Y124283D03*
X119230Y138838D03*
X106205Y161306D03*
X107540Y176665D03*
Y168665D03*
Y196665D03*
Y192665D03*
X107653Y186778D03*
X107572Y204864D03*
Y208864D03*
X112621Y218085D03*
X115421D03*
X103213Y219379D03*
X117948Y249108D03*
X109329Y248371D03*
X111993Y710102D03*
X120250Y758841D03*
X113505Y796856D03*
X109591Y796905D03*
X102355Y874267D03*
X102947Y877196D03*
X102320Y891043D03*
X110887Y884000D03*
X103972Y977609D03*
X103836Y980330D03*
X111836Y988813D03*
X119836D03*
X115836D03*
X107836D03*
X103825Y1009655D03*
X105971Y1025745D03*
X114770Y1016827D03*
X110409Y1024094D03*
X114770Y1029427D03*
X110970Y1030672D03*
X101970D03*
X104970D03*
X107970D03*
X102761Y1096233D03*
X108971Y1109564D03*
X103124D03*
Y1122164D03*
X108971D03*
X103124Y1134764D03*
X108971D03*
X103124Y1147364D03*
X108971D03*
X103124Y1172564D03*
X108971D03*
X103124Y1159964D03*
X108971D03*
X103861Y1182703D03*
X118533Y1207737D03*
X112048Y1214372D03*
X107803Y1218169D03*
X128950Y97667D03*
X133200Y95111D03*
X124606Y102495D03*
X119333Y116594D03*
Y119594D03*
X122867Y125107D03*
X124340Y142862D03*
X131481Y143762D03*
X125381Y148717D03*
X131947Y199248D03*
X127929Y195176D03*
X130429D03*
X132929D03*
X134947Y199248D03*
X128010Y210509D03*
X130510D03*
X132283Y206806D03*
X129783D03*
X131947Y201748D03*
X122000Y226320D03*
X119221Y216385D03*
X121934Y216970D03*
Y219470D03*
Y221970D03*
X129702Y230556D03*
X133957Y227824D03*
X124961Y228646D03*
X128687Y242078D03*
X123918Y232971D03*
X134044Y246874D03*
X120568Y244571D03*
X127911Y256394D03*
X126131Y359511D03*
X125753Y365856D03*
X119099Y755052D03*
X118467Y796785D03*
X122437Y860775D03*
X125698Y857515D03*
X122432Y857540D03*
X129666Y857514D03*
X133424Y857303D03*
X122887Y888000D03*
X123387Y892000D03*
X135836Y988813D03*
X131836D03*
X123836D03*
X127836D03*
X120617Y1029427D03*
Y1016827D03*
X133579Y1097469D03*
X124925Y1102091D03*
X130380Y1105091D03*
X124880D03*
X124925Y1114691D03*
Y1127291D03*
X124880Y1117691D03*
X130380D03*
X124925Y1139891D03*
X124880Y1130291D03*
X130380D03*
X130434Y1144964D03*
X124474Y1142997D03*
X130380Y1155491D03*
X124880D03*
X124925Y1152491D03*
X124474Y1168197D03*
X130434Y1170164D03*
X124925Y1165091D03*
Y1177691D03*
X131000Y1180266D03*
X124765Y1180691D03*
X135757Y1221407D03*
X135448Y1229402D03*
Y1234921D03*
X126433Y1230407D03*
X129250Y1227650D03*
X137410Y103411D03*
X137804Y97667D03*
X148600Y90650D03*
X148350Y95236D03*
X137569Y106561D03*
X135429Y195176D03*
X134947Y202048D03*
X138547Y230117D03*
X134563Y238714D03*
X138664Y241699D03*
X148061Y378600D03*
Y382600D03*
X148176Y458711D03*
X148940Y455921D03*
X145376Y458711D03*
X147520Y463600D03*
X142024Y552466D03*
X147925Y603600D03*
Y619600D03*
Y623600D03*
X149469Y634190D03*
X152658Y645389D03*
X136862Y857244D03*
X147836Y988813D03*
X139836D03*
X151836D03*
X143836D03*
X142026Y1012354D03*
X136571Y1009354D03*
X136526Y1012354D03*
X136571Y1021954D03*
X142026Y1024954D03*
X136526D03*
X144640Y1039439D03*
X150952Y1040115D03*
X146595Y1053457D03*
X136432Y1224472D03*
X167191Y92874D03*
X153912Y90615D03*
X158283Y95236D03*
X158233Y99961D03*
X166240Y162368D03*
X157095Y210478D03*
Y207978D03*
Y215478D03*
Y212978D03*
X160424Y264180D03*
X162924D03*
X160349Y258880D03*
X164496Y309405D03*
X150703Y453682D03*
X159836Y988813D03*
X155836Y997860D03*
X160733Y1056594D03*
X153693Y1051037D03*
X160547Y1049283D03*
X160627Y1053561D03*
X160807Y1043955D03*
X166188Y1066551D03*
X163191Y1065313D03*
X159228Y1065613D03*
X165649Y1159350D03*
Y1151870D03*
X167147Y77393D03*
Y74793D03*
Y85193D03*
Y82593D03*
Y79993D03*
X175472Y98551D03*
X179022Y103783D03*
X169218Y107649D03*
Y104249D03*
X173784Y147540D03*
X177556Y141247D03*
X185023Y143740D03*
X182403Y148277D03*
X175940Y162793D03*
Y165393D03*
X168840Y162368D03*
X175940Y167993D03*
Y170493D03*
X178148Y181366D03*
X180943Y181009D03*
X174937Y181426D03*
X182864Y177616D03*
X183445Y172190D03*
X175145Y184221D03*
X177762Y184012D03*
X171623Y211695D03*
X182884Y213132D03*
X179181Y211359D03*
Y213859D03*
X174123Y211695D03*
X167551Y208213D03*
Y213213D03*
Y210713D03*
X171623Y208695D03*
X174423D03*
X167551Y215713D03*
X182884Y215632D03*
X177800Y265701D03*
X182887Y265896D03*
X174618Y267526D03*
Y270026D03*
X169318Y267526D03*
X172118D03*
Y270026D03*
X169318D03*
X179435Y281716D03*
X170215Y311671D03*
X175615Y550907D03*
X173115D03*
X175615Y553407D03*
X173115D03*
X174923Y545263D03*
Y541863D03*
X177385Y566929D03*
X171339Y572070D03*
X172686Y569928D03*
X175033Y570962D03*
X174776Y568475D03*
X177099Y569426D03*
X169389Y1155610D03*
X191568Y76587D03*
Y72615D03*
X193007Y100625D03*
X186026Y97475D03*
X185957Y106186D03*
X197380Y112083D03*
X193586Y141247D03*
X198073Y143518D03*
X197173Y152373D03*
X201015Y183834D03*
X201125Y178560D03*
X186118Y168697D03*
X201188Y172665D03*
X187206Y191941D03*
X195260Y192490D03*
X200535Y190185D03*
X201305Y200864D03*
X189215Y206767D03*
X191715D03*
X194215D03*
X201394Y212455D03*
X201328Y207037D03*
X194345Y221708D03*
X198695Y221642D03*
X190460Y228221D03*
Y231021D03*
X191845Y221708D03*
X188760Y224421D03*
X189345Y221708D03*
X191011Y236189D03*
X193511D03*
X196011D03*
X190952Y248765D03*
X193452D03*
X195952D03*
X183128Y256303D03*
X187903Y266114D03*
X196449Y268195D03*
X193649D03*
X196449Y270695D03*
X193649D03*
X191149D03*
Y268195D03*
X185376Y281982D03*
X185328Y545528D03*
X194063Y577716D03*
X191125Y610400D03*
X203248Y55513D03*
X199473Y68581D03*
X205848Y60513D03*
X208645Y60369D03*
X199486Y80581D03*
X214389Y86012D03*
X203616Y88801D03*
X214389Y94374D03*
X206533Y94351D03*
X210482Y94279D03*
X209530Y86046D03*
X205976Y85731D03*
X209726Y116594D03*
X201669Y103621D03*
X215669Y110784D03*
X209726Y119594D03*
X210160Y124283D03*
X215226Y124879D03*
X208567Y161306D03*
X200323Y152562D03*
X205818Y157370D03*
X209902Y176665D03*
Y168665D03*
X202001Y186629D03*
X209902Y196665D03*
Y192665D03*
X210015Y186778D03*
X209934Y204864D03*
Y208864D03*
X214983Y218085D03*
X205575Y219379D03*
X206203Y228631D03*
X211691Y248371D03*
X200109Y265897D03*
X202609D03*
X204675Y382109D03*
X204674Y551683D03*
Y558917D03*
Y561420D03*
X200495Y577937D03*
X208500Y595500D03*
X203500Y606929D03*
X208000Y604567D03*
X203460Y618400D03*
X203741Y612592D03*
X209158Y610072D03*
X209094Y616317D03*
X208540Y621591D03*
X205941Y668934D03*
X201115Y695581D03*
X203046Y693716D03*
X213969Y1447453D03*
Y1461853D03*
Y1458453D03*
Y1450853D03*
X231312Y97667D03*
X221695Y116594D03*
X226968Y102495D03*
X220669Y110784D03*
X221695Y119594D03*
X225229Y125107D03*
X220248Y124663D03*
X226702Y142862D03*
X227743Y148717D03*
X221592Y138838D03*
X230291Y195176D03*
X230372Y210509D03*
X224362Y226320D03*
X224296Y216970D03*
Y219470D03*
Y221970D03*
X221583Y216385D03*
X217783Y218085D03*
X232064Y230556D03*
X227323Y228646D03*
X231049Y242078D03*
X226280Y232971D03*
X220310Y249108D03*
X222930Y244571D03*
X233417Y253198D03*
X230842Y313888D03*
X233258Y359186D03*
X228267Y396718D03*
X221375Y455024D03*
X220349Y465622D03*
X225500Y530000D03*
X225000Y540500D03*
X224000Y547075D03*
X224200Y549800D03*
X223500Y568000D03*
X224104Y562800D03*
X224040Y558800D03*
X221693Y594982D03*
X222289Y590895D03*
X220333Y617930D03*
X220255Y629749D03*
X217906Y1430452D03*
Y1427052D03*
X219525Y1440028D03*
X216125D03*
X224780Y1478149D03*
X217985Y1483055D03*
X225765Y1471985D03*
X233313Y1476699D03*
X221899Y1488800D03*
X218021Y1494724D03*
X222843Y1498442D03*
X217614Y1489671D03*
X233180Y1486442D03*
X233166Y1491454D03*
X226135Y1502442D03*
X230758Y1505046D03*
X226971Y1514578D03*
X227552Y1530675D03*
X232622Y1531104D03*
X226971Y1522578D03*
X219981Y1530797D03*
X223322Y1518578D03*
X222119Y1539941D03*
X227882Y1540816D03*
X233753Y1539752D03*
X239772Y103411D03*
X240166Y97667D03*
X235562Y95111D03*
X239931Y106561D03*
X233843Y143762D03*
X232791Y195176D03*
X235291D03*
X237309Y199248D03*
X234309D03*
X237791Y195176D03*
X237309Y202048D03*
X232872Y210509D03*
X234645Y206806D03*
X232145D03*
X234309Y201748D03*
X240909Y230117D03*
X236319Y227824D03*
X236925Y238714D03*
X236406Y246874D03*
X238626Y244297D03*
X234986Y336161D03*
X236264Y342494D03*
X245362Y546712D03*
Y542712D03*
X247536Y602689D03*
X247278Y618288D03*
X243278D03*
X240194Y643113D03*
X242102Y656321D03*
X250102D03*
X246102D03*
X245000Y678462D03*
X244267Y696911D03*
X235790Y754332D03*
X241204Y814841D03*
X237591Y815266D03*
X248556Y824003D03*
X246311Y819000D03*
X238400Y836900D03*
X234976Y1481676D03*
X243535Y1511473D03*
X245500Y1517033D03*
X237633Y1511909D03*
X244600Y1531700D03*
X240808Y1519942D03*
X235687Y1522578D03*
X237580Y1528604D03*
X245937Y1524237D03*
X239949Y1541327D03*
X244912Y1539389D03*
X250962Y90650D03*
X256274Y90615D03*
X260595Y99961D03*
X260645Y95236D03*
X250712D03*
X259457Y210478D03*
Y207978D03*
Y215478D03*
Y212978D03*
X262786Y264180D03*
X262711Y258880D03*
X257993Y307994D03*
X256475Y422088D03*
X252695Y442956D03*
X254512Y438323D03*
X261965Y458455D03*
X250336Y456386D03*
X254678Y445873D03*
X263301Y444232D03*
X262526Y451108D03*
X249125Y465874D03*
X252688Y636364D03*
X248690Y678519D03*
X248090Y691114D03*
X254634Y698241D03*
X248506Y812042D03*
X256303Y812254D03*
X250700Y819900D03*
X254058Y819851D03*
X255289Y824340D03*
X252305Y831018D03*
X252100Y836800D03*
X250876Y1532782D03*
X255909Y1542043D03*
X250790Y1539759D03*
X269509Y77393D03*
Y74793D03*
Y85193D03*
Y82593D03*
Y79993D03*
X277834Y98551D03*
X269553Y92874D03*
X271580Y107649D03*
Y104249D03*
X276146Y147540D03*
X279918Y141247D03*
X268602Y162368D03*
X271202D03*
X278302Y162793D03*
Y165393D03*
Y167993D03*
Y170493D03*
X277299Y181426D03*
X280124Y184012D03*
X277507Y184221D03*
X269913Y210713D03*
X273985Y208695D03*
X276785D03*
X273985Y211695D03*
X276485D03*
X269913Y208213D03*
Y213213D03*
Y215713D03*
X265286Y264180D03*
X280162Y265701D03*
X276980Y267526D03*
Y270026D03*
X271680Y267526D03*
X274480D03*
Y270026D03*
X271680D03*
X281797Y281716D03*
X277575Y395084D03*
X274425Y381500D03*
X278784Y435158D03*
X278529Y440489D03*
X274949Y442606D03*
X278827Y444841D03*
X282230Y458572D03*
X265011Y453881D03*
X280220Y448493D03*
X274866Y446606D03*
X265011Y446595D03*
X275873Y463479D03*
X276344Y467367D03*
X274096Y820725D03*
X274697Y830951D03*
X275123Y847874D03*
X269700Y853100D03*
X275400Y864400D03*
X278400Y890839D03*
X275400Y899400D03*
X279261Y926339D03*
X278739Y936439D03*
X289797Y36735D03*
X290113Y23188D03*
X284666Y34068D03*
X289631Y28281D03*
X293930Y76587D03*
Y72615D03*
X295369Y100625D03*
X288388Y97475D03*
X281384Y103783D03*
X288319Y106186D03*
X295948Y141247D03*
X287385Y143740D03*
X284765Y148277D03*
X285807Y172190D03*
X280510Y181366D03*
X283305Y181009D03*
X288480Y168697D03*
X285226Y177616D03*
X289568Y191941D03*
X297622Y192490D03*
X291577Y206767D03*
X294077D03*
X296577D03*
X285246Y213132D03*
X281543Y211359D03*
Y213859D03*
X296707Y221708D03*
X292822Y228221D03*
Y231021D03*
X294207Y221708D03*
X291122Y224421D03*
X291707Y221708D03*
X285246Y215632D03*
X293373Y236189D03*
X295873D03*
X293314Y248765D03*
X295814D03*
X285490Y256303D03*
X290265Y266114D03*
X285249Y265896D03*
X296011Y270695D03*
X293511D03*
Y268195D03*
X296011D03*
X287738Y281982D03*
X286940Y315039D03*
X297719Y339559D03*
X291396Y350223D03*
X292520Y384410D03*
X292358Y393858D03*
X298000Y391496D03*
X295699Y382047D03*
X296000Y403500D03*
X298000Y409000D03*
X294000Y398583D03*
X295253Y440869D03*
Y438269D03*
X292453D03*
Y440869D03*
Y435669D03*
Y430469D03*
Y433069D03*
X295253D03*
Y430469D03*
Y435669D03*
X293307Y451677D03*
X295807D03*
X293307Y454177D03*
X295807D03*
X295011Y460218D03*
Y463618D03*
X281980Y953926D03*
X312256Y37543D03*
X305610Y55513D03*
X301835Y68581D03*
X310817Y60393D03*
X307916Y60529D03*
X301848Y80581D03*
X305978Y88801D03*
X312844Y94279D03*
X308895Y94351D03*
X308338Y85731D03*
X311892Y86046D03*
X312088Y116594D03*
X299742Y112083D03*
X304031Y103621D03*
X312088Y119594D03*
X312522Y124283D03*
X300435Y143518D03*
X299535Y152373D03*
X310929Y161306D03*
X302685Y152562D03*
X308180Y157370D03*
X312264Y176665D03*
Y168665D03*
X303377Y183834D03*
X303550Y172665D03*
X303487Y178560D03*
X304363Y186629D03*
X302897Y190185D03*
X312264Y196665D03*
Y192665D03*
X303667Y200864D03*
X312377Y186778D03*
X300814Y192859D03*
X312296Y204864D03*
Y208864D03*
X303756Y212455D03*
X303690Y207037D03*
X301057Y221642D03*
X307937Y219379D03*
X308565Y228631D03*
X298373Y236189D03*
X298314Y248765D03*
X302471Y265897D03*
X304971D03*
X298811Y270695D03*
Y268195D03*
X315079Y314890D03*
X312263Y324518D03*
X301943Y328867D03*
X308952Y356875D03*
X312316Y356747D03*
X299000Y377912D03*
Y386500D03*
X299088Y397912D03*
X322847Y19806D03*
X321840Y14408D03*
X322113Y26187D03*
X316751Y86012D03*
Y94374D03*
X324057Y116594D03*
X318031Y110784D03*
X323031D03*
X324057Y119594D03*
X327591Y125107D03*
X322610Y124663D03*
X317588Y124879D03*
X329064Y142862D03*
X330105Y148717D03*
X323954Y138838D03*
X317345Y218085D03*
X320145D03*
X323945Y216385D03*
X326658Y216970D03*
Y219470D03*
X326724Y226320D03*
X326658Y221970D03*
X329685Y228646D03*
X328642Y232971D03*
X322672Y249108D03*
X325292Y244571D03*
X314053Y248371D03*
X327032Y303962D03*
X314855Y311740D03*
X318508Y324322D03*
X315944Y332584D03*
X316067Y347937D03*
X321416Y348015D03*
X317333Y353470D03*
X318500Y356519D03*
X315310Y356712D03*
X318660Y539315D03*
X320785Y553287D03*
X327456Y550065D03*
X321119Y622912D03*
X330905Y15806D03*
Y19806D03*
Y27806D03*
X333674Y97667D03*
X342134Y103411D03*
X342528Y97667D03*
X337924Y95111D03*
X329330Y102495D03*
X342293Y106561D03*
X336205Y143762D03*
X335153Y195176D03*
X332653D03*
X336671Y199248D03*
X337653Y195176D03*
X340153D03*
X339671Y199248D03*
X336671Y201748D03*
X334507Y206806D03*
X337007D03*
X335234Y210509D03*
X332734D03*
X339671Y202048D03*
X343271Y230117D03*
X338681Y227824D03*
X334426Y230556D03*
X339287Y238714D03*
X333411Y242078D03*
X338768Y246874D03*
X340988Y244297D03*
X332635Y256394D03*
X347058Y399918D03*
X339072Y416888D03*
Y419488D03*
Y422088D03*
X345050Y454334D03*
X337078Y551381D03*
X335399Y544718D03*
X333985Y1017945D03*
X341077Y1018056D03*
X339251Y1138130D03*
X336755Y1143489D03*
X340500Y1147500D03*
X335190Y1173065D03*
X341266Y1171956D03*
X330800Y1174500D03*
X343121Y1188412D03*
X342009Y1176100D03*
X339776Y1187962D03*
X335502Y1188222D03*
X339540Y1196894D03*
X358636Y90615D03*
X353324Y90650D03*
X362957Y99961D03*
X353074Y95236D03*
X359376Y290592D03*
X348351Y319372D03*
X348806Y315427D03*
X351132Y322202D03*
X349120Y336100D03*
X351136Y372334D03*
X350486Y377173D03*
X358491D03*
X347591Y391533D03*
X359486Y385123D03*
X349311Y385644D03*
X354486Y385123D03*
X357655Y405889D03*
Y408489D03*
X358248Y403300D03*
X353894Y406060D03*
X354155Y421489D03*
Y418889D03*
Y416289D03*
X350163Y412106D03*
X357655Y413689D03*
Y416289D03*
Y421489D03*
Y418889D03*
Y424089D03*
Y411089D03*
X358042Y432718D03*
X357655Y426689D03*
X358042Y435518D03*
X358754Y450091D03*
X356241Y447001D03*
X359241D03*
X353320Y454214D03*
X353663Y449045D03*
X353367Y459330D03*
X358754Y462060D03*
X353670Y473571D03*
Y481071D03*
Y478571D03*
Y476071D03*
X360242Y477053D03*
X357742D03*
X358207Y836462D03*
X346366Y1134729D03*
X361621D03*
X349748D03*
X357748D03*
X353748D03*
X352545Y1142666D03*
X360877Y1157404D03*
X354420Y1157544D03*
X352931Y1167768D03*
X357950D03*
X357057Y1179542D03*
X357796Y1188058D03*
X357083Y1185205D03*
X361792Y1187310D03*
X348432Y1187215D03*
X348125Y1180175D03*
X358368Y1201043D03*
X354398D03*
X350402D03*
X346387Y1199256D03*
X360523Y1192282D03*
X349276Y1217228D03*
X351940Y1219895D03*
X362332Y1230265D03*
X355215Y1223170D03*
X360273Y1228226D03*
X358062Y1226016D03*
X371871Y85193D03*
Y82593D03*
Y79993D03*
Y77393D03*
Y74793D03*
X371915Y92874D03*
X363007Y95236D03*
X373942Y104249D03*
Y107649D03*
X370964Y162368D03*
X373564D03*
X372275Y208213D03*
X379147Y208695D03*
X376347D03*
Y211695D03*
X372275Y210713D03*
Y213213D03*
X361819Y207978D03*
Y212978D03*
Y215478D03*
Y210478D03*
X372275Y215713D03*
X367648Y264180D03*
X365148D03*
X365073Y258880D03*
X374042Y270026D03*
X376842D03*
X374042Y267526D03*
X376842D03*
X371417Y353820D03*
X365559Y354300D03*
X377237Y371060D03*
X373264Y379429D03*
X378875Y379088D03*
X366526Y377173D03*
X370486D03*
X362486Y385123D03*
X366486D03*
X370160Y391569D03*
X368587Y401066D03*
X378927Y406739D03*
X367919Y439318D03*
X375919Y442118D03*
Y439318D03*
X367919Y442118D03*
X361754Y450091D03*
X367564Y456034D03*
Y461034D03*
X373546Y470001D03*
X376046D03*
X361754Y462060D03*
X373971Y489036D03*
X371832Y485580D03*
X374332D03*
X376832D03*
X366420Y479986D03*
Y477486D03*
X363686Y478668D03*
Y476168D03*
X376207Y492836D03*
Y495636D03*
X376881Y518564D03*
X363015Y710365D03*
X365887Y710329D03*
X372400Y746300D03*
X372300Y750000D03*
X373500Y767300D03*
X376300D03*
X370415Y766108D03*
X373703Y782555D03*
X365850Y773950D03*
X371436Y791188D03*
X365691Y815127D03*
X371507Y815303D03*
X362042Y814772D03*
X368067Y925136D03*
X370214Y943812D03*
X368626Y931346D03*
X368964Y937738D03*
X372858Y935136D03*
X366761Y934550D03*
X363893Y946863D03*
X379928Y949774D03*
X379245Y956643D03*
X378875Y961862D03*
X370214Y947812D03*
X370101Y953699D03*
X370214Y963812D03*
Y971812D03*
X378928Y967812D03*
X372501Y1123695D03*
X365748Y1134325D03*
X368657Y1150087D03*
X366133Y1170767D03*
X366429Y1185238D03*
X366222Y1180235D03*
X362402Y1201039D03*
X366402Y1200969D03*
X366521Y1208993D03*
X370202Y1314764D03*
Y1311364D03*
X383612Y33768D03*
X388612Y31168D03*
X387948Y27288D03*
X380196Y98551D03*
X390750Y97475D03*
X383746Y103783D03*
X390681Y106186D03*
X380664Y165393D03*
Y162793D03*
Y167993D03*
Y170493D03*
X387588Y177616D03*
X382872Y181366D03*
X379661Y181426D03*
X385667Y181009D03*
X390842Y168697D03*
X388169Y172190D03*
X391930Y191941D03*
X382486Y184012D03*
X379869Y184221D03*
X393939Y206767D03*
X383905Y211359D03*
X387608Y213132D03*
X378847Y211695D03*
X383905Y213859D03*
X394069Y221708D03*
X393484Y224421D03*
X387608Y215632D03*
X387852Y256303D03*
X387611Y265896D03*
X382524Y265701D03*
X392627Y266114D03*
X379342Y270026D03*
Y267526D03*
X384159Y281716D03*
X390100Y281982D03*
X391737Y377581D03*
X384173Y379028D03*
X381237Y371076D03*
X394237Y379591D03*
X391940Y383817D03*
Y388817D03*
Y386317D03*
X385864Y398278D03*
X383364D03*
X378927Y409539D03*
X381927D03*
Y407039D03*
X381591Y401981D03*
X384091D03*
X378210Y424067D03*
X380710D03*
X385710D03*
X383210D03*
X378445Y413611D03*
X380945D03*
X385945D03*
X383445D03*
X385584Y438293D03*
Y441093D03*
Y443893D03*
X393646Y474382D03*
X385634Y472020D03*
X393662Y470382D03*
X385694Y477318D03*
X385293Y466409D03*
X387141Y484882D03*
X385131Y487382D03*
X391470Y732865D03*
X380963Y731000D03*
X381875Y740341D03*
X379800Y769200D03*
X380331Y782627D03*
X380607Y786932D03*
X387958Y813700D03*
X381631Y814147D03*
X384666Y814103D03*
X383391Y804000D03*
X386589Y864408D03*
X383462Y860535D03*
X392584Y875845D03*
X382675Y870151D03*
X391614Y930676D03*
X384856Y947987D03*
X378119Y953696D03*
X392910Y948536D03*
X393998Y971780D03*
X378790Y1001083D03*
X380280Y1006071D03*
X383710Y1007283D03*
X382465Y1012430D03*
X378410Y1131573D03*
X380261Y1129692D03*
X385091Y1297453D03*
Y1300853D03*
X386415Y1321645D03*
X391691Y1326715D03*
X392234Y1369579D03*
Y1364501D03*
X391757Y1383480D03*
X391852Y1389931D03*
X393951Y1447455D03*
X381900Y1544800D03*
X389700Y1536900D03*
X391740Y1545629D03*
Y1540529D03*
X382017Y1559700D03*
X395296Y1561024D03*
X391740Y1550729D03*
Y1555829D03*
X410789Y22627D03*
X408680Y37530D03*
X396680Y37543D03*
X400714Y45448D03*
X404686D03*
X397731Y100625D03*
X402104Y112083D03*
X406393Y103621D03*
X405912Y172665D03*
X405739Y183834D03*
X405849Y178560D03*
X406725Y186629D03*
X399984Y192490D03*
X405259Y190185D03*
X406029Y200864D03*
X395942Y192300D03*
X398939Y206767D03*
X396439D03*
X406118Y212455D03*
X406052Y207037D03*
X395184Y228221D03*
X399069Y221708D03*
X396569D03*
X403419Y221642D03*
X395184Y231021D03*
X410299Y219379D03*
X410927Y228631D03*
X400735Y236189D03*
X398235D03*
X395735D03*
X400676Y248765D03*
X398176D03*
X395676D03*
X407333Y265897D03*
X404833D03*
X401173Y268195D03*
Y270695D03*
X398373Y268195D03*
X395873D03*
Y270695D03*
X398373D03*
X405843Y315158D03*
X403343D03*
X394883Y341777D03*
Y338377D03*
X410086Y336795D03*
X409655Y331589D03*
X410688Y344736D03*
X400993Y331589D03*
Y335589D03*
X400728Y353152D03*
X411007Y356743D03*
X406421Y387151D03*
Y382151D03*
Y384651D03*
X398453Y387702D03*
X401253D03*
X394653Y389402D03*
X395577Y438293D03*
Y441093D03*
Y443893D03*
X397315Y471560D03*
X405801Y475560D03*
X405301Y467560D03*
X397315Y475560D03*
X406200Y741300D03*
X397223Y796792D03*
X400023D03*
X397900Y789000D03*
X407000Y784700D03*
X404468Y864407D03*
X396306Y864409D03*
X406770Y869767D03*
X405466Y881299D03*
X397431Y870654D03*
X401108Y878487D03*
X401121Y929686D03*
X409121D03*
X401121Y932186D03*
X409121D03*
X405179Y959051D03*
X404971Y956256D03*
X402354Y956465D03*
X401968Y959111D03*
X399173Y959468D03*
X397252Y962861D03*
X404176Y977684D03*
Y975084D03*
Y969984D03*
Y972484D03*
X396671Y968287D03*
X406954Y982970D03*
X409554D03*
X404354D03*
X407547Y1058097D03*
X410047D03*
X405047D03*
X407547Y1060697D03*
X410047D03*
X405047D03*
X408989Y1082501D03*
X409015Y1087705D03*
Y1085205D03*
X408847Y1090956D03*
Y1093956D03*
X406895Y1107997D03*
X402695D03*
Y1110897D03*
X407780Y1113648D03*
X409231Y1118801D03*
X406995Y1110597D03*
X404895Y1112397D03*
X404795Y1109397D03*
X402695Y1113797D03*
X408961Y1162384D03*
Y1164884D03*
Y1167384D03*
Y1169884D03*
Y1172384D03*
X403263Y1160834D03*
X408961Y1174884D03*
X406319Y1186709D03*
Y1184209D03*
Y1181709D03*
Y1179209D03*
X404004Y1192621D03*
Y1190121D03*
X397063Y1221428D03*
X401063D03*
X405063D03*
X409063D03*
X397063Y1233428D03*
Y1229428D03*
Y1225428D03*
X401063Y1237428D03*
Y1233428D03*
Y1229428D03*
Y1225428D03*
X405063Y1237428D03*
Y1233428D03*
Y1229428D03*
Y1225428D03*
X409063Y1237428D03*
Y1233428D03*
Y1229428D03*
Y1225428D03*
X401063Y1241428D03*
X405063Y1245428D03*
Y1241428D03*
X409063Y1245428D03*
Y1241428D03*
X404324Y1271889D03*
Y1275889D03*
X407767Y1292198D03*
X403678Y1295426D03*
X398584Y1313443D03*
X401011Y1307258D03*
X402967Y1319815D03*
X409220Y1315516D03*
X404583Y1316131D03*
X404921Y1321819D03*
X408787Y1321795D03*
X399959Y1352153D03*
X408159Y1349072D03*
X404759D03*
X395112Y1395690D03*
X398340Y1399779D03*
X395770Y1389817D03*
X410172Y1402446D03*
X402489Y1417275D03*
X405889D03*
X407970Y1449751D03*
X404500Y1452500D03*
X395888Y1450022D03*
X395199Y1482223D03*
X395380Y1485778D03*
X397266Y1514647D03*
X398747Y1500959D03*
X395370Y1501022D03*
X397266Y1518047D03*
X408964Y1531149D03*
X394391Y1537786D03*
Y1535286D03*
X399373Y1555855D03*
X405496Y1561024D03*
X400396D03*
X410596D03*
X397461Y1569560D03*
X401461D03*
X416900Y33400D03*
X422473Y22627D03*
X422450Y30483D03*
X422378Y26534D03*
X414145Y27486D03*
X413904Y32569D03*
X426147Y147540D03*
X414626Y176665D03*
Y168665D03*
Y196665D03*
Y192665D03*
X414739Y186778D03*
X414658Y204864D03*
Y208864D03*
X423651Y307470D03*
X419177Y304470D03*
X415777D03*
X422988Y323627D03*
X415129Y325181D03*
X412671Y333418D03*
X412812Y330617D03*
X426830Y359026D03*
X426138Y355079D03*
X416574Y357528D03*
X421413Y359053D03*
X412318Y367903D03*
X420422Y367859D03*
X418997Y382210D03*
Y384710D03*
Y387210D03*
X422215Y424939D03*
Y427439D03*
X414924Y435321D03*
Y438121D03*
X412124Y435321D03*
Y438121D03*
X414924Y440921D03*
X412124D03*
X414924Y443721D03*
X412124D03*
X426647Y452987D03*
X421267Y452799D03*
X414910Y448931D03*
X415433Y459170D03*
X425673Y461607D03*
X424876Y471334D03*
X418801Y474513D03*
X414275Y492469D03*
X424731Y492704D03*
X414275Y497469D03*
Y499969D03*
X427693Y498943D03*
X424731Y497704D03*
Y495204D03*
Y500204D03*
X414275Y494969D03*
X419340Y549990D03*
X419140Y547390D03*
Y544790D03*
X419340Y552590D03*
Y555190D03*
X423963Y625778D03*
X426607Y712360D03*
Y709760D03*
X424993Y728291D03*
X423700Y795500D03*
X426300Y797400D03*
X421200Y786400D03*
X411267Y829193D03*
Y831693D03*
X416267D03*
X413767D03*
Y829193D03*
X416267D03*
X425062Y883981D03*
X417121Y929686D03*
X425121D03*
X417121Y932186D03*
X425121D03*
X411960Y962261D03*
X414560D03*
X417160D03*
X411276Y978109D03*
X416476D03*
X413876D03*
X415047Y1058097D03*
X412547D03*
X415047Y1060697D03*
X412547D03*
X411989Y1082501D03*
X412015Y1085205D03*
X414989Y1082501D03*
X415015Y1085205D03*
Y1088205D03*
X412015D03*
X412297Y1091227D03*
X425060Y1101917D03*
X420782Y1105552D03*
X423340Y1104335D03*
X424995Y1106897D03*
X416988Y1104792D03*
X418495Y1106867D03*
X414580Y1113648D03*
X412080D03*
X411461Y1162384D03*
Y1164884D03*
Y1167384D03*
Y1169884D03*
Y1172384D03*
X420619Y1179421D03*
Y1181921D03*
Y1184421D03*
Y1186921D03*
X411461Y1174884D03*
X422934Y1192621D03*
Y1190121D03*
X417469Y1192621D03*
Y1190121D03*
X413063Y1221428D03*
X417063D03*
X421063D03*
X425063D03*
X413063Y1237428D03*
Y1233428D03*
Y1229428D03*
Y1225428D03*
X417063Y1237428D03*
Y1233428D03*
Y1229428D03*
Y1225428D03*
X421063Y1237428D03*
Y1233428D03*
Y1229428D03*
Y1225428D03*
X425063Y1237428D03*
Y1233428D03*
Y1229428D03*
Y1225428D03*
X413063Y1245428D03*
Y1241428D03*
X417063Y1245428D03*
Y1241428D03*
X421063Y1245428D03*
Y1241428D03*
X425063Y1245428D03*
Y1241428D03*
X425702Y1257160D03*
X422702Y1260160D03*
Y1257160D03*
X425702Y1260160D03*
X419702Y1257160D03*
Y1260160D03*
X413526Y1288938D03*
X419977Y1288843D03*
X413640Y1292856D03*
X419545Y1317722D03*
X413127Y1318011D03*
X425283Y1364023D03*
X417305Y1359169D03*
X425855Y1360495D03*
X425912Y1357141D03*
X416029Y1371572D03*
X420636Y1383912D03*
X418610Y1371590D03*
X423400Y1394500D03*
X423200Y1397500D03*
X418430Y1394237D03*
X422729Y1400490D03*
X420925Y1390330D03*
X419045Y1398874D03*
X421300Y1415400D03*
X419100Y1402200D03*
X421200Y1417900D03*
X411000Y1463500D03*
Y1460500D03*
Y1457500D03*
Y1454500D03*
Y1451000D03*
X413934Y1477101D03*
X417334D03*
X415202Y1496118D03*
Y1499518D03*
X417153Y1516886D03*
X413753D03*
X419619Y1539978D03*
X421454Y1544625D03*
X422539Y1534361D03*
X426701Y1541947D03*
X418151Y1552470D03*
X417461Y1569584D03*
X429919Y141247D03*
X437386Y143740D03*
X434766Y148277D03*
X431525Y304470D03*
X434925D03*
X427051Y307470D03*
X441296Y325061D03*
X436666Y322583D03*
X427713Y321965D03*
X430361Y323187D03*
X443424Y332988D03*
X440538Y355372D03*
X428420Y353578D03*
X435886Y353867D03*
X431524Y370309D03*
X434924D03*
X428637Y408104D03*
X431437D03*
X434237D03*
X428354Y420375D03*
X431154D03*
X433954D03*
X438098Y442114D03*
X437835Y435101D03*
X432270Y431112D03*
X432440Y440101D03*
X432075Y452718D03*
X438086Y452601D03*
X438078Y447121D03*
X433673Y461607D03*
X429673D03*
X435789Y501525D03*
X427568Y502003D03*
X435831Y498923D03*
X438644Y500461D03*
X428740Y549990D03*
X442804Y546990D03*
Y544390D03*
X428740Y546990D03*
Y544390D03*
Y555190D03*
Y552590D03*
X431384D03*
Y555190D03*
Y544390D03*
Y546990D03*
Y549990D03*
X443144Y628667D03*
X441162Y638313D03*
X439290Y712399D03*
X436790D03*
X439290Y709799D03*
X436790D03*
X434290Y712399D03*
Y709799D03*
X429290D03*
X431790Y712399D03*
X429290D03*
X431790Y709799D03*
X429253Y759847D03*
X432303Y785067D03*
X434100Y797400D03*
X430600D03*
X443091Y1026266D03*
X432678Y1016186D03*
X429878D03*
X427078D03*
X427052Y1019384D03*
X429852D03*
X432652D03*
X433378Y1091816D03*
Y1089316D03*
X430878Y1084316D03*
Y1086816D03*
X433378D03*
Y1084316D03*
X436244Y1090288D03*
X433378Y1081816D03*
X430878D03*
X429677Y1106955D03*
X439023Y1107997D03*
X436244Y1093088D03*
X434823Y1107997D03*
X431476Y1115896D03*
X427810Y1110092D03*
X439908Y1113648D03*
X441359Y1116101D03*
Y1118801D03*
X439123Y1110597D03*
X434823Y1113797D03*
Y1110897D03*
X437023Y1112397D03*
X436923Y1109397D03*
X431476Y1118396D03*
X429348Y1129092D03*
X432838Y1128821D03*
X436789Y1167384D03*
Y1164884D03*
Y1162384D03*
Y1172384D03*
Y1169884D03*
X439289Y1167384D03*
Y1164884D03*
Y1162384D03*
X427231D03*
X429731D03*
Y1164884D03*
Y1167384D03*
Y1169884D03*
Y1172384D03*
X427231D03*
Y1169884D03*
Y1167384D03*
Y1164884D03*
X439289Y1172384D03*
Y1169884D03*
X437132Y1158266D03*
X433249Y1186709D03*
Y1184209D03*
Y1181709D03*
Y1179209D03*
X429731Y1174884D03*
X427231D03*
X436789D03*
X439289D03*
X430934Y1190121D03*
Y1192621D03*
X429063Y1221428D03*
X433063D03*
X429063Y1237428D03*
Y1233428D03*
Y1229428D03*
Y1225428D03*
X433063Y1237428D03*
Y1233428D03*
Y1229428D03*
Y1225428D03*
X429063Y1245428D03*
Y1241428D03*
X433063Y1245428D03*
Y1241428D03*
X440702Y1260160D03*
Y1257160D03*
X437702Y1260160D03*
Y1257160D03*
X428702D03*
X431702Y1260160D03*
Y1257160D03*
X434702Y1260160D03*
Y1257160D03*
X428702Y1260160D03*
X434424Y1286274D03*
X430527Y1289198D03*
X440906D03*
X431867Y1315696D03*
X431885Y1313115D03*
X439434Y1322369D03*
X429530Y1325051D03*
X445949Y141247D03*
X450436Y143518D03*
X449536Y152373D03*
X452686Y152562D03*
X458181Y157370D03*
X443508Y337713D03*
X446566Y337917D03*
X443480Y344014D03*
X450852Y372054D03*
X455885Y367702D03*
X448391Y382641D03*
X448323Y379643D03*
X451144Y468809D03*
X459414Y468689D03*
X459757Y463520D03*
X459461Y473805D03*
X459929Y491669D03*
X450942Y506449D03*
X448442D03*
X445942D03*
X460537Y501905D03*
X459952Y496842D03*
X459645Y509486D03*
X446025Y511512D03*
X448525D03*
X446025Y519699D03*
X448525D03*
X452404Y549790D03*
X443004Y549890D03*
X452404Y546990D03*
Y544390D03*
X443004Y555090D03*
X452404Y552390D03*
Y554990D03*
X443004Y552490D03*
X455009Y554912D03*
Y552312D03*
Y544312D03*
Y546912D03*
Y549712D03*
X447279Y637031D03*
X447921Y630789D03*
X453552Y631779D03*
X446987Y643360D03*
X456469Y638302D03*
X460498Y870334D03*
X458120Y974701D03*
X451460Y974695D03*
X450591Y1004766D03*
X453270Y1003763D03*
X459360Y1012325D03*
X443591Y1019766D03*
X459885Y1018860D03*
X451140Y1021793D03*
X447091Y1019766D03*
X450875Y1028416D03*
X443091Y1034266D03*
X452091Y1039880D03*
X459700Y1032266D03*
X455468Y1104335D03*
X457188Y1101917D03*
X452910Y1105552D03*
X457123Y1106897D03*
X449116Y1104792D03*
X450623Y1106867D03*
X444208Y1113648D03*
X446708D03*
X457559Y1169884D03*
Y1167384D03*
Y1164884D03*
Y1162384D03*
X455059D03*
Y1164884D03*
Y1167384D03*
Y1169884D03*
Y1172384D03*
X457559D03*
X455059Y1174884D03*
X457559D03*
X447549Y1179421D03*
Y1181921D03*
Y1184421D03*
Y1186921D03*
X449864Y1190121D03*
Y1192621D03*
X449702Y1260160D03*
Y1257160D03*
X443702Y1260160D03*
X446702D03*
Y1257160D03*
X443702D03*
X451304Y1297045D03*
X454385Y1301845D03*
Y1305245D03*
X444288Y1314391D03*
X462089Y116594D03*
X474058D03*
X473032Y110784D03*
X468032D03*
X462089Y119594D03*
X474058D03*
X477592Y125107D03*
X462523Y124283D03*
X467589Y124879D03*
X472611Y124663D03*
X473955Y138838D03*
X460930Y161306D03*
X467346Y218085D03*
X470146D03*
X473946Y216385D03*
X475293Y244571D03*
X472673Y249108D03*
X464054Y248371D03*
X460950Y328185D03*
Y324785D03*
X463950Y332659D03*
Y336059D03*
X460950Y343933D03*
Y340533D03*
X472810Y347995D03*
X472913Y360089D03*
X472608Y352495D03*
X467335Y359944D03*
X463950Y351807D03*
Y348407D03*
X472913Y369089D03*
Y373589D03*
X469530Y366754D03*
X472913Y387089D03*
Y391589D03*
Y382589D03*
Y378089D03*
X470796Y394592D03*
X464848Y464566D03*
X467848D03*
X465126Y460435D03*
X462126D03*
X473658Y470509D03*
Y475509D03*
X467848Y476535D03*
X464848D03*
X468558Y495669D03*
Y499669D03*
Y516609D03*
X464199Y510184D03*
X468850Y545586D03*
X469300Y799500D03*
X459245Y807152D03*
X473654Y821234D03*
X472399Y839566D03*
X463404Y846870D03*
X465492Y861970D03*
X471726Y883705D03*
X474540Y927341D03*
X471110Y921577D03*
X471876Y937236D03*
X471068Y930235D03*
X473992Y952546D03*
X475018Y992568D03*
X467345Y996480D03*
X459360Y1004680D03*
X464795Y1000647D03*
X462185Y1016825D03*
X459860Y1015825D03*
X464385Y1038534D03*
X471558Y1029482D03*
X471755Y1038665D03*
X470610Y1033783D03*
X475588Y1043055D03*
X473639Y1030952D03*
X459700Y1035716D03*
X470978Y1046591D03*
X474348Y1090171D03*
X462913Y1106365D03*
X474277Y1093048D03*
X472482Y1107997D03*
X468282D03*
X459938Y1110092D03*
X463604Y1115896D03*
X473367Y1113648D03*
X474818Y1116101D03*
Y1118801D03*
X472582Y1110597D03*
X470482Y1112397D03*
X468282Y1110897D03*
Y1113797D03*
X470382Y1109397D03*
X463604Y1118396D03*
X462687Y1160834D03*
X474548Y1172384D03*
Y1169884D03*
Y1167384D03*
Y1164884D03*
Y1162384D03*
X468850Y1160834D03*
X474548Y1174884D03*
X465785Y1197471D03*
X461285Y1193471D03*
Y1197471D03*
X465785Y1193471D03*
X474647Y1260160D03*
Y1257160D03*
X471647D03*
Y1260160D03*
X459290Y1297035D03*
X463290D03*
X492135Y103411D03*
X492529Y97667D03*
X483675D03*
X487925Y95111D03*
X479331Y102495D03*
X479065Y142862D03*
X486206Y143762D03*
X480106Y148717D03*
X487654Y195176D03*
X489672Y199248D03*
X485154Y195176D03*
X482654D03*
X486672Y199248D03*
X490154Y195176D03*
X485235Y210509D03*
X482735D03*
X489672Y202048D03*
X486672Y201748D03*
X484508Y206806D03*
X487008D03*
X476659Y216970D03*
Y219470D03*
X476725Y226320D03*
X476659Y221970D03*
X493272Y230117D03*
X484427Y230556D03*
X488682Y227824D03*
X479686Y228646D03*
X483412Y242078D03*
X478643Y232971D03*
X488769Y246874D03*
X489288Y238714D03*
X490989Y244297D03*
X482636Y256394D03*
X492817Y357111D03*
X491843Y351089D03*
X481724Y373589D03*
Y369089D03*
X490885Y373589D03*
X491053Y365423D03*
X491289Y391589D03*
X481724Y382589D03*
Y378089D03*
X490885Y382570D03*
X490985Y412342D03*
X488438Y418417D03*
X485485Y439903D03*
X489485D03*
X481485Y439900D03*
Y431917D03*
X489485Y431417D03*
X492736Y491982D03*
X482836Y534249D03*
X491818Y534909D03*
X491445Y541135D03*
X482905Y527726D03*
Y548726D03*
Y544726D03*
X491534Y552726D03*
X491511Y546553D03*
X487209Y611071D03*
X484772Y621311D03*
X493392Y622285D03*
X493580Y616905D03*
X484772Y629311D03*
Y625311D03*
X493661Y627713D03*
X493778Y633724D03*
X481165Y646036D03*
X483059Y662649D03*
X488765Y667224D03*
X481742Y657477D03*
X486837Y701306D03*
Y704706D03*
X489406Y797558D03*
X489572Y822805D03*
X479448Y828594D03*
X479700Y847600D03*
X477574Y860815D03*
X490706Y859339D03*
X491616Y938771D03*
X476475Y952249D03*
X479613Y952189D03*
X489163Y977163D03*
X487091Y989550D03*
X480711Y999941D03*
X477857Y1004375D03*
X488041Y1020440D03*
X485678Y1039880D03*
X485633Y1036155D03*
X477765Y1093432D03*
X477607Y1089942D03*
X491503Y1086796D03*
Y1084296D03*
X478517Y1086724D03*
Y1084224D03*
Y1081724D03*
X476017D03*
Y1084224D03*
Y1086724D03*
X486369Y1105552D03*
X490647Y1101917D03*
X488927Y1104335D03*
X490582Y1106897D03*
X482575Y1104792D03*
X484082Y1106867D03*
X480167Y1113648D03*
X477667D03*
X477048Y1172384D03*
Y1169884D03*
Y1167384D03*
Y1164884D03*
Y1162384D03*
X479521Y1179209D03*
Y1181709D03*
Y1184209D03*
Y1186709D03*
X477048Y1174884D03*
X490671Y1192621D03*
Y1190121D03*
X477206Y1192621D03*
Y1190121D03*
X489647Y1260160D03*
Y1257160D03*
X486647D03*
Y1260160D03*
X480647Y1257160D03*
X477647D03*
Y1260160D03*
X480647D03*
X483647Y1257160D03*
Y1260160D03*
X490100Y1302100D03*
X487600D03*
X503325Y90650D03*
X508637Y90615D03*
X503075Y95236D03*
X492294Y106561D03*
X496023Y362913D03*
X497048Y369450D03*
X495750Y377531D03*
X506500Y379687D03*
X495203Y386890D03*
X503729Y439919D03*
X503682Y448419D03*
X500729Y469905D03*
X496729Y470419D03*
X504729Y469905D03*
X496729Y461919D03*
X504729Y461419D03*
X505476Y485128D03*
X497095Y481467D03*
X501224Y492050D03*
X501649Y482165D03*
X501887Y504825D03*
X499387D03*
X496887D03*
X500890Y500202D03*
X502493Y495917D03*
X492736Y495982D03*
X501828Y517401D03*
X499328D03*
X496828D03*
X502379Y522569D03*
X495444Y531948D03*
X503494Y531882D03*
X502379Y525369D03*
X500994Y531882D03*
X498494D03*
X504079Y529169D03*
X503729Y555194D03*
X500929D03*
Y571194D03*
X503729D03*
Y563194D03*
X500929D03*
X505286Y581222D03*
X502486D03*
X505286Y591215D03*
X502486D03*
X505458Y610562D03*
X502658D03*
Y607762D03*
X505458D03*
X497448Y610548D03*
X504265Y633736D03*
X499258Y633716D03*
X506278Y628078D03*
X494465Y657772D03*
X502755Y657694D03*
X496070Y665976D03*
X499528Y657843D03*
X504966Y678098D03*
X498284Y681453D03*
Y678953D03*
X500714Y708755D03*
X502832Y720491D03*
X504895Y770457D03*
X501495D03*
X504508Y783817D03*
X506166Y793224D03*
X504641Y789139D03*
X507095Y814784D03*
X494677Y830468D03*
X509665Y824512D03*
X495073Y835586D03*
X495470Y844271D03*
X495700Y849389D03*
X503383Y863025D03*
X498507Y865392D03*
X508248Y873319D03*
X509791Y881932D03*
X509017Y905295D03*
X494315Y941212D03*
X503144Y957934D03*
X504088Y985171D03*
X506888D03*
X506702Y978947D03*
X493091Y989550D03*
X503933Y981392D03*
X498435Y1008766D03*
X506566D03*
Y996766D03*
X498524Y997590D03*
X498585Y1016266D03*
X506566Y1012266D03*
X503177Y1058097D03*
X495677D03*
X493177D03*
X498177D03*
X500677D03*
X503177Y1060697D03*
X495677D03*
X493177D03*
X498177D03*
X500677D03*
X494003Y1086796D03*
X496503D03*
X499003D03*
X501503D03*
Y1084296D03*
X499003D03*
X496503D03*
X494003D03*
X501831Y1090288D03*
X496372Y1106298D03*
X504610Y1107997D03*
X501831Y1093088D03*
X500410Y1107997D03*
X497063Y1115896D03*
X505495Y1113648D03*
X506946Y1116101D03*
Y1118801D03*
X504710Y1110597D03*
X500410Y1113797D03*
X502610Y1112397D03*
X500410Y1110897D03*
X502510Y1109397D03*
X493397Y1110092D03*
X497063Y1118396D03*
X498727Y1128759D03*
X495236Y1129094D03*
X502376Y1172384D03*
Y1169884D03*
Y1167384D03*
Y1164884D03*
Y1162384D03*
X504876Y1172384D03*
Y1169884D03*
Y1167384D03*
Y1164884D03*
Y1162384D03*
X492818D03*
Y1164884D03*
Y1167384D03*
Y1169884D03*
Y1172384D03*
X495318D03*
Y1169884D03*
Y1167384D03*
Y1164884D03*
Y1162384D03*
X502562Y1158200D03*
X506451Y1179209D03*
Y1181709D03*
Y1184209D03*
Y1186709D03*
X504876Y1174884D03*
X493821Y1186921D03*
Y1184421D03*
Y1181921D03*
Y1179421D03*
X492818Y1174884D03*
X495318D03*
X502376D03*
X504136Y1190121D03*
Y1192621D03*
X496136Y1190121D03*
Y1192621D03*
X506562Y1222194D03*
X502562D03*
X498562D03*
X494562D03*
X506562Y1226194D03*
Y1230194D03*
Y1234194D03*
Y1238194D03*
X502562Y1226194D03*
Y1230194D03*
Y1234194D03*
Y1238194D03*
X498562Y1226194D03*
Y1230194D03*
Y1234194D03*
Y1238194D03*
X494562Y1226194D03*
Y1230194D03*
Y1234194D03*
Y1238194D03*
Y1246194D03*
Y1242194D03*
X506562D03*
Y1246194D03*
X502562Y1242194D03*
Y1246194D03*
X498562Y1242194D03*
Y1246194D03*
X504647Y1257160D03*
X507347D03*
X501647D03*
Y1260160D03*
X495647D03*
X492647D03*
Y1257160D03*
X495647D03*
X498647D03*
Y1260160D03*
X507347D03*
X504647D03*
X521872Y82593D03*
Y85193D03*
Y74793D03*
Y77393D03*
Y79993D03*
X521916Y92874D03*
X512958Y99961D03*
X513008Y95236D03*
X523943Y107649D03*
Y104249D03*
X520965Y162368D03*
X523565D03*
X511820Y207978D03*
Y210478D03*
Y215478D03*
Y212978D03*
X522276Y208213D03*
Y213213D03*
Y210713D03*
Y215713D03*
X515149Y264180D03*
X517649D03*
X515074Y258880D03*
X524043Y270026D03*
Y267526D03*
X514769Y312953D03*
X519638Y314346D03*
X511790Y313804D03*
X512943Y443071D03*
X520823Y442603D03*
X511753Y454339D03*
Y456839D03*
X509253D03*
Y454339D03*
X518240Y459371D03*
X509253Y459339D03*
X511753D03*
X512210Y475825D03*
X517310Y470045D03*
X513310Y462004D03*
X522756Y461818D03*
X508325Y485138D03*
X512210Y478625D03*
X513910Y482425D03*
X513325Y485138D03*
X510825D03*
X519786Y491214D03*
X523489Y492987D03*
X519786Y493714D03*
X523489Y495487D03*
X509955Y537958D03*
X513658Y539731D03*
X518716Y541895D03*
X521216Y544895D03*
Y541895D03*
X513658Y542231D03*
X518416Y544895D03*
X509955Y540458D03*
X521494Y582747D03*
X508086Y581222D03*
X520945Y590801D03*
X508086Y591215D03*
X520770Y597130D03*
X524770Y605637D03*
X518940Y620653D03*
Y617853D03*
X511058Y610562D03*
Y607762D03*
X508258Y610562D03*
Y607762D03*
X520770Y605443D03*
X516770D03*
X523616Y625013D03*
X515267Y627908D03*
X511278Y633473D03*
X521778Y642184D03*
X521868Y666577D03*
X518812Y662874D03*
X510425Y683246D03*
X522200Y677613D03*
X521540Y686319D03*
X515484Y695757D03*
X515504Y701351D03*
X521159Y706388D03*
X515649D03*
X512530Y718301D03*
X514531Y716398D03*
X523929Y706388D03*
X518389D03*
X521131Y741071D03*
X517731D03*
X511724Y741035D03*
X508324D03*
X520549Y761982D03*
X509096Y753072D03*
X515422Y753455D03*
X513504Y755804D03*
X513278Y783286D03*
X520833Y773389D03*
X513551Y773203D03*
X522697Y797102D03*
X519891Y795848D03*
X518157Y803973D03*
X518565Y811973D03*
X520741Y805149D03*
X522481Y824661D03*
X517702Y826600D03*
X514682Y834590D03*
X511741Y846649D03*
X524741Y845149D03*
X520870Y874694D03*
X525159Y913818D03*
X521572Y901500D03*
X516902Y910251D03*
X520146Y939241D03*
X523289Y939195D03*
X521353Y952266D03*
X522544Y992854D03*
X512232Y985172D03*
X514566Y1000766D03*
X514690Y996766D03*
Y1004766D03*
X514566Y1016266D03*
X514649Y1020266D03*
X514843Y1030766D03*
X519500Y1028377D03*
X518497Y1105552D03*
X522775Y1101917D03*
X521055Y1104335D03*
X514703Y1104792D03*
X522710Y1106897D03*
X516210Y1106867D03*
X509795Y1113648D03*
X512295D03*
X520646Y1169884D03*
Y1167384D03*
Y1164884D03*
Y1162384D03*
X523146D03*
Y1164884D03*
Y1167384D03*
Y1169884D03*
Y1172384D03*
X520646D03*
X520751Y1186921D03*
Y1184421D03*
Y1181921D03*
Y1179421D03*
X523146Y1174884D03*
X520646D03*
X523066Y1190121D03*
Y1192621D03*
X522562Y1222194D03*
X518562D03*
X514562D03*
X510562D03*
X522562Y1226194D03*
X518562D03*
Y1230194D03*
Y1234194D03*
X514562Y1226194D03*
Y1230194D03*
Y1234194D03*
Y1238194D03*
X510562Y1226194D03*
Y1230194D03*
Y1234194D03*
Y1238194D03*
X514562Y1242194D03*
Y1246194D03*
X510562Y1242194D03*
Y1246194D03*
X530197Y98551D03*
X540751Y97475D03*
X533747Y103783D03*
X532281Y141247D03*
X528509Y147540D03*
X539748Y143740D03*
X537128Y148277D03*
X530665Y162793D03*
Y165393D03*
Y170493D03*
Y167993D03*
X538170Y172190D03*
X535668Y181009D03*
X529662Y181426D03*
X532873Y181366D03*
X537589Y177616D03*
X529870Y184221D03*
X532487Y184012D03*
X533906Y211359D03*
Y213859D03*
X528848Y211695D03*
X537609Y213132D03*
X526348Y208695D03*
X529148D03*
X526348Y211695D03*
X537609Y215632D03*
X537853Y256303D03*
X532525Y265701D03*
X537612Y265896D03*
X526843Y270026D03*
X529343D03*
X526843Y267526D03*
X529343D03*
X534160Y281716D03*
X540101Y281982D03*
X532659Y359557D03*
X526388Y351301D03*
X531612Y354272D03*
X531636Y349057D03*
X528812Y369164D03*
X533211Y364746D03*
X533115Y371856D03*
X530144Y376062D03*
X531953Y380749D03*
X542034Y392209D03*
X541706Y386223D03*
X533189Y390723D03*
X531953Y385749D03*
X531992Y397552D03*
X526216Y456652D03*
X528716D03*
X526216Y459152D03*
Y461652D03*
X528716Y459152D03*
Y461652D03*
X535119Y491133D03*
X531047Y498151D03*
X535119Y493633D03*
Y496133D03*
Y498633D03*
X531047Y495151D03*
X528547D03*
X528247Y498151D03*
X525288Y537877D03*
X535219Y555897D03*
Y553297D03*
X533488Y548344D03*
X525288Y540377D03*
Y545377D03*
Y542877D03*
X528488Y548344D03*
X525988D03*
X530988D03*
X535219Y561097D03*
Y563697D03*
Y566797D03*
Y558497D03*
X532009Y570478D03*
X529214Y570686D03*
X529423Y573303D03*
X532069Y573689D03*
X532426Y576484D03*
X535819Y578405D03*
X541245Y578986D03*
X524770Y597232D03*
X534820Y596782D03*
X540770Y596729D03*
X529601Y596089D03*
X526756Y613913D03*
Y616713D03*
Y619513D03*
X538826Y614158D03*
Y616958D03*
Y619758D03*
X536770Y605443D03*
X537664Y661556D03*
X534264D03*
X529664Y664056D03*
X526264D03*
X538316Y687357D03*
X535738Y687489D03*
X536087Y702364D03*
X529469Y706230D03*
X526699Y706388D03*
X535585Y736593D03*
X538985D03*
X530985Y741593D03*
X527585D03*
X524598Y753387D03*
X539449Y782389D03*
X537578Y772428D03*
X532304Y806649D03*
X531313Y812850D03*
Y826630D03*
X532316Y833649D03*
X534000Y843000D03*
X537300Y842900D03*
X530741Y845149D03*
X534632Y849830D03*
X525718Y873821D03*
X533468Y878533D03*
X538468Y888033D03*
X530968Y888283D03*
X528975Y898346D03*
X537279Y897943D03*
X533143Y897910D03*
X531076Y913190D03*
X527879Y952189D03*
X530473Y961728D03*
X528500Y1106365D03*
X529191Y1115896D03*
X525525Y1110092D03*
X529191Y1118396D03*
X528274Y1160834D03*
X554198Y68581D03*
X554211Y80581D03*
X546293Y76587D03*
Y72615D03*
X547732Y100625D03*
X540682Y106186D03*
X552105Y112083D03*
X556394Y103621D03*
X548311Y141247D03*
X552798Y143518D03*
X551898Y152373D03*
X555048Y152562D03*
X540843Y168697D03*
X555850Y178560D03*
X555913Y172665D03*
X555740Y183834D03*
X541931Y191941D03*
X555260Y190185D03*
X549985Y192490D03*
X556030Y200864D03*
X548940Y206767D03*
X546440D03*
X543940D03*
X556119Y212455D03*
X556053Y207037D03*
X549070Y221708D03*
X546570D03*
X553420Y221642D03*
X545185Y231021D03*
Y228221D03*
X544070Y221708D03*
X543485Y224421D03*
X550736Y236189D03*
X548236D03*
X545736D03*
X550677Y248765D03*
X548177D03*
X545677D03*
X542628Y266114D03*
X545874Y268195D03*
X548374D03*
X551174Y270695D03*
X554834Y265897D03*
X551174Y268195D03*
X548374Y270695D03*
X545874D03*
X551536Y359223D03*
Y354723D03*
Y350223D03*
Y345723D03*
Y377223D03*
Y372723D03*
Y368223D03*
Y363723D03*
Y381723D03*
X551620Y390723D03*
X553563Y384987D03*
X544738Y581659D03*
X544770Y605443D03*
X551475Y661504D03*
X547227Y678299D03*
X547276Y675521D03*
X543101Y698772D03*
X540379Y719785D03*
X557751Y750851D03*
X550420Y793743D03*
X556326D03*
X540578Y793889D03*
X544515Y793875D03*
X544741Y809649D03*
X544878Y816309D03*
X546855Y829949D03*
X550087Y829836D03*
X556326Y829989D03*
X556741Y820149D03*
X544741Y823149D03*
X546241Y843149D03*
X557836Y851669D03*
X548665Y850399D03*
X540968Y878360D03*
X546940Y871389D03*
X548327Y905295D03*
X552238Y959102D03*
X552923Y988813D03*
X542793Y998507D03*
X544719Y1007522D03*
X551485Y1006648D03*
X551673Y1023900D03*
X548852Y1018307D03*
X545094Y1013678D03*
X545566Y1023731D03*
X554696Y1018469D03*
X556493Y1118351D03*
X557584Y1543411D03*
X560573Y60513D03*
X563433Y60438D03*
X557973Y55513D03*
X569114Y86012D03*
X558341Y88801D03*
X569114Y94374D03*
X561258Y94351D03*
X565207Y94279D03*
X560701Y85731D03*
X564255Y86046D03*
X564451Y116594D03*
X570394Y110784D03*
X564451Y119594D03*
X574973Y124663D03*
X564885Y124283D03*
X569951Y124879D03*
X563292Y161306D03*
X560543Y157370D03*
X564627Y176665D03*
Y168665D03*
X556726Y186629D03*
X564627Y196665D03*
Y192665D03*
X564740Y186778D03*
X564659Y204864D03*
Y208864D03*
X569708Y218085D03*
X572508D03*
X560300Y219379D03*
X560928Y228631D03*
X575035Y249108D03*
X566416Y248371D03*
X557334Y265897D03*
X573479Y374705D03*
X569938Y378317D03*
X559070Y684809D03*
Y700809D03*
Y688209D03*
X561570Y696209D03*
Y692809D03*
X559070Y716809D03*
X561570Y708809D03*
Y712209D03*
X559070Y704209D03*
Y720209D03*
X558616Y732530D03*
X562001Y732834D03*
X562374Y721593D03*
X567428Y750145D03*
X557847Y744599D03*
X563200Y739600D03*
X571493Y763090D03*
X570038Y752339D03*
X564362Y757979D03*
X560263Y782207D03*
X567126Y779066D03*
X571984Y784507D03*
X561001Y806889D03*
X567559Y803008D03*
Y824661D03*
X562400Y818900D03*
X560813Y840574D03*
X568990Y844721D03*
X572476Y845535D03*
X559295Y874267D03*
X559887Y877196D03*
X561134Y869291D03*
X559260Y891043D03*
X559214Y897425D03*
X564165Y894411D03*
X567827Y884000D03*
X562328Y957307D03*
X566303Y951807D03*
X569403D03*
X563103D03*
X570603Y957207D03*
X560923Y980443D03*
X556923Y980523D03*
X564923Y988813D03*
X560923D03*
X556923D03*
X568923D03*
X558112Y1009655D03*
X560912D03*
X567484Y1024003D03*
X571857Y1016827D03*
X559057Y1030563D03*
X562057D03*
X568057Y1030672D03*
X565057D03*
X571857Y1029427D03*
X566058Y1109564D03*
X560211D03*
X566058Y1122164D03*
X560211D03*
X566058Y1134764D03*
X560211D03*
X566058Y1147364D03*
X560211D03*
X566058Y1159964D03*
X560211D03*
X566058Y1172564D03*
X560211D03*
X566058Y1185164D03*
X560211D03*
X568532Y1200001D03*
X575620Y1207737D03*
X569135Y1214372D03*
X564890Y1218169D03*
X570796Y1530309D03*
X567324Y1528151D03*
X572432Y1521462D03*
X565400Y1535100D03*
X563968Y1541445D03*
X568279Y1538438D03*
X572507Y1541375D03*
X586037Y97667D03*
X581693Y102495D03*
X576420Y116594D03*
X575394Y110784D03*
X576420Y119594D03*
X579954Y125107D03*
X581427Y142862D03*
X588568Y143762D03*
X582468Y148717D03*
X576317Y138838D03*
X587516Y195176D03*
X585016D03*
X589034Y199248D03*
X587597Y210509D03*
X585097D03*
X589034Y201748D03*
X586870Y206806D03*
X576308Y216385D03*
X579021Y216970D03*
Y219470D03*
X579087Y226320D03*
X579021Y221970D03*
X586789Y230556D03*
X591044Y227824D03*
X582048Y228646D03*
X585774Y242078D03*
X581005Y232971D03*
X577655Y244571D03*
X584998Y256394D03*
X578193Y336391D03*
X584679Y336285D03*
X576556Y728219D03*
X575979Y732517D03*
X573778Y747437D03*
X577638Y769772D03*
X578271Y763556D03*
X583102Y767137D03*
X587183Y785008D03*
X578204Y775137D03*
X585912Y778470D03*
X588345Y798030D03*
X588659Y790336D03*
X582100Y787600D03*
X586060Y793145D03*
X581001Y810973D03*
X588377Y807536D03*
X588272Y804601D03*
X588231Y801520D03*
X577501Y829069D03*
X588001Y829624D03*
X582737Y819831D03*
X581158Y823473D03*
X573300Y829600D03*
X579827Y888000D03*
X580327Y892000D03*
X586136Y908935D03*
X583065Y903294D03*
X573103Y941307D03*
X585703D03*
X586103Y961807D03*
X573895Y965319D03*
X584923Y988813D03*
X576923D03*
X580923D03*
X588923D03*
X572923D03*
X577704Y1029427D03*
Y1016827D03*
X587880Y1034834D03*
X581967Y1105091D03*
X587467D03*
X582012Y1102091D03*
X587467Y1117691D03*
X581967D03*
X582012Y1127291D03*
Y1114691D03*
X587467Y1130291D03*
X581967D03*
X587467Y1142891D03*
X582012Y1139891D03*
X581967Y1155491D03*
X587467D03*
X581967Y1142891D03*
X582012Y1152491D03*
X581967Y1168091D03*
X587467D03*
X582012Y1165091D03*
X581967Y1180691D03*
X587467D03*
X582012Y1177691D03*
X586502Y1227300D03*
X583520Y1230407D03*
X581803Y1493687D03*
X578859Y1497758D03*
X588859Y1490895D03*
X590826Y1495688D03*
X588507Y1514141D03*
X582027Y1502800D03*
X581803Y1509687D03*
X577931Y1505687D03*
X575809Y1532912D03*
X572849Y1518702D03*
X587809Y1528389D03*
X583809Y1533025D03*
X579809Y1528163D03*
X587809Y1545854D03*
X583809Y1541607D03*
X577571Y1544013D03*
X594497Y103411D03*
X594891Y97667D03*
X605687Y90650D03*
X590287Y95111D03*
X594656Y106561D03*
X590016Y195176D03*
X592516D03*
X592034Y199248D03*
Y202048D03*
X589370Y206806D03*
X595634Y230117D03*
X591131Y246874D03*
X591650Y238714D03*
X593351Y244297D03*
X592900Y309871D03*
X605147Y378600D03*
Y382600D03*
X605262Y458711D03*
X602462D03*
X604606Y463600D03*
X598462Y504684D03*
X599110Y552466D03*
X605011Y603600D03*
Y619600D03*
Y623600D03*
X592272Y877262D03*
X592110Y895611D03*
X601084Y913544D03*
X604715Y914640D03*
X589203Y941407D03*
X591403Y938807D03*
Y936007D03*
X591754Y956979D03*
X597556Y965829D03*
X602484Y965764D03*
X600923Y988813D03*
X592923D03*
X604923D03*
X596923D03*
X599113Y1012354D03*
X593658Y1009354D03*
X593613Y1012354D03*
X599113Y1024954D03*
X593613D03*
X593658Y1021954D03*
X606434Y1041904D03*
X603682Y1053457D03*
X594183Y1220068D03*
X593519Y1224472D03*
X592885Y1229402D03*
X592634Y1234921D03*
X591487Y1501687D03*
X591481Y1509313D03*
X595809Y1532133D03*
X591872Y1518071D03*
X595809Y1546214D03*
X591809Y1542407D03*
X610999Y90615D03*
X615370Y95236D03*
X615320Y99961D03*
X605437Y95236D03*
X620727Y162368D03*
X614182Y210478D03*
Y215478D03*
Y212978D03*
Y207978D03*
X617511Y264180D03*
X620011D03*
X617436Y258880D03*
X607789Y453682D03*
X606026Y455921D03*
X609133Y941137D03*
X605733D03*
X608965Y966414D03*
X616923Y988813D03*
X608923D03*
X612923Y997860D03*
X618878Y1011914D03*
X621479Y1030482D03*
X607993Y1036920D03*
X610780Y1051037D03*
X617634Y1049283D03*
X617894Y1043955D03*
X612955Y1062941D03*
X622736Y1151870D03*
Y1159350D03*
X613738Y1546507D03*
X624234Y74793D03*
Y82593D03*
Y85193D03*
Y77393D03*
Y79993D03*
X624278Y92874D03*
X632559Y98551D03*
X636109Y103783D03*
X626305Y104249D03*
Y107649D03*
X630871Y147540D03*
X634643Y141247D03*
X639490Y148277D03*
X625927Y162368D03*
X623327D03*
X633027Y165393D03*
Y162793D03*
Y170493D03*
Y167993D03*
X639951Y177616D03*
X632024Y181426D03*
X635235Y181366D03*
X632232Y184221D03*
X634849Y184012D03*
X628710Y211695D03*
Y208695D03*
X631510D03*
X624638Y208213D03*
X636268Y211359D03*
Y213859D03*
X631210Y211695D03*
X624638Y213213D03*
Y210713D03*
Y215713D03*
X639974Y265896D03*
X634887Y265701D03*
X629205Y267526D03*
X626405D03*
X631705D03*
X629205Y270026D03*
X626405D03*
X631705D03*
X636522Y281716D03*
X632009Y541863D03*
Y545263D03*
X630201Y553407D03*
X632701D03*
X630201Y550907D03*
X632701D03*
X634185Y569426D03*
X634471Y566929D03*
X628425Y572070D03*
X629772Y569928D03*
X632119Y570962D03*
X631862Y568475D03*
X621592Y1033862D03*
X626476Y1155610D03*
X621727Y1556800D03*
X648655Y76587D03*
Y72615D03*
X650094Y100625D03*
X643113Y97475D03*
X643044Y106186D03*
X650673Y141247D03*
X655160Y143518D03*
X642110Y143740D03*
X654260Y152373D03*
X640532Y172190D03*
X638030Y181009D03*
X643205Y168697D03*
X644293Y191941D03*
X652347Y192490D03*
X646302Y206767D03*
X651302D03*
X648802D03*
X639971Y213132D03*
X648932Y221708D03*
X647547Y228221D03*
X645847Y224421D03*
X647547Y231021D03*
X646432Y221708D03*
X651432D03*
X639971Y215632D03*
X650598Y236189D03*
X648098D03*
X653098D03*
X653039Y248765D03*
X650539D03*
X648039D03*
X640215Y256303D03*
X644990Y266114D03*
X650736Y268195D03*
X653536Y270695D03*
Y268195D03*
X650736Y270695D03*
X648236D03*
Y268195D03*
X642463Y281982D03*
X642414Y545528D03*
X651149Y577716D03*
X648211Y610400D03*
X650958Y668153D03*
X662935Y60513D03*
X665795Y60438D03*
X657507Y58013D03*
X656560Y68581D03*
X671476Y86012D03*
X656573Y80581D03*
X660703Y88801D03*
X663620Y94351D03*
X667569Y94279D03*
X663063Y85731D03*
X666617Y86046D03*
X658756Y103621D03*
X666813Y116594D03*
X654467Y112083D03*
X666813Y119594D03*
X667247Y124283D03*
X672313Y124879D03*
X665654Y161306D03*
X657410Y152562D03*
X662905Y157370D03*
X666989Y176665D03*
Y168665D03*
X658275Y172665D03*
X658212Y178560D03*
X658102Y183834D03*
X659088Y186629D03*
X657622Y190185D03*
X658392Y200864D03*
X666989Y196665D03*
Y192665D03*
X667102Y186778D03*
X667021Y204864D03*
Y208864D03*
X658481Y212455D03*
X658415Y207037D03*
X655782Y221642D03*
X662662Y219379D03*
X663290Y228631D03*
X668886Y248371D03*
X657196Y265897D03*
X659696D03*
X661761Y382109D03*
X661760Y551683D03*
Y561420D03*
Y558917D03*
X657581Y577937D03*
X660586Y606929D03*
X665086Y604567D03*
X665586Y595500D03*
X660827Y612592D03*
X666244Y610072D03*
X660546Y618400D03*
X666180Y616317D03*
X665643Y646055D03*
X658233Y646449D03*
X658064Y650119D03*
X657967Y662981D03*
X662092Y666275D03*
X659209Y691851D03*
X661018Y707592D03*
X688399Y97667D03*
X671476Y94374D03*
X678782Y116594D03*
X684055Y102495D03*
X677756Y110784D03*
X672756D03*
X678782Y119594D03*
X682316Y125107D03*
X677335Y124663D03*
X683789Y142862D03*
X684830Y148717D03*
X678679Y138838D03*
X674870Y218085D03*
X681383Y219470D03*
Y216970D03*
X678670Y216385D03*
X681383Y221970D03*
X681449Y226320D03*
X672070Y218085D03*
X684410Y228646D03*
X683367Y232971D03*
X677397Y249108D03*
X680017Y244571D03*
X682857Y339477D03*
X687055Y376456D03*
X685353Y396718D03*
X678461Y455981D03*
X675237Y465611D03*
X682586Y530000D03*
X682086Y540500D03*
X681086Y547075D03*
X681286Y549800D03*
X680586Y568000D03*
X681126Y558800D03*
X681190Y562800D03*
X696859Y103411D03*
X697253Y97667D03*
X692649Y95111D03*
X697018Y106561D03*
X690930Y143762D03*
X691396Y199248D03*
X687378Y195176D03*
X689878D03*
X694396Y199248D03*
X694878Y195176D03*
X692378D03*
X691396Y201748D03*
X689232Y206806D03*
X687459Y210509D03*
X689959D03*
X694396Y202048D03*
X691732Y206806D03*
X697996Y230117D03*
X689151Y230556D03*
X693406Y227824D03*
X694012Y238714D03*
X688136Y242078D03*
X693493Y246874D03*
X695713Y244297D03*
X690504Y253198D03*
X689486Y339583D03*
X702448Y546712D03*
Y542712D03*
X699188Y656321D03*
X702086Y678462D03*
X692478Y730641D03*
X702691Y762971D03*
Y756971D03*
X692356Y764614D03*
X691991Y759581D03*
X702677Y780659D03*
Y775159D03*
X692155Y778974D03*
X692221Y773449D03*
X690449Y814406D03*
X708049Y90650D03*
X713361Y90615D03*
X717732Y95236D03*
X717682Y99961D03*
X707799Y95236D03*
X716544Y215478D03*
Y210478D03*
Y207978D03*
Y212978D03*
X718338Y305272D03*
X712692Y356779D03*
X717105Y410964D03*
X717420Y404334D03*
X709781Y442956D03*
X720996Y442856D03*
X711598Y438323D03*
X719051Y458455D03*
X719612Y451108D03*
X710643Y456335D03*
X711764Y445873D03*
X706211Y465874D03*
X711463Y546712D03*
X704364Y618288D03*
X711328Y653821D03*
X705390Y655789D03*
X705776Y678519D03*
X713200Y699676D03*
X716623Y702463D03*
X703600Y702212D03*
X703680Y697094D03*
X715802Y706446D03*
X710196Y707562D03*
X717434Y782500D03*
X710275Y786131D03*
X713222Y793312D03*
Y790812D03*
X712901Y821600D03*
X726596Y74793D03*
Y77393D03*
Y79993D03*
Y85193D03*
Y82593D03*
X726640Y92874D03*
X734921Y98551D03*
X728667Y104249D03*
Y107649D03*
X733233Y147540D03*
X728289Y162368D03*
X725689D03*
X734386Y181426D03*
X734594Y184221D03*
X727000Y213213D03*
Y208213D03*
X733872Y208695D03*
X731072D03*
X733572Y211695D03*
X731072D03*
X727000Y210713D03*
Y215713D03*
X722373Y264180D03*
X719873D03*
X719798Y258880D03*
X737249Y265701D03*
X731567Y267526D03*
X728767D03*
X734067D03*
Y270026D03*
X731567D03*
X728767D03*
X723404Y379657D03*
X721900Y384500D03*
X723440Y391496D03*
X734661Y393633D03*
X731511Y381113D03*
X723440Y398583D03*
X732035Y442606D03*
X722097Y453881D03*
X731952Y446606D03*
X722097Y446595D03*
X732959Y463479D03*
X733430Y467367D03*
X724362Y504731D03*
X722473Y693718D03*
X723656Y705858D03*
X720985Y711658D03*
X725667Y732161D03*
X723177Y728219D03*
X721163Y738981D03*
X733000Y816000D03*
X730880Y828924D03*
X733680Y828977D03*
X732713Y853890D03*
X722600Y869600D03*
X728503Y891692D03*
X736452Y890548D03*
X728692Y886653D03*
X724707Y893143D03*
X719661Y904900D03*
X722789Y927095D03*
X722400Y942500D03*
X725194Y942073D03*
X720271Y931730D03*
X732306Y942682D03*
X728846Y948331D03*
X733798Y950186D03*
X727116Y959326D03*
X732825Y1604100D03*
X736067Y1611892D03*
X729600Y1625165D03*
X732268Y1618260D03*
X751017Y76587D03*
Y72615D03*
X752456Y100625D03*
X745475Y97475D03*
X745406Y106186D03*
X738471Y103783D03*
X737005Y141247D03*
X744472Y143740D03*
X741852Y148277D03*
X735389Y165393D03*
Y162793D03*
Y170493D03*
Y167993D03*
X740392Y181009D03*
X737597Y181366D03*
X745567Y168697D03*
X742894Y172190D03*
X742313Y177616D03*
X746655Y191941D03*
X737211Y184012D03*
X750667Y192300D03*
X751164Y206767D03*
X748664D03*
X738630Y213859D03*
Y211359D03*
X742333Y213132D03*
X749909Y228221D03*
Y231021D03*
X751294Y221708D03*
X748209Y224421D03*
X748794Y221708D03*
X742333Y215632D03*
X750460Y236189D03*
X750401Y248765D03*
X742577Y256303D03*
X747352Y266114D03*
X742336Y265896D03*
X750598Y268195D03*
Y270695D03*
X744825Y281982D03*
X738884Y281716D03*
X741051Y316389D03*
X749444Y393858D03*
X749606Y384410D03*
X752785Y382047D03*
X753086Y403500D03*
X751086Y398583D03*
X749539Y438269D03*
Y440869D03*
Y435669D03*
Y430469D03*
Y433069D03*
X735599Y449961D03*
X739316Y458572D03*
X750393Y451677D03*
Y454177D03*
X741992Y763480D03*
X742000Y768137D03*
X743428Y772418D03*
X741993Y775909D03*
X736000Y864266D03*
X742407Y988452D03*
X743062Y1004460D03*
X749439Y1458777D03*
X740530Y1524113D03*
X747140Y1581335D03*
X749786Y1590517D03*
X738775Y1597866D03*
X737892Y1602340D03*
X749704Y1608631D03*
X744924Y1617709D03*
X743331Y1627871D03*
X741705Y1622015D03*
X738325Y1634485D03*
X762697Y55513D03*
X758922Y68581D03*
X765297Y60513D03*
X758935Y80581D03*
X763065Y88801D03*
X765982Y94351D03*
X769931Y94279D03*
X765425Y85731D03*
X756829Y112083D03*
X761118Y103621D03*
X769609Y124283D03*
X753035Y141247D03*
X757522Y143518D03*
X756622Y152373D03*
X759772Y152562D03*
X765267Y157370D03*
X760637Y172665D03*
X760464Y183834D03*
X760574Y178560D03*
X761450Y186629D03*
X754709Y192490D03*
X759984Y190185D03*
X760754Y200864D03*
X753182Y198671D03*
X753664Y206767D03*
X769383Y208864D03*
X760843Y212455D03*
X760777Y207037D03*
X753794Y221708D03*
X758144Y221642D03*
X765024Y219379D03*
X763653Y224536D03*
X752960Y236189D03*
X755460D03*
X755401Y248765D03*
X752901D03*
X753098Y268195D03*
X755898D03*
X753098Y270695D03*
X755898D03*
X759558Y265897D03*
X762058D03*
X769349Y324518D03*
X759029Y328867D03*
X754805Y339559D03*
X759624Y353961D03*
X756086Y377912D03*
X766344D03*
X755086Y391496D03*
X756086Y386500D03*
X766344Y381912D03*
X756174Y397912D03*
X755086Y409000D03*
X766344Y397912D03*
X752339Y438269D03*
Y433069D03*
Y430469D03*
Y435669D03*
Y440869D03*
X752893Y451677D03*
Y454177D03*
X752097Y460218D03*
Y463618D03*
X755035Y1443524D03*
X765713Y1437365D03*
X760398Y1440276D03*
X755187Y1580821D03*
X759802Y1590864D03*
X763542Y1590186D03*
X768361Y1610083D03*
X762671Y1619367D03*
X756358Y1613767D03*
X768157Y60438D03*
X773838Y86012D03*
Y94374D03*
X768979Y86046D03*
X781144Y116594D03*
X769175D03*
X775118Y110784D03*
X780118D03*
X781144Y119594D03*
X769175D03*
X784678Y125107D03*
X779697Y124663D03*
X774675Y124879D03*
X781041Y138838D03*
X768016Y161306D03*
X769351Y176665D03*
Y168665D03*
Y192665D03*
X769464Y186778D03*
X769383Y204864D03*
X774432Y218085D03*
X777232D03*
X783745Y216970D03*
X781032Y216385D03*
X783745Y221970D03*
X783811Y226320D03*
X783745Y219470D03*
X782379Y244571D03*
X779759Y249108D03*
X771140Y248371D03*
X772165Y314890D03*
X784118Y303962D03*
X771941Y311740D03*
X772162Y332584D03*
X778502Y348015D03*
X772859Y347937D03*
X774419Y353470D03*
X784902Y428653D03*
X775746Y539315D03*
X777708Y553287D03*
X781429Y545017D03*
X778860Y626912D03*
X778205Y622912D03*
X783694Y1410977D03*
X778685Y1416198D03*
X780162Y1412848D03*
X777749Y1431432D03*
X783469Y1424655D03*
X771557Y1446818D03*
X768910Y1437741D03*
X777749Y1435432D03*
Y1439432D03*
X777260Y1446237D03*
X778428Y1455156D03*
X777725Y1450193D03*
X783620Y1460108D03*
X768812Y1453306D03*
X781124Y1583553D03*
X781110Y1595254D03*
X777059Y1608982D03*
X784046Y1600438D03*
X778045Y1619395D03*
X778358Y1627418D03*
X771383Y1616917D03*
X799221Y103411D03*
X799615Y97667D03*
X790761D03*
X795011Y95111D03*
X786417Y102495D03*
X799380Y106561D03*
X786151Y142862D03*
X793292Y143762D03*
X787192Y148717D03*
X796758Y199248D03*
X797240Y195176D03*
X794740D03*
X789740D03*
X792240D03*
X793758Y199248D03*
X794094Y206806D03*
X791594D03*
X789821Y210509D03*
X792321D03*
X793758Y201748D03*
X796758Y202048D03*
X800358Y230117D03*
X795768Y227824D03*
X791513Y230556D03*
X786772Y228646D03*
X796374Y238714D03*
X790498Y242078D03*
X785729Y232971D03*
X795855Y246874D03*
X798075Y244297D03*
X789722Y256394D03*
X786461Y293028D03*
X790280Y287421D03*
X800155Y337368D03*
X800029Y333368D03*
X797141Y350368D03*
X795445Y356950D03*
X789581Y405011D03*
X793893Y409502D03*
X784804Y425371D03*
X794173Y450510D03*
X802136Y448334D03*
X796000Y553101D03*
X788600Y1006923D03*
X799631Y1025440D03*
X795631D03*
X789050Y1026150D03*
X796338Y1138130D03*
X793842Y1143384D03*
X797160Y1146609D03*
X792277Y1173065D03*
X799020Y1175975D03*
X798353Y1172011D03*
X787887Y1174500D03*
X798542Y1188345D03*
X792382Y1191664D03*
X794533Y1195766D03*
X794983Y1334030D03*
Y1331230D03*
X793548Y1397690D03*
X795296Y1416995D03*
X792848Y1414718D03*
X793459Y1429165D03*
X789647Y1427518D03*
X788648Y1422044D03*
X785820Y1425993D03*
X798601Y1431673D03*
X793288Y1450918D03*
X793744Y1437159D03*
X786787Y1433800D03*
X787694Y1442749D03*
X800607Y1440760D03*
X790361Y1447895D03*
X790754Y1441399D03*
X793994Y1441499D03*
X799057Y1449158D03*
X797083Y1467883D03*
X799057Y1456016D03*
X794005Y1464178D03*
X790296Y1463459D03*
X787038Y1460533D03*
X786591Y1452803D03*
X790989Y1455695D03*
X799314Y1475693D03*
X797318Y1471242D03*
X810411Y90650D03*
X815723Y90615D03*
X810161Y95236D03*
X805952Y301675D03*
X817456Y305368D03*
Y313368D03*
X809490Y305368D03*
X809466Y310604D03*
X801097Y325858D03*
X817100Y319600D03*
X809457Y330459D03*
X809490Y325368D03*
Y317368D03*
X809489Y313830D03*
X809490Y321368D03*
Y333368D03*
X816177Y441442D03*
X813456Y441474D03*
X810749Y443045D03*
X815840Y444091D03*
Y456060D03*
X810453Y453330D03*
X810406Y448214D03*
X810756Y471071D03*
Y468571D03*
X814580Y468806D03*
X814828Y472053D03*
X810756Y473571D03*
Y476071D03*
X813902Y730738D03*
X813678Y740979D03*
X813653Y746856D03*
X817584Y764219D03*
X813635Y762000D03*
X818000Y797000D03*
X817845Y817879D03*
X818500Y810135D03*
X813000Y805000D03*
X813548Y814000D03*
X813009Y819734D03*
X815500Y824000D03*
X815863Y830097D03*
X814299Y840877D03*
X813887Y835146D03*
X816037Y845578D03*
X812440Y862306D03*
X814080Y864464D03*
X812575Y880834D03*
X812219Y883586D03*
X817884Y915425D03*
X803673Y1025440D03*
X803453Y1134729D03*
X814835D03*
X806835D03*
X809632Y1142666D03*
X817964Y1157404D03*
X811507Y1157544D03*
X810018Y1167768D03*
X815037D03*
X814160Y1178240D03*
X814170Y1185205D03*
X805212Y1180175D03*
X805519Y1187215D03*
X815455Y1201043D03*
X811485D03*
X807489D03*
X804452Y1199814D03*
X804458Y1193112D03*
X809027Y1219895D03*
X807020Y1217900D03*
X812302Y1223170D03*
X815149Y1226016D03*
X810148Y1374884D03*
X806148Y1383715D03*
Y1375208D03*
X810204Y1401661D03*
X804654Y1404769D03*
X812901Y1432804D03*
X815901D03*
X810059Y1432778D03*
X812104Y1426483D03*
X809986Y1438785D03*
X812986D03*
X815986D03*
X809986Y1441485D03*
X812986D03*
X815986D03*
X812901Y1435504D03*
X815901D03*
X810001D03*
X803057Y1449158D03*
X801057Y1447158D03*
X805569Y1441519D03*
X803057Y1456016D03*
X801057Y1458016D03*
X802684Y1465549D03*
X801354Y1478681D03*
X807576Y1469584D03*
X804919Y1489247D03*
X828958Y79993D03*
Y77393D03*
Y74793D03*
Y85193D03*
Y82593D03*
X829002Y92874D03*
X820094Y95236D03*
X820044Y99961D03*
X831029Y104249D03*
Y107649D03*
X830651Y162368D03*
X828051D03*
X829362Y213213D03*
X818906Y207978D03*
Y212978D03*
Y215478D03*
Y210478D03*
X829362Y208213D03*
Y210713D03*
Y215713D03*
X822235Y264180D03*
X824735D03*
X822160Y258880D03*
X831129Y267526D03*
Y270026D03*
X822477Y309368D03*
X825971Y345101D03*
X829485D03*
X822626Y348066D03*
X818840Y444091D03*
X825103Y430358D03*
Y435558D03*
Y432958D03*
X831378Y433086D03*
Y435686D03*
Y430486D03*
X818840Y456060D03*
X824650Y455034D03*
Y450034D03*
X817328Y472053D03*
X820810Y471243D03*
X817380Y468806D03*
X823544Y475061D03*
Y472561D03*
X820810Y473743D03*
X828918Y480580D03*
X831418D03*
X831057Y484036D03*
X834282Y536085D03*
X828272Y535462D03*
X827291Y533100D03*
X829496Y676793D03*
X829784Y716589D03*
Y705489D03*
X823890Y703415D03*
X823670Y710542D03*
X824387Y726246D03*
X818307Y724144D03*
X821582Y727140D03*
X826484Y747127D03*
X827500Y750000D03*
X819788Y739634D03*
X830484Y738750D03*
X824500Y760500D03*
X830075Y769000D03*
X822151Y752283D03*
X824500Y756000D03*
X817365Y756827D03*
X824500Y778500D03*
Y774000D03*
Y782500D03*
X830075Y787000D03*
X824500Y796500D03*
X824342Y792315D03*
X824500Y800500D03*
X830075Y805000D03*
X824500Y814500D03*
X830075Y823000D03*
X829946Y829788D03*
X825721Y839816D03*
X830014Y833046D03*
X829757Y842672D03*
X822608Y848526D03*
X822916Y852576D03*
X823540Y857956D03*
X831654Y864494D03*
X831583Y853454D03*
X822938Y863298D03*
X826209Y866052D03*
X823234Y870830D03*
X833194Y873561D03*
X827992Y874107D03*
X826070Y893014D03*
X817152Y896380D03*
X817139Y890330D03*
X830063Y898500D03*
X819918Y889365D03*
X823900Y882083D03*
X824804Y898395D03*
X834465Y884538D03*
X829848Y914211D03*
X818031Y907747D03*
X825336Y916774D03*
X831057Y916745D03*
X834751Y922368D03*
X823552Y930700D03*
X829617Y939583D03*
X824414Y939655D03*
X816519Y931147D03*
X824168Y949538D03*
X825670Y964671D03*
X832423Y964669D03*
X828964Y977780D03*
X830356Y1116251D03*
X827856D03*
X825335Y1137129D03*
X819449Y1134534D03*
X819026Y1128137D03*
X825744Y1150087D03*
X823220Y1170767D03*
X818879Y1187310D03*
X823309Y1180235D03*
X823516Y1185238D03*
X819489Y1201039D03*
X823489Y1200969D03*
X823608Y1208993D03*
X819419Y1230265D03*
X817360Y1228226D03*
X816648Y1380758D03*
X824901Y1427404D03*
X827901D03*
X821901D03*
X818901Y1430104D03*
X821901D03*
X830901D03*
X827901D03*
X824901D03*
Y1432804D03*
X827901D03*
X830901D03*
X821901D03*
X818901D03*
X824901Y1435504D03*
X827901D03*
X821901D03*
X818901D03*
X821986Y1441485D03*
X818986D03*
Y1438785D03*
X821986D03*
X826204Y1444689D03*
Y1440689D03*
X826341Y1451236D03*
X826365Y1458974D03*
X826219Y1455244D03*
X837283Y98551D03*
X847837Y97475D03*
X840833Y103783D03*
X847768Y106186D03*
X837751Y165393D03*
Y162793D03*
Y170493D03*
Y167993D03*
X842754Y181009D03*
X839959Y181366D03*
X836748Y181426D03*
X847929Y168697D03*
X844675Y177616D03*
X845256Y172190D03*
X839573Y184012D03*
X836956Y184221D03*
X836234Y208695D03*
X833434D03*
X835934Y211695D03*
X840992Y213859D03*
Y211359D03*
X833434Y211695D03*
X844695Y213132D03*
Y215632D03*
X844939Y256303D03*
X844698Y265896D03*
X839611Y265701D03*
X849714Y266114D03*
X836429Y267526D03*
X833929D03*
Y270026D03*
X836429D03*
X841246Y281716D03*
X847187Y281982D03*
X842240Y324854D03*
X848879Y360849D03*
X845435Y356172D03*
X846098Y408715D03*
X849591Y411388D03*
X842515Y461382D03*
X850732Y469382D03*
X842779Y473076D03*
X842916Y467009D03*
X833293Y490636D03*
Y487836D03*
X833918Y480580D03*
X834215Y484138D03*
X844227Y479882D03*
X842476Y482382D03*
X833269Y506683D03*
X833953Y530621D03*
X848444Y657756D03*
X837272Y663910D03*
X839636Y666533D03*
X842352Y659243D03*
X842640Y662814D03*
X838152Y700215D03*
X845784Y705489D03*
Y716589D03*
X845850Y710969D03*
X845784Y708089D03*
X836078Y709619D03*
X835987Y713745D03*
X838484Y746701D03*
X846484Y738750D03*
X836713Y738751D03*
X842661Y769521D03*
X846000Y772079D03*
X840136Y830903D03*
X836839Y831301D03*
X836894Y824401D03*
X848224Y823502D03*
X835626Y843629D03*
X838189Y843459D03*
Y847490D03*
X835215Y847719D03*
X848384Y843459D03*
X846239Y847490D03*
X835553Y835119D03*
X848384Y839459D03*
Y835459D03*
X838194Y836962D03*
X848739Y847459D03*
X837183Y855459D03*
X840234Y851459D03*
X847138Y859459D03*
X839530Y859408D03*
X848384Y863459D03*
X846336Y855459D03*
X845820Y863413D03*
X848384Y851459D03*
X843574Y859423D03*
X837434Y851459D03*
X833327Y855560D03*
X837383Y879530D03*
X837396Y871459D03*
X840234Y875459D03*
X836999Y867413D03*
X845876Y879459D03*
X848384Y867459D03*
X845820Y867413D03*
X848384Y879459D03*
Y871459D03*
Y875459D03*
X837290Y887490D03*
X842827Y895443D03*
X835346Y891346D03*
X848322Y888421D03*
X848792Y896472D03*
X836066Y894955D03*
X847098Y891213D03*
X845633Y883492D03*
X845964Y887490D03*
X837276Y883459D03*
X848200Y883400D03*
X841329Y926602D03*
X841274Y914060D03*
X843315Y916612D03*
X836909Y916618D03*
Y914018D03*
X833683Y939579D03*
X836243D03*
X833683Y949105D03*
X836243D03*
X842856Y949146D03*
X836423Y964669D03*
X835431Y977775D03*
X840935Y1011499D03*
X844058Y1011738D03*
X848045Y1019310D03*
X848070Y1022190D03*
X839744Y1444959D03*
Y1440859D03*
Y1448959D03*
X836704Y1448849D03*
Y1440849D03*
X836744Y1444849D03*
X845306Y1438269D03*
X846844Y1454334D03*
X837685Y1453196D03*
X839744Y1457959D03*
X835474Y1457397D03*
X846044Y1451459D03*
X839744Y1461959D03*
X834475Y1460059D03*
X865059Y55513D03*
X861284Y68581D03*
X861297Y80581D03*
X853379Y76587D03*
Y72615D03*
X854818Y100625D03*
X859191Y112083D03*
X863480Y103621D03*
X862826Y183834D03*
X862999Y172665D03*
X862936Y178560D03*
X849017Y191941D03*
X863812Y186629D03*
X857071Y192490D03*
X862346Y190185D03*
X863116Y200864D03*
X853029Y192300D03*
X853526Y206767D03*
X856026D03*
X851026D03*
X863205Y212455D03*
X863139Y207037D03*
X860506Y221642D03*
X852271Y228221D03*
Y231021D03*
X853656Y221708D03*
X856156D03*
X850571Y224421D03*
X851156Y221708D03*
X866015Y224536D03*
X852822Y236189D03*
X855322D03*
X857822D03*
X852763Y248765D03*
X855263D03*
X857763D03*
X852960Y268195D03*
Y270695D03*
X855460D03*
X864420Y265897D03*
X858260Y268195D03*
Y270695D03*
X861920Y265897D03*
X855460Y268195D03*
X863430Y309368D03*
Y316970D03*
X863114Y324505D03*
X863040Y330140D03*
X861770Y343006D03*
X852569Y356712D03*
X856069Y356426D03*
X854086Y374500D03*
X858586D03*
X863086D03*
X860586Y383000D03*
X861235Y394000D03*
X854086Y392999D03*
X864086Y384000D03*
X855017Y411969D03*
X861413Y417071D03*
X858827Y419896D03*
X858410Y413890D03*
X858767Y416685D03*
X861622Y419688D03*
X862882Y458991D03*
X854882D03*
X862882Y461791D03*
X854882D03*
X850748Y465382D03*
X861468Y483303D03*
Y487303D03*
X858169Y495032D03*
X853989Y630453D03*
Y632953D03*
X861663Y646653D03*
X855300Y646819D03*
X853982Y657506D03*
X859441Y678015D03*
X849680Y694789D03*
X858186Y701170D03*
X855646Y692710D03*
X864029Y688970D03*
X867455Y710611D03*
X858002Y707244D03*
X857986Y722670D03*
X854484Y746701D03*
X859199Y744517D03*
X854484Y738633D03*
X859000Y756000D03*
X849500Y758500D03*
Y763500D03*
X863443Y753254D03*
X859000Y764000D03*
Y760000D03*
Y774000D03*
X849500Y776500D03*
Y781500D03*
X861425Y770500D03*
X859000Y781000D03*
Y778000D03*
X853282Y789887D03*
X857632Y789385D03*
X859000Y792000D03*
X849500Y794500D03*
Y799500D03*
X861425Y788500D03*
X859000Y800000D03*
Y796000D03*
X861425Y806500D03*
X859000Y810000D03*
X849500Y812500D03*
X859000Y814000D03*
X850496Y831469D03*
X861425Y824500D03*
X849500Y817500D03*
X859000Y818000D03*
X851184Y839459D03*
Y835459D03*
X859165Y848728D03*
X851239Y847459D03*
X851184Y843459D03*
Y863459D03*
X862114Y859479D03*
X851184Y851459D03*
X859603Y863570D03*
X859461Y859459D03*
X851184Y867459D03*
Y871459D03*
Y875459D03*
X859234Y879600D03*
X859463Y866125D03*
X851184Y879459D03*
X849267Y892567D03*
X859614Y883800D03*
Y887846D03*
X850900Y888359D03*
X850800Y883500D03*
X858988Y898307D03*
X855524Y898505D03*
X864253Y918042D03*
X856628D03*
X849600Y918028D03*
X849205Y924129D03*
X867096Y935963D03*
X858601Y934505D03*
X853030Y934690D03*
X851925Y951350D03*
X850686Y1006923D03*
X853449Y1007048D03*
X863334Y1009393D03*
X861047Y1018909D03*
X860887Y1023208D03*
Y1026762D03*
X863956Y1020763D03*
X863689Y1024974D03*
X863944Y1432359D03*
Y1429359D03*
X860944Y1432359D03*
X857944Y1429359D03*
X860944D03*
Y1426359D03*
X857944D03*
X863944D03*
X857944Y1432359D03*
X863944Y1435359D03*
Y1441359D03*
Y1438359D03*
X860944Y1441359D03*
X857944Y1435359D03*
X860944D03*
X857944Y1441359D03*
Y1438359D03*
X860944D03*
X850544Y1447559D03*
X853514Y1457510D03*
X850644Y1457359D03*
X870519Y60438D03*
X867659Y60513D03*
X876200Y86012D03*
X867787Y85731D03*
X865427Y88801D03*
X876200Y94374D03*
X872293Y94279D03*
X868344Y94351D03*
X871341Y86046D03*
X871713Y168665D03*
Y176665D03*
Y196665D03*
Y192665D03*
X871826Y186778D03*
X871745Y204864D03*
Y208864D03*
X867386Y219379D03*
X883118Y262687D03*
X876622Y293721D03*
X872050Y302644D03*
X873262Y300030D03*
X869924Y305368D03*
X879112Y302369D03*
X877977Y305368D03*
Y309368D03*
X869924Y313368D03*
X877977D03*
Y325368D03*
Y317368D03*
Y321368D03*
X869924D03*
Y328722D03*
X874005Y344917D03*
X870413Y342791D03*
X869924Y333722D03*
X877977Y333368D03*
Y329368D03*
X872158Y359962D03*
X868086Y373750D03*
X876736Y383125D03*
X877909Y391731D03*
X880736Y383125D03*
X882925Y391099D03*
X872736Y391754D03*
X867586Y393000D03*
Y385000D03*
X869342Y407627D03*
X868586Y398500D03*
X877253Y420380D03*
X876917Y415322D03*
X879417D03*
X881190Y411619D03*
X878690D03*
X874253Y422880D03*
Y420080D03*
X877253Y422880D03*
X881271Y426952D03*
X878771D03*
X873536Y437408D03*
X876036D03*
X881036D03*
X878536D03*
X873771Y426952D03*
X876271D03*
X870882Y458991D03*
X880910Y454634D03*
Y457434D03*
Y460234D03*
X870882Y461791D03*
X869454Y479303D03*
X869954Y487303D03*
X882954Y486256D03*
X882195Y539204D03*
X867093Y554703D03*
X866938Y549771D03*
X878382Y554942D03*
X874649Y545296D03*
X876949Y571419D03*
X867093Y586828D03*
Y574703D03*
X881476Y588202D03*
X881131Y577349D03*
X875290Y578703D03*
X876351Y605023D03*
Y608523D03*
X879135Y632552D03*
X872862Y666859D03*
X878881Y667156D03*
X876286Y690970D03*
X868919Y700894D03*
X876286Y694970D03*
Y698970D03*
X881157Y749148D03*
X874142Y748914D03*
X879875Y753612D03*
X873728Y752692D03*
X875473Y742056D03*
X878670Y742841D03*
X869325Y761259D03*
X870017Y757313D03*
X867000Y774000D03*
X870000Y780000D03*
X879887Y784719D03*
X880040Y792851D03*
X867000Y792000D03*
X876402Y797415D03*
X874925Y800746D03*
X870035Y801032D03*
X867000Y810000D03*
X879916Y808965D03*
X877407Y828017D03*
X877818Y824214D03*
X876475Y830372D03*
X871600Y898584D03*
X872628Y918042D03*
X876628Y915242D03*
X880628Y918042D03*
X876628D03*
X872126Y934766D03*
X865830Y961600D03*
X870209Y949384D03*
X865973Y978187D03*
X874066Y977928D03*
X875391Y993796D03*
X872183Y993980D03*
X878976Y994020D03*
X871069Y1023114D03*
X878927Y1022387D03*
X878783Y1018751D03*
X872845Y1018988D03*
X866906Y1018751D03*
X866887Y1023208D03*
X875887D03*
X878887Y1026762D03*
X872887D03*
X866887D03*
X869741Y1025895D03*
X873824Y1071604D03*
X871224D03*
X876424D03*
Y1074104D03*
X871224D03*
X873824D03*
X868624Y1071604D03*
Y1074104D03*
X870057Y1091604D03*
X875257D03*
Y1089104D03*
X870057D03*
X872657D03*
X880115Y1084666D03*
X867457Y1091604D03*
Y1089104D03*
X872657Y1091604D03*
X875375Y1107647D03*
X872675D03*
X870075D03*
X867475D03*
X871364Y1120636D03*
X873964D03*
X876564D03*
X879264D03*
X875376Y1110175D03*
X872676D03*
X870076D03*
X867476D03*
X871364Y1139336D03*
X868664D03*
X879264Y1130336D03*
X876564D03*
X873964D03*
X871364D03*
X870522Y1148080D03*
X868022D03*
X875321Y1207654D03*
X872600Y1300833D03*
Y1298333D03*
X872944Y1432359D03*
Y1429359D03*
Y1426359D03*
X869944Y1432359D03*
Y1429359D03*
Y1426359D03*
X866944Y1432359D03*
Y1429359D03*
Y1426359D03*
X872944Y1435359D03*
Y1441359D03*
Y1438359D03*
X869944Y1435359D03*
X866944D03*
X869944Y1441359D03*
Y1438359D03*
X866944Y1441359D03*
Y1438359D03*
X881244Y1448859D03*
Y1440859D03*
X878244Y1451605D03*
X881244Y1464859D03*
Y1453059D03*
Y1456859D03*
X875744Y1453573D03*
X881244Y1476859D03*
X883233Y147540D03*
X887005Y141247D03*
X894472Y143740D03*
X891852Y148277D03*
X893284Y233339D03*
Y236739D03*
X895064Y250186D03*
X891383Y243203D03*
X896034Y243307D03*
X885884Y255118D03*
X897004Y257480D03*
X892484Y260860D03*
X887148Y249670D03*
X896953Y272012D03*
X886496Y268968D03*
X895140Y265236D03*
X886059Y284644D03*
X885918Y289500D03*
X885989Y309368D03*
Y305368D03*
Y317368D03*
X885953Y325368D03*
X885989Y313368D03*
X885953Y321368D03*
Y329368D03*
Y333368D03*
X896592Y358369D03*
Y354369D03*
X888812Y357372D03*
X883552Y357276D03*
X896592Y374369D03*
X891251Y387484D03*
X890553Y392038D03*
X887266Y400158D03*
Y405158D03*
Y402658D03*
X896579Y404043D03*
X893779D03*
X889979Y405743D03*
X890903Y454634D03*
Y457434D03*
Y460234D03*
X891454Y486303D03*
X892931Y534093D03*
X885931D03*
X891449Y547363D03*
X893949D03*
X886549Y553963D03*
X885556Y543664D03*
X887417Y566713D03*
X891673Y600049D03*
X891933Y618143D03*
X895933Y609696D03*
X883309Y666608D03*
X892461Y666671D03*
X886304Y666650D03*
X884903Y696678D03*
X884911Y690279D03*
X886836Y715970D03*
X893241Y704656D03*
X883686Y729778D03*
X889525Y722060D03*
X882098Y741565D03*
X884976Y740891D03*
X884463Y744757D03*
X881637Y744154D03*
X883126Y766124D03*
X883413Y759855D03*
X892040Y784511D03*
X889763Y788159D03*
X898737Y792289D03*
X889516Y792851D03*
X891916Y799605D03*
X884002Y797616D03*
X887916Y800815D03*
X895916Y808965D03*
X883916D03*
X887916D03*
X895829Y800660D03*
X883916Y800815D03*
X890326Y828548D03*
X895050D03*
X889178Y905619D03*
X884628Y915242D03*
Y918042D03*
X896553D03*
X892628Y915242D03*
X888628D03*
Y918042D03*
X882763Y933472D03*
X891367Y941126D03*
X888400Y994579D03*
X894660Y994330D03*
X891343Y994378D03*
X885099Y1021685D03*
X881887Y1023208D03*
X888743Y1019931D03*
X895394Y1026985D03*
X893147Y1020025D03*
X893887Y1023208D03*
X887887D03*
X890887Y1026762D03*
X884887D03*
X882779Y1074104D03*
Y1071604D03*
X887979Y1074104D03*
X885379D03*
X890579D03*
Y1071604D03*
X885379D03*
X887979D03*
X882615Y1084666D03*
X887862Y1088067D03*
X894004Y1081231D03*
X892856Y1102760D03*
X894249Y1114103D03*
X891549D03*
X888949D03*
X886349D03*
Y1123803D03*
X888949D03*
X891549D03*
X894249D03*
X895275Y1132870D03*
X892575D03*
X895547Y1145169D03*
X894713Y1210419D03*
X898878Y1214182D03*
X899286Y1219469D03*
X892532Y1220112D03*
X897169Y1225259D03*
X886888Y1263058D03*
X889388D03*
X891888D03*
X889388Y1260558D03*
X886888D03*
X891888D03*
X886926Y1298712D03*
X889729Y1295516D03*
X891107Y1314305D03*
X887342Y1314990D03*
X889244Y1444859D03*
X892244Y1449636D03*
Y1440859D03*
X889944Y1457959D03*
X889244Y1460859D03*
X895244Y1457510D03*
X889336Y1452554D03*
X893919Y1462132D03*
X889244Y1472859D03*
Y1468859D03*
X903035Y141247D03*
X907522Y143518D03*
X906622Y152373D03*
X909772Y152562D03*
X899573Y158195D03*
X910977Y243307D03*
Y248032D03*
Y262205D03*
X898048Y269387D03*
X913057Y311046D03*
X915653Y307438D03*
X899352Y308560D03*
Y311960D03*
X909298Y302347D03*
X905898D03*
X898533Y334498D03*
X908521Y356708D03*
X908625Y359317D03*
X905483Y355262D03*
X905000Y362158D03*
X898869Y351114D03*
X906161Y367191D03*
X913288Y372752D03*
X910646Y376084D03*
X906344Y372524D03*
X911072Y386992D03*
X897736Y383125D03*
X901747Y398492D03*
Y403492D03*
Y400992D03*
X910250Y457262D03*
Y454462D03*
X907450D03*
Y457262D03*
X910250Y451662D03*
X907450D03*
X910250Y460062D03*
X907450D03*
X910236Y465272D03*
X910759Y475511D03*
X899931Y534093D03*
X899530Y530753D03*
X914296Y558143D03*
X913728Y550495D03*
X899407Y560019D03*
X908846Y560124D03*
X910789Y598726D03*
X898207Y599891D03*
X900676Y621536D03*
X904076D03*
X909508Y621616D03*
X912908D03*
X900753Y656925D03*
X912462Y683770D03*
X909265Y677795D03*
X912462Y687770D03*
X906886Y702285D03*
X902236Y689332D03*
Y694332D03*
X908699Y709387D03*
X913247Y714204D03*
X902841Y703665D03*
X910836Y721570D03*
X913858Y721289D03*
X907866Y795572D03*
X911028Y796598D03*
X909785Y810778D03*
X903916Y810809D03*
X913716Y811954D03*
X899916Y808965D03*
X902641Y800748D03*
X907884Y829866D03*
X908920Y905630D03*
X900628Y918042D03*
X912628Y915242D03*
X908628Y918042D03*
X900628Y915242D03*
X912628Y918042D03*
X904838D03*
X908628Y915242D03*
X900983Y940895D03*
X903759Y951358D03*
X909811Y962400D03*
X913005Y969605D03*
X912690Y994350D03*
X897825Y994413D03*
X909166Y994188D03*
X897717Y1019915D03*
X899887Y1023208D03*
Y1026762D03*
X908422Y1023103D03*
X908856Y1017677D03*
X902389Y1081764D03*
X908799Y1093659D03*
Y1088659D03*
X908278Y1083484D03*
X908799Y1096659D03*
Y1100659D03*
X902353Y1104333D03*
X898278Y1136426D03*
X898047Y1145169D03*
X903959Y1207823D03*
X906784Y1216607D03*
X913784Y1221057D03*
X910633Y1222799D03*
X906309Y1226647D03*
X909077Y1232724D03*
X899699Y1283872D03*
X910788Y1299456D03*
X906506Y1299188D03*
X902908Y1299828D03*
X911117Y1314130D03*
X902875Y1309301D03*
X905740Y1309264D03*
X908700Y1316300D03*
X911135Y1345560D03*
X904177Y1359955D03*
X899944Y1432359D03*
X908944Y1426359D03*
Y1429359D03*
Y1432359D03*
X911944Y1426359D03*
Y1429359D03*
Y1432359D03*
X905944Y1426359D03*
X899944D03*
X902944D03*
Y1429359D03*
X899944D03*
X902944Y1432359D03*
X905944Y1429359D03*
Y1432359D03*
X902944Y1438359D03*
X899944D03*
Y1441359D03*
X902944Y1435359D03*
X899944D03*
X908944Y1438359D03*
Y1441359D03*
X911944Y1438359D03*
Y1441359D03*
X902944D03*
X905944Y1438359D03*
Y1441359D03*
X908944Y1435359D03*
X911944D03*
X905944D03*
X919175Y116594D03*
X930118Y110784D03*
X925118D03*
X919175Y119594D03*
X924675Y124879D03*
X929697Y124663D03*
X919609Y124283D03*
X931041Y138838D03*
X918016Y161306D03*
X915267Y157370D03*
X916453Y167975D03*
X927898Y203256D03*
X925098D03*
X919577Y240945D03*
Y250394D03*
Y271654D03*
X919616Y268462D03*
X919577Y264567D03*
X923732Y304585D03*
X917882Y328216D03*
Y324816D03*
X915954Y344150D03*
X916229Y336333D03*
X919354Y344150D03*
X919629Y336333D03*
X927964Y344041D03*
X924564D03*
X923311Y349959D03*
X929943Y372600D03*
X921343Y376888D03*
X916330Y377748D03*
X929947Y376821D03*
X915072Y386992D03*
X914323Y398551D03*
Y403551D03*
Y401051D03*
X927563Y424445D03*
X924763D03*
X921963D03*
X927280Y436716D03*
X921680D03*
X924480D03*
X917541Y441280D03*
Y443780D03*
X927766Y456442D03*
X927596Y447453D03*
X921973Y469328D03*
X927401Y469059D03*
X916593Y469140D03*
X928999Y477948D03*
X920999D03*
X924999D03*
X917811Y544325D03*
X923453Y569578D03*
X923642Y561578D03*
X919080Y587640D03*
X921507Y578791D03*
X919038Y579378D03*
X923599Y581578D03*
X921217Y589216D03*
X913998Y597103D03*
X925949Y612363D03*
Y608863D03*
X922626Y633772D03*
X915800Y629700D03*
X918300D03*
X929690Y666593D03*
X920090Y666714D03*
X928353Y686342D03*
X928704Y680261D03*
X921061Y715386D03*
X926961Y723797D03*
X914202Y797460D03*
X923872Y798271D03*
X922352Y800809D03*
X917803Y811365D03*
X927916Y800909D03*
X929790Y828603D03*
X927916Y817015D03*
X925228Y816934D03*
X929181Y895029D03*
X921451Y903800D03*
X920628Y918042D03*
X916628D03*
X924628D03*
X928628D03*
X924628Y915242D03*
X920628D03*
X928628D03*
X916628D03*
X914193Y945318D03*
X928227Y951125D03*
X921364Y951251D03*
X918265Y969745D03*
X923289Y965780D03*
X926796Y966297D03*
X929741Y967006D03*
X916932Y994405D03*
X924956Y994321D03*
X924864Y1026762D03*
Y1023208D03*
X925024Y1018909D03*
X927861Y1024768D03*
X916749Y1084659D03*
X916992Y1076659D03*
X916749Y1092664D03*
X916875Y1098643D03*
X916749Y1104659D03*
X914637Y1210568D03*
Y1214838D03*
X930754Y1310564D03*
X924650Y1327819D03*
Y1324419D03*
X914033Y1345613D03*
X927193Y1361547D03*
X931159Y1379427D03*
X920360Y1387039D03*
X920255Y1383264D03*
X931199Y1371951D03*
X931159Y1390827D03*
Y1406027D03*
X914944Y1426359D03*
Y1429359D03*
Y1432359D03*
Y1438359D03*
Y1441359D03*
Y1435359D03*
X921498Y1446692D03*
X925697Y1460109D03*
X917744Y1453573D03*
X920244Y1451605D03*
X919285Y1456226D03*
X924803Y1474743D03*
X925435Y1478114D03*
X940761Y97667D03*
X945011Y95111D03*
X931144Y116594D03*
X936417Y102495D03*
X931144Y119594D03*
X934678Y125107D03*
X936151Y142862D03*
X943292Y143762D03*
X937192Y148717D03*
X945406Y180347D03*
X940406D03*
X942906D03*
X947424Y184419D03*
X944424Y186919D03*
X944760Y191977D03*
X942260D03*
X940487Y195680D03*
X942987D03*
X944424Y184419D03*
X934411Y202141D03*
X931698Y201556D03*
X934411Y207141D03*
X934477Y211491D03*
X934411Y204641D03*
X946234Y213390D03*
X942179Y215727D03*
X937438Y213817D03*
X936395Y218142D03*
X933403Y245507D03*
X936962Y249807D03*
X944248Y239844D03*
X945018Y276051D03*
X943183Y281652D03*
X930727Y302571D03*
X937000Y312284D03*
Y315684D03*
X940997Y331912D03*
Y335312D03*
X934128Y355168D03*
X934464Y358618D03*
X944238Y360828D03*
X934047Y369160D03*
X936175Y364823D03*
X931072Y386992D03*
X941872Y440942D03*
X933424Y458455D03*
X933161Y451442D03*
X933404Y463462D03*
X933412Y468942D03*
X936653Y526836D03*
X944351Y534211D03*
X948532Y541135D03*
X939992Y527726D03*
Y548726D03*
Y544726D03*
X948598Y546553D03*
X948621Y552726D03*
X931627Y557641D03*
Y569578D03*
Y581578D03*
Y577578D03*
Y573578D03*
X933725Y585936D03*
X933741Y598087D03*
Y594687D03*
X933725Y589336D03*
X944296Y611071D03*
X941859Y621311D03*
Y629311D03*
X943181Y632536D03*
X945434Y634325D03*
X941859Y625311D03*
X946128Y666522D03*
X935281Y680945D03*
X936026Y727450D03*
X933974Y719371D03*
X942676Y789286D03*
X933201Y798297D03*
X946970Y786366D03*
X944916Y808965D03*
X938357Y808856D03*
X931916Y817015D03*
X942858Y819430D03*
X945736Y819397D03*
X935124Y831382D03*
X940100Y830700D03*
X935262Y825135D03*
X932418D03*
X940716Y840074D03*
X944297Y839975D03*
X933021Y840893D03*
X933054Y843804D03*
X937200Y841000D03*
X936450Y858327D03*
X937551Y860801D03*
X932770Y878233D03*
X935765Y878317D03*
X934928Y871727D03*
X932319Y871626D03*
X938729Y874396D03*
X932300Y890200D03*
X942194Y891216D03*
X930800Y904840D03*
X941592Y900908D03*
X936628Y915242D03*
X940628D03*
X932628D03*
X936628Y918042D03*
X932628D03*
X936371Y951484D03*
X940716Y951733D03*
X946363Y951179D03*
X935255Y962725D03*
X945671Y982191D03*
X940015Y1020176D03*
X934911Y1023579D03*
X945864Y1023208D03*
X930864Y1026762D03*
X936864D03*
X942864D03*
X939864Y1023208D03*
X930864D03*
X930883Y1018751D03*
X936822Y1018988D03*
X942760Y1018751D03*
X943093Y1021769D03*
X932289Y1074182D03*
Y1071682D03*
X937489Y1074182D03*
X934889D03*
X940089D03*
Y1071682D03*
X934889D03*
X937489D03*
X944092Y1084666D03*
X931628Y1091409D03*
Y1088909D03*
X936828Y1091409D03*
X934228D03*
X939428D03*
Y1088909D03*
X934228D03*
X936828D03*
X943241Y1120636D03*
X940541D03*
X937941D03*
X935341D03*
X937941Y1130336D03*
X940541D03*
X943241D03*
X932641Y1139336D03*
X935341Y1130336D03*
Y1139336D03*
X934500Y1147708D03*
X932000D03*
X939298Y1207654D03*
X943891Y1306608D03*
X944207Y1320739D03*
X947308Y1325035D03*
X931137Y1375878D03*
X931159Y1383227D03*
X939559Y1398427D03*
X931159Y1394627D03*
Y1387027D03*
Y1398427D03*
Y1402227D03*
X939559D03*
X944235Y1406262D03*
X943725Y1430744D03*
Y1427744D03*
X934725Y1430744D03*
X940725Y1427744D03*
Y1430744D03*
X934725Y1427744D03*
X937725D03*
Y1430744D03*
X943725Y1433744D03*
Y1439744D03*
Y1436744D03*
X940725Y1433744D03*
Y1439744D03*
Y1436744D03*
X934725Y1433744D03*
X937725D03*
X934725Y1439744D03*
X937725D03*
X934725Y1436744D03*
X937725D03*
X937671Y1492139D03*
Y1488139D03*
X949221Y103411D03*
X949615Y97667D03*
X960411Y90650D03*
X960161Y95236D03*
X949380Y106561D03*
X947906Y180347D03*
X947424Y187219D03*
X950177Y215730D03*
X947040Y223885D03*
X948741Y229468D03*
X948785Y242464D03*
X951278Y250583D03*
X946482Y255940D03*
X949974Y291554D03*
X947733Y319680D03*
X950953Y317947D03*
X960376Y392807D03*
X962769Y451419D03*
X959816Y472905D03*
X955816Y473419D03*
Y464919D03*
X963816Y464419D03*
X962563Y485128D03*
X954182Y481467D03*
X958124Y492354D03*
X958736Y482165D03*
X958974Y504825D03*
X956474D03*
X953974D03*
X949823Y491982D03*
X959600Y496486D03*
X949823Y495982D03*
X957977Y500202D03*
X958915Y517401D03*
X956415D03*
X953915D03*
X959466Y522569D03*
Y525369D03*
X958081Y531882D03*
X955581D03*
X961166Y529169D03*
X952531Y531948D03*
X960581Y531882D03*
X948905Y534909D03*
X958016Y555194D03*
X960816D03*
X958016Y563194D03*
X960816D03*
Y571194D03*
X958016D03*
X959573Y581222D03*
X962373D03*
X959573Y591215D03*
X962373D03*
X962545Y607762D03*
X959745D03*
Y610562D03*
X962545D03*
X950479Y622285D03*
X954535Y610548D03*
X950667Y616905D03*
X963365Y628078D03*
X961352Y633736D03*
X950865Y633724D03*
X950748Y627713D03*
X956345Y633716D03*
X949137Y666660D03*
X954526Y666671D03*
X947556Y699550D03*
X956023Y706907D03*
X951151Y730111D03*
X963869Y725057D03*
X955950Y734178D03*
X957763Y725336D03*
X959950Y734178D03*
X957579Y744168D03*
X953837Y763025D03*
X950699Y779711D03*
X956017Y770300D03*
X957500Y780800D03*
X955076Y784861D03*
X950475Y789361D03*
X955225Y788984D03*
X949609Y796051D03*
X957487Y798553D03*
X951461Y812223D03*
X951791Y808121D03*
X957379Y826586D03*
X954760Y826734D03*
X951708Y818894D03*
X955712Y833988D03*
X956239Y829577D03*
X960100Y846665D03*
X954700Y837700D03*
X961175Y838525D03*
X955343Y866850D03*
X955850Y862902D03*
X957900Y856300D03*
X950300Y877800D03*
X953240Y876834D03*
X954567Y927654D03*
X964280Y927777D03*
X958567Y927654D03*
X947029Y915242D03*
X959545Y918306D03*
X951863Y936168D03*
X957235Y936398D03*
X962329Y936229D03*
X957671Y977921D03*
X949671D03*
X961671Y991564D03*
X953671D03*
X949671D03*
X953671Y982191D03*
X954937Y1021998D03*
X948864Y1026762D03*
X954864D03*
X951864Y1023208D03*
X957864D03*
X957678Y1018555D03*
X961208Y1018592D03*
X960636Y1021917D03*
X959371Y1026985D03*
X948975Y1021325D03*
X951956Y1071604D03*
X949356D03*
X954556D03*
Y1074104D03*
X949356D03*
X951956D03*
X946756Y1071604D03*
Y1074104D03*
X946592Y1084666D03*
X957981Y1081231D03*
X951839Y1088067D03*
X956833Y1102760D03*
X950326Y1114103D03*
Y1123803D03*
X952926D03*
X955526D03*
Y1114103D03*
X958226D03*
X952926D03*
X958226Y1123803D03*
X956552Y1132870D03*
X959252D03*
X962255Y1136426D03*
X962024Y1145169D03*
X959524D03*
X958690Y1210419D03*
X963263Y1219469D03*
X962855Y1214182D03*
X956509Y1220112D03*
X961146Y1225259D03*
X950865Y1263058D03*
X953365D03*
X955865D03*
X953365Y1260558D03*
X950865D03*
X955865D03*
X948259Y1295965D03*
X948832Y1371654D03*
X951832D03*
X952561Y1383465D03*
X952417Y1379528D03*
X949469D03*
X949385Y1375591D03*
X952385D03*
X952514Y1391339D03*
X952395Y1395276D03*
X952716Y1387402D03*
X952180Y1407087D03*
X950239Y1409555D03*
X948235Y1406262D03*
X946725Y1427744D03*
Y1430744D03*
X949725D03*
Y1427744D03*
X960883Y1427997D03*
Y1430997D03*
X946725Y1433744D03*
X949725D03*
X946725Y1439744D03*
X949725D03*
X946725Y1436744D03*
X949725D03*
X960883Y1433997D03*
Y1436997D03*
Y1439997D03*
X952695Y1444139D03*
X979002Y92874D03*
X965723Y90615D03*
X970094Y95236D03*
X970044Y99961D03*
X978051Y162368D03*
X968906Y207978D03*
Y212978D03*
Y215478D03*
Y210478D03*
X970865Y264068D03*
X973365D03*
X972160Y258880D03*
X977150Y331972D03*
Y338972D03*
X975631Y343112D03*
Y346612D03*
X971721Y407762D03*
X968348Y402369D03*
X971826Y430187D03*
X966694Y427599D03*
X968462Y429368D03*
X970840Y457339D03*
X968340D03*
X962816Y442919D03*
X972030Y446071D03*
X979910Y445603D03*
X970840Y459839D03*
Y462339D03*
X968340D03*
Y459839D03*
X963816Y472905D03*
X976397Y473045D03*
X972397Y465004D03*
X977327Y462371D03*
X965412Y485138D03*
X969297Y478625D03*
Y475825D03*
X970997Y482425D03*
X970412Y485138D03*
X967912D03*
X976873Y491214D03*
Y493714D03*
X970745Y539731D03*
X967042Y537658D03*
X970745Y542231D03*
X978303Y541895D03*
X975803D03*
X967042Y540458D03*
X975503Y544895D03*
X978303D03*
X978581Y582747D03*
X965173Y581222D03*
X978032Y590801D03*
X965173Y591215D03*
X977857Y597130D03*
X976027Y620653D03*
Y617853D03*
X968145Y610562D03*
X965345Y607762D03*
Y610562D03*
X968145Y607762D03*
X977857Y605443D03*
X973857D03*
X972354Y627908D03*
X968365Y633473D03*
X978865Y642184D03*
X966797Y667653D03*
X970197D03*
X965774Y706907D03*
X973712Y722064D03*
X968589Y722434D03*
X970839Y729923D03*
X965042Y722234D03*
X971081Y722637D03*
X978352Y730766D03*
X963950Y734178D03*
X973450Y747280D03*
X965983Y763567D03*
X966127Y776382D03*
X968094Y799792D03*
X976186Y789819D03*
X967562Y802982D03*
X978978Y817618D03*
X978214Y821224D03*
X967337Y828901D03*
X970040Y842903D03*
X969309Y839334D03*
X974437Y849140D03*
X973510Y834991D03*
X967842Y864801D03*
X970299Y853773D03*
X978880Y869552D03*
X967510Y868971D03*
X966813Y904556D03*
X973988Y910038D03*
X968507Y937615D03*
X971443Y938828D03*
X965671Y991564D03*
Y982191D03*
X963864Y1026762D03*
Y1023208D03*
X966366Y1081764D03*
X972776Y1093659D03*
X972255Y1083484D03*
X972776Y1088659D03*
Y1096659D03*
X966330Y1104333D03*
X972776Y1100659D03*
X967936Y1207823D03*
X978614Y1210568D03*
X970761Y1216607D03*
X978614Y1214838D03*
X978169Y1221268D03*
X974985Y1290950D03*
X979996Y1386100D03*
X963883Y1430997D03*
Y1427997D03*
X966883Y1430997D03*
Y1427997D03*
X969883D03*
Y1430997D03*
X975883Y1427997D03*
Y1430997D03*
X972883D03*
Y1427997D03*
X963883Y1433997D03*
X966883D03*
X969883D03*
X963883Y1436997D03*
Y1439997D03*
X966883Y1436997D03*
Y1439997D03*
X969883Y1436997D03*
Y1439997D03*
X975883Y1433997D03*
X972883D03*
X975883Y1436997D03*
X972883D03*
X975883Y1439997D03*
X972883D03*
X977547Y1546081D03*
X974547D03*
X971547D03*
X978958Y85193D03*
Y82593D03*
Y77393D03*
Y74793D03*
Y79993D03*
X987283Y98551D03*
X990833Y103783D03*
X981029Y104249D03*
Y107649D03*
X985595Y147540D03*
X989367Y141247D03*
X996834Y143740D03*
X994214Y148277D03*
X980651Y162368D03*
X987751Y162793D03*
Y165393D03*
Y167993D03*
Y170493D03*
X995256Y172190D03*
X994675Y177616D03*
X989959Y181366D03*
X986748Y181426D03*
X992754Y181009D03*
X986956Y184221D03*
X989573Y184012D03*
X994695Y213132D03*
X979362Y208213D03*
Y210713D03*
Y213213D03*
X986234Y208695D03*
X983434D03*
X985934Y211695D03*
X990992Y213859D03*
Y211359D03*
X983434Y211695D03*
X979362Y215713D03*
X994695Y215632D03*
X994939Y256303D03*
X989611Y265701D03*
X994698Y265896D03*
X986429Y270026D03*
X983929D03*
X981129D03*
X983929Y267526D03*
X986429D03*
X981129D03*
X991246Y281716D03*
X997187Y281982D03*
X987517Y314092D03*
X993552Y318175D03*
X990420Y340454D03*
Y337954D03*
X989630Y343862D03*
X983717Y341665D03*
X983956Y346652D03*
X993026Y353813D03*
X981719Y352217D03*
X988631Y349496D03*
X980045Y366559D03*
X986373Y370467D03*
X991392Y409230D03*
X985303Y464652D03*
Y462152D03*
Y459652D03*
X987803Y464652D03*
Y462152D03*
Y459652D03*
X981843Y464818D03*
X992206Y491133D03*
Y498633D03*
X988134Y495151D03*
X985634D03*
X980576Y492987D03*
X985334Y498151D03*
X980576Y495487D03*
X988134Y498151D03*
X992206Y493633D03*
Y496133D03*
X982375Y537877D03*
X992306Y555897D03*
Y553297D03*
X989888Y548366D03*
X987388D03*
X982388D03*
X984888D03*
X982375Y542877D03*
Y545377D03*
Y540377D03*
X992306Y561097D03*
Y563697D03*
Y566797D03*
Y558497D03*
X986301Y570686D03*
X989096Y570478D03*
X989513Y576484D03*
X989156Y573689D03*
X986510Y573303D03*
X992906Y578405D03*
X981857Y597232D03*
X991907Y596782D03*
X986688Y596089D03*
X983843Y619513D03*
Y616713D03*
Y613913D03*
X993857Y605443D03*
X981857Y605637D03*
X980703Y625013D03*
X986600Y717641D03*
X987461Y745796D03*
X981876Y745179D03*
X988371Y764143D03*
X983786Y765647D03*
X984357Y777555D03*
X997051Y778833D03*
X990699Y778630D03*
X987990Y774005D03*
X987394Y787490D03*
X987501Y812573D03*
X985921Y805135D03*
X994051Y810871D03*
X996385Y816141D03*
X979203Y829159D03*
X994094Y829000D03*
X982300Y821200D03*
X987702Y829159D03*
X989700Y846500D03*
X987202Y846395D03*
X987319Y843589D03*
X979203Y833159D03*
X989800Y843900D03*
X987200Y848940D03*
X987703Y837159D03*
X990457Y852043D03*
X983269Y853883D03*
X981700Y856300D03*
X979891Y876589D03*
X992441Y870398D03*
X988054Y888283D03*
X990300Y897500D03*
X979592Y902849D03*
X982783Y909995D03*
X979498Y907500D03*
X989311Y920364D03*
X983227Y968565D03*
X988240Y1020015D03*
Y1016923D03*
Y1023968D03*
X984909Y1081071D03*
X983751Y1078675D03*
X980969Y1076659D03*
X980726Y1084659D03*
X980852Y1098643D03*
X980726Y1104659D03*
Y1092664D03*
X986645Y1108465D03*
X989513Y1097683D03*
X995009Y1131223D03*
X991763Y1140378D03*
Y1128378D03*
Y1134378D03*
X984558Y1140774D03*
X988112Y1137774D03*
X984558Y1128774D03*
Y1134774D03*
X987804Y1131619D03*
X984817Y1303297D03*
X979001Y1288925D03*
X990613Y1324248D03*
Y1327048D03*
X993413Y1324248D03*
Y1327048D03*
X990501Y1320756D03*
X988784Y1361974D03*
X980139Y1381496D03*
X980166Y1373622D03*
X980203Y1377559D03*
X980047Y1397245D03*
X985448Y1398271D03*
X980092Y1389370D03*
X980139Y1393308D03*
X984136Y1401636D03*
X987136D03*
X986949Y1430997D03*
Y1427997D03*
X983949D03*
X989949Y1430997D03*
Y1427997D03*
X983949Y1430997D03*
X992949Y1427997D03*
Y1430997D03*
X986949Y1433997D03*
X983949D03*
X989949D03*
X992949D03*
X986949Y1436997D03*
X983949D03*
X986949Y1439997D03*
X983949D03*
X989949Y1436997D03*
Y1439997D03*
X992949Y1436997D03*
Y1439997D03*
X978934Y1444392D03*
X978987Y1489832D03*
X982241Y1489637D03*
X986773Y1546081D03*
X983773D03*
X980773D03*
X1011284Y68581D03*
X1011297Y80581D03*
X1003379Y72615D03*
Y76587D03*
X1004818Y100625D03*
X997837Y97475D03*
X1013480Y103621D03*
X997768Y106186D03*
X1009191Y112083D03*
X1005397Y141247D03*
X1009884Y143518D03*
X1008984Y152373D03*
X1012936Y178560D03*
X997929Y168697D03*
X1012826Y183834D03*
X1012999Y172665D03*
X999017Y191941D03*
X1003029Y192300D03*
X1012346Y190185D03*
X1007071Y192490D03*
X1013116Y200864D03*
X1003526Y206767D03*
X1006026D03*
X1001026D03*
X1010291Y199582D03*
X1013139Y207037D03*
X1013205Y212455D03*
X1002271Y228221D03*
Y231021D03*
X1010506Y221642D03*
X1003656Y221708D03*
X1006156D03*
X1000571Y224421D03*
X1001156Y221708D03*
X1002822Y236189D03*
X1005322D03*
X1007822D03*
X1002763Y248765D03*
X1005263D03*
X1007763D03*
X999714Y266114D03*
X1008260Y268195D03*
X1005460D03*
X1002960D03*
X1008260Y270695D03*
X1002960D03*
X1005460D03*
X1000698Y300276D03*
X1002580Y309619D03*
X1010499Y309062D03*
X1003181Y323057D03*
X1001105Y318006D03*
X1009770Y344486D03*
X997020Y345354D03*
X1003076Y332496D03*
X1000420Y353954D03*
X996024Y352132D03*
X1001825Y581659D03*
X998332Y578986D03*
X997857Y596729D03*
X995913Y619758D03*
Y616958D03*
Y614158D03*
X1001857Y605443D03*
X1003900Y628700D03*
X1001605Y627605D03*
X1005800Y637600D03*
X1002883Y622521D03*
X1001676Y678015D03*
X1011185Y724519D03*
X1009562Y722438D03*
X1003990Y765899D03*
X1007990D03*
X1002751Y757169D03*
X999990Y764566D03*
X1013151Y756726D03*
X1012695Y776728D03*
X999990Y774671D03*
X1013319Y785929D03*
X1007027Y792973D03*
X998376Y810970D03*
X1006054Y810969D03*
X1010699Y803454D03*
X1002699Y819475D03*
X1011144Y844340D03*
X1010977Y841737D03*
X1012703Y837659D03*
X1001187Y850084D03*
X1004577Y853679D03*
X1004713Y871389D03*
X998313Y888295D03*
X1005413Y905295D03*
X1004953Y923995D03*
X1008935Y924007D03*
X1004994Y955372D03*
X1007919Y948822D03*
X1011019D03*
X1004719D03*
X1012219Y954222D03*
X1006222Y980337D03*
X1009564Y988874D03*
X999879Y998507D03*
X1001805Y1007522D03*
X1008571Y1006648D03*
X1008759Y1023900D03*
X1002180Y1013678D03*
X1002652Y1023731D03*
X1005938Y1018307D03*
X995317Y1137378D03*
X996213Y1324248D03*
Y1327048D03*
X1009333Y1346693D03*
Y1343293D03*
X998600Y1369200D03*
X1008387Y1380797D03*
X998600Y1373400D03*
X997401Y1381200D03*
X999283Y1377400D03*
X1007850Y1368835D03*
X998643Y1398271D03*
X1008138Y1407186D03*
Y1409986D03*
X1005338Y1407186D03*
Y1409986D03*
X1008138Y1415586D03*
Y1412786D03*
X1005338Y1415586D03*
Y1412786D03*
X1008138Y1418386D03*
X1005338D03*
X998949Y1427997D03*
Y1430997D03*
X995949D03*
Y1427997D03*
X1009981Y1431097D03*
Y1428097D03*
X1006981D03*
Y1431097D03*
X998949Y1433997D03*
X995949D03*
X998949Y1436997D03*
X995949D03*
X998949Y1439997D03*
X995949D03*
X1009981Y1434097D03*
X1006981D03*
X1009981Y1437097D03*
X1006981D03*
X1009981Y1440097D03*
X1006981D03*
X1002194Y1444392D03*
X1015059Y55513D03*
X1020519Y60438D03*
X1017659Y60513D03*
X1026200Y86012D03*
X1017787Y85731D03*
X1026200Y94374D03*
X1015427Y88801D03*
X1022293Y94279D03*
X1018344Y94351D03*
X1021341Y86046D03*
X1021537Y116594D03*
X1027480Y110784D03*
X1021537Y119594D03*
X1021971Y124283D03*
X1027037Y124879D03*
X1020378Y161306D03*
X1012134Y152562D03*
X1017629Y157370D03*
X1021713Y176665D03*
Y168665D03*
X1013812Y186629D03*
X1021713Y196665D03*
X1021826Y186778D03*
X1021713Y192665D03*
X1021745Y204864D03*
Y208864D03*
X1026794Y218085D03*
X1017386Y219379D03*
X1018014Y228631D03*
X1023502Y248371D03*
X1014420Y265897D03*
X1011920D03*
X1027216Y289440D03*
X1022604Y290262D03*
X1016635Y300276D03*
X1012635D03*
X1025749D03*
X1020635D03*
X1022435Y312865D03*
X1021848Y310396D03*
X1020406Y350772D03*
X1012188Y443421D03*
X1015659Y679654D03*
Y683054D03*
X1021885Y698974D03*
X1022937Y691421D03*
X1014641Y724436D03*
X1012851Y722417D03*
X1026916Y719769D03*
X1018015Y751565D03*
X1013486Y750773D03*
X1024684Y756485D03*
X1017664Y779101D03*
X1014064Y793660D03*
X1018071Y798490D03*
X1013821Y813520D03*
X1014781Y810319D03*
X1017955Y812097D03*
X1021895Y818974D03*
X1020703Y837659D03*
X1013918Y851306D03*
X1017800Y867065D03*
X1016973Y877196D03*
X1016574Y874537D03*
X1016798Y890299D03*
X1021408Y895008D03*
X1024913Y884000D03*
X1012842Y910685D03*
X1022346Y917669D03*
X1029570Y917718D03*
X1018419Y917575D03*
X1014719Y938322D03*
X1027319D03*
X1027719Y958822D03*
X1014009Y980356D03*
X1018009D03*
X1014009Y988813D03*
X1018009D03*
X1021924Y980456D03*
X1026009Y988813D03*
X1022009D03*
X1017998Y1009655D03*
X1015198D03*
X1024570Y1024003D03*
X1011782Y1016591D03*
X1022143Y1030672D03*
X1019143D03*
X1016143D03*
X1025143D03*
X1023144Y1109564D03*
X1017297D03*
X1023144Y1122164D03*
X1017297D03*
X1023144Y1134764D03*
X1017297D03*
X1023144Y1147364D03*
X1017297D03*
X1023144Y1159964D03*
X1017297D03*
Y1172564D03*
X1023162Y1174445D03*
X1023139Y1184856D03*
X1017297Y1185164D03*
X1026221Y1214372D03*
X1021976Y1218169D03*
X1023358Y1363921D03*
X1013991Y1360842D03*
X1019391Y1377061D03*
X1012981Y1431097D03*
Y1428097D03*
X1015981D03*
Y1431097D03*
X1021981Y1428097D03*
Y1431097D03*
X1018981D03*
Y1428097D03*
X1012981Y1434097D03*
X1015981D03*
X1012981Y1437097D03*
Y1440097D03*
X1015981Y1437097D03*
Y1440097D03*
X1021981Y1434097D03*
X1018981D03*
X1021981Y1437097D03*
X1018981D03*
X1021981Y1440097D03*
X1018981D03*
X1025615Y1444492D03*
X1020023Y1489637D03*
X1016769Y1489832D03*
X1043123Y97667D03*
X1033506Y116594D03*
X1038779Y102495D03*
X1032480Y110784D03*
X1033506Y119594D03*
X1037040Y125107D03*
X1032059Y124663D03*
X1038513Y142862D03*
X1045654Y143762D03*
X1039554Y148717D03*
X1033403Y138838D03*
X1042102Y195176D03*
X1042183Y210509D03*
X1029594Y218085D03*
X1036107Y221970D03*
X1036173Y226320D03*
X1036107Y219470D03*
Y216970D03*
X1033394Y216385D03*
X1043875Y230556D03*
X1039134Y228646D03*
X1042860Y242078D03*
X1038091Y232971D03*
X1034741Y244571D03*
X1032121Y249108D03*
X1042084Y256394D03*
X1037290Y296293D03*
X1033890D03*
X1045650Y300093D03*
X1029639Y300141D03*
X1041783Y321114D03*
X1030220Y313554D03*
X1042948Y333696D03*
X1043106Y340230D03*
X1031259Y350427D03*
X1029885Y711762D03*
X1033200Y731700D03*
X1035619Y755809D03*
X1038344Y756476D03*
X1043016Y782161D03*
X1038678Y776750D03*
X1039251Y812340D03*
X1042414Y801443D03*
X1043425Y830800D03*
X1043626Y836563D03*
X1041100Y838500D03*
X1037527Y836486D03*
X1031813Y850273D03*
X1046045Y841217D03*
X1040822Y841339D03*
X1044390Y861210D03*
X1035185Y862793D03*
X1037685Y862789D03*
X1038363Y875288D03*
X1037709Y886209D03*
X1038010Y902565D03*
X1033019Y933022D03*
Y935822D03*
X1030819Y938422D03*
X1033370Y953994D03*
X1038009Y988813D03*
X1030009D03*
X1042009D03*
X1034009D03*
X1028943Y1016827D03*
X1034790D03*
X1028943Y1029427D03*
X1034790D03*
X1039499Y1098758D03*
X1039053Y1105091D03*
X1044553D03*
X1039098Y1102091D03*
X1039053Y1117691D03*
X1044553D03*
X1039098Y1114691D03*
Y1127291D03*
X1039053Y1130291D03*
X1044553D03*
Y1142891D03*
X1039098Y1139891D03*
X1039053Y1142891D03*
Y1155491D03*
X1044553D03*
X1039098Y1152491D03*
X1044553Y1168091D03*
X1039053D03*
X1039098Y1165091D03*
X1044553Y1180691D03*
X1039053D03*
X1039098Y1177691D03*
X1032831Y1207950D03*
X1029797Y1220921D03*
X1040606Y1230407D03*
X1043588Y1227300D03*
X1032867Y1431213D03*
Y1428213D03*
X1029867D03*
X1035867Y1431213D03*
Y1428213D03*
X1029867Y1431213D03*
X1038867Y1428213D03*
Y1431213D03*
X1041867D03*
Y1428213D03*
X1032867Y1434213D03*
X1029867D03*
X1035867D03*
X1038867D03*
X1032867Y1437213D03*
X1029867D03*
X1032867Y1440213D03*
X1029867D03*
X1035867Y1437213D03*
Y1440213D03*
X1038867Y1437213D03*
Y1440213D03*
X1041867Y1434213D03*
Y1437213D03*
Y1440213D03*
X1051583Y103411D03*
X1051977Y97667D03*
X1047373Y95111D03*
X1051742Y106561D03*
X1047102Y195176D03*
X1046120Y199248D03*
X1044602Y195176D03*
X1049120Y199248D03*
X1049602Y195176D03*
X1046120Y201748D03*
X1049120Y202048D03*
X1044683Y210509D03*
X1046456Y206806D03*
X1043956D03*
X1052720Y230117D03*
X1048130Y227824D03*
X1048736Y238714D03*
X1048217Y246874D03*
X1050437Y244297D03*
X1045364Y279895D03*
X1051796Y279965D03*
X1050164Y302748D03*
X1050076Y305512D03*
X1061387Y343509D03*
X1060679Y356151D03*
X1059549Y458711D03*
X1055885Y554555D03*
X1046068Y792742D03*
X1046930Y796557D03*
X1048314Y833102D03*
X1053392Y832788D03*
X1051550Y823146D03*
X1055700Y840900D03*
X1053913Y837718D03*
X1050358Y837793D03*
X1052500Y841200D03*
X1049087Y856033D03*
X1053909Y855472D03*
X1045300Y872352D03*
X1054900Y879321D03*
X1058155Y887635D03*
X1050295Y891100D03*
X1054009Y988813D03*
X1046009D03*
X1050009D03*
X1058009D03*
X1056199Y1012354D03*
X1050744Y1009354D03*
X1056199Y1024954D03*
X1050699D03*
Y1012354D03*
X1050744Y1021954D03*
X1046485Y1034538D03*
X1057212Y1040356D03*
X1049930Y1221407D03*
X1050605Y1224472D03*
X1049770Y1229402D03*
X1049720Y1234921D03*
X1052660Y1293257D03*
X1050002Y1293283D03*
X1049204Y1337377D03*
X1049670Y1347462D03*
X1046075Y1350650D03*
X1049493Y1350694D03*
X1044867Y1428213D03*
Y1431213D03*
Y1434213D03*
Y1437213D03*
Y1440213D03*
X1048403Y1444608D03*
X1062773Y90650D03*
X1068085Y90615D03*
X1072456Y95236D03*
X1072406Y99961D03*
X1062523Y95236D03*
X1071268Y207978D03*
Y212978D03*
Y215478D03*
Y210478D03*
X1074597Y264180D03*
X1074522Y258880D03*
X1076571Y310574D03*
X1060679Y368276D03*
X1062234Y378600D03*
Y382600D03*
X1062349Y458711D03*
X1064876Y453682D03*
X1063113Y455921D03*
X1061693Y463600D03*
X1062098Y603600D03*
X1061342Y610269D03*
X1061496Y612786D03*
X1062098Y619600D03*
X1063642Y634190D03*
X1062098Y623600D03*
X1066931Y645389D03*
X1060698Y931619D03*
X1069685Y933391D03*
X1066878Y931909D03*
X1070009Y988813D03*
X1069607Y980131D03*
X1066009Y980330D03*
X1062009Y988813D03*
X1065823Y988773D03*
X1074009Y988813D03*
X1070009Y997860D03*
X1073525Y1012428D03*
X1076110Y1029535D03*
X1065079Y1036920D03*
X1076577Y1041332D03*
X1074232Y1055836D03*
X1067866Y1051037D03*
X1060768Y1053457D03*
X1074650Y1070006D03*
X1069642Y1445541D03*
X1068861Y1451311D03*
X1081320Y85193D03*
Y82593D03*
Y79993D03*
Y77393D03*
Y74793D03*
X1089645Y98551D03*
X1081364Y92874D03*
X1083391Y104249D03*
Y107649D03*
X1087957Y147540D03*
X1091729Y141247D03*
X1083013Y162368D03*
X1090113Y165393D03*
Y162793D03*
X1080413Y162368D03*
X1090113Y170493D03*
Y167993D03*
X1092321Y181366D03*
X1089110Y181426D03*
X1091935Y184012D03*
X1089318Y184221D03*
X1081724Y208213D03*
X1085796Y208695D03*
Y211695D03*
X1081724Y210713D03*
Y213213D03*
X1088596Y208695D03*
X1088296Y211695D03*
X1081724Y215713D03*
X1077097Y264180D03*
X1091973Y265701D03*
X1083491Y267526D03*
X1088791D03*
X1086291D03*
X1083491Y270026D03*
X1086291D03*
X1088791D03*
X1093608Y281716D03*
X1080351Y328256D03*
X1079748Y322743D03*
Y319343D03*
X1080351Y331656D03*
X1082297Y340770D03*
X1092554Y340318D03*
X1085615Y339815D03*
X1092561Y353374D03*
X1082787Y348501D03*
X1091031Y374810D03*
X1089788Y550907D03*
X1087288D03*
X1089788Y553407D03*
X1087288D03*
X1089096Y541863D03*
Y545263D03*
X1091558Y566929D03*
X1091272Y569426D03*
X1088949Y568475D03*
X1089206Y570962D03*
X1086859Y569928D03*
X1085512Y572070D03*
X1078920Y856700D03*
X1090375Y899047D03*
X1076800Y1012900D03*
X1078755Y1031518D03*
X1079178Y1037884D03*
X1076868Y1047293D03*
X1079910Y1045264D03*
X1079822Y1151870D03*
X1083562Y1155610D03*
X1079822Y1159350D03*
X1083283Y1526583D03*
X1084000Y1529600D03*
X1091529Y1528718D03*
X1091525Y1546300D03*
X1090876Y1554183D03*
X1091569Y1561300D03*
X1092527Y1579422D03*
X1086469Y1588435D03*
X1090469D03*
X1083900Y1593206D03*
X1082176Y1600598D03*
X1090904Y1599047D03*
X1088021Y1606949D03*
X1093778Y1599574D03*
X1086904Y1599004D03*
X1090093Y1628297D03*
X1085474Y1629028D03*
X1089474Y1638213D03*
X1105741Y76587D03*
Y72615D03*
X1100199Y97475D03*
X1107180Y100625D03*
X1100130Y106186D03*
X1093195Y103783D03*
X1107759Y141247D03*
X1099196Y143740D03*
X1096576Y148277D03*
X1095116Y181009D03*
X1100291Y168697D03*
X1097618Y172190D03*
X1109903Y171523D03*
X1097037Y177616D03*
X1101379Y191941D03*
X1109433Y192490D03*
X1105888Y206767D03*
X1108388D03*
X1103388D03*
X1093354Y213859D03*
Y211359D03*
X1097057Y213132D03*
X1104633Y228221D03*
X1106018Y221708D03*
X1108518D03*
X1102933Y224421D03*
X1103518Y221708D03*
X1104633Y231021D03*
X1097057Y215632D03*
X1105184Y236189D03*
X1107684D03*
X1105125Y248765D03*
X1107625D03*
X1097301Y256303D03*
X1102076Y266114D03*
X1097060Y265896D03*
X1107822Y268195D03*
X1105322D03*
Y270695D03*
X1107822D03*
X1099549Y281982D03*
X1093478Y310305D03*
X1108779Y327705D03*
X1103432Y340544D03*
X1097976Y340477D03*
X1105012Y353504D03*
X1098845Y353404D03*
X1093841Y371335D03*
X1099501Y545528D03*
X1108236Y577716D03*
X1105298Y610400D03*
X1108045Y668153D03*
X1092769Y936975D03*
X1095080Y1513398D03*
X1096780Y1526700D03*
X1101402Y1531702D03*
X1095250Y1531600D03*
X1098617Y1546183D03*
X1096780Y1535400D03*
X1100876Y1554183D03*
X1099371Y1561153D03*
X1100476Y1579318D03*
X1102904Y1566668D03*
X1093682Y1582433D03*
X1098498Y1590435D03*
X1104233Y1587983D03*
X1100233Y1588000D03*
X1107620Y1603602D03*
X1098904Y1602138D03*
X1101946Y1614709D03*
X1096941Y1627905D03*
X1105474Y1629450D03*
X1101474Y1637820D03*
X1093474Y1638213D03*
X1105474Y1638426D03*
X1097474Y1637753D03*
X1114781Y58013D03*
X1113646Y68581D03*
X1120021Y60513D03*
X1122881Y60438D03*
X1113659Y80581D03*
X1120149Y85731D03*
X1117789Y88801D03*
X1123703Y86046D03*
X1120706Y94351D03*
X1124655Y94279D03*
X1115842Y103621D03*
X1123899Y116594D03*
X1111553Y112083D03*
X1123899Y119594D03*
X1124333Y124283D03*
X1112246Y143518D03*
X1111346Y152373D03*
X1122740Y161306D03*
X1114496Y152562D03*
X1119991Y157370D03*
X1124075Y168665D03*
Y176665D03*
X1115188Y183834D03*
X1115298Y178560D03*
X1115361Y172665D03*
X1116174Y186629D03*
X1124075Y192665D03*
Y196665D03*
X1115478Y200864D03*
X1114708Y190185D03*
X1124188Y186778D03*
X1124107Y204864D03*
X1115501Y207037D03*
X1115567Y212455D03*
X1124107Y208864D03*
X1112868Y221642D03*
X1119748Y219379D03*
X1120376Y228631D03*
X1110184Y236189D03*
X1110125Y248765D03*
X1116782Y265897D03*
X1114282D03*
X1110622Y268195D03*
Y270695D03*
X1115000Y329000D03*
Y334000D03*
Y339000D03*
X1118848Y382109D03*
X1118847Y551683D03*
Y561420D03*
Y558917D03*
X1122705Y588515D03*
X1114668Y577937D03*
X1117673Y606929D03*
X1122673Y595500D03*
X1122173Y604567D03*
X1122705Y591015D03*
X1123331Y610072D03*
X1123267Y616317D03*
X1117633Y618400D03*
X1117914Y612592D03*
X1115151Y650119D03*
X1115320Y646449D03*
X1115054Y662981D03*
X1116296Y691851D03*
X1111785Y686971D03*
X1118105Y707592D03*
X1128562Y86012D03*
Y94374D03*
X1135868Y116594D03*
X1141141Y102495D03*
X1129842Y110784D03*
X1134842D03*
X1135868Y119594D03*
X1139402Y125107D03*
X1129399Y124879D03*
X1134421Y124663D03*
X1140875Y142862D03*
X1141916Y148717D03*
X1135765Y138838D03*
X1129156Y218085D03*
X1131956D03*
X1138469Y221970D03*
X1138535Y226320D03*
X1138469Y219470D03*
Y216970D03*
X1135756Y216385D03*
X1141496Y228646D03*
X1140453Y232971D03*
X1137103Y244571D03*
X1134483Y249108D03*
X1125864Y248371D03*
X1137830Y336230D03*
X1135548Y455804D03*
X1134629Y465551D03*
X1126622Y506256D03*
X1139673Y530000D03*
X1139173Y540500D03*
X1138373Y549800D03*
X1138173Y547075D03*
X1137673Y568000D03*
X1138213Y558800D03*
X1138277Y562800D03*
X1129471Y732571D03*
X1153945Y103411D03*
X1145485Y97667D03*
X1154339D03*
X1149735Y95111D03*
X1154104Y106561D03*
X1148016Y143762D03*
X1149464Y195176D03*
X1148482Y199248D03*
X1151482D03*
X1144464Y195176D03*
X1146964D03*
X1151964D03*
X1151482Y202048D03*
X1146318Y206806D03*
X1144545Y210509D03*
X1147045D03*
X1148818Y206806D03*
X1148482Y201748D03*
X1146237Y230556D03*
X1155082Y230117D03*
X1150492Y227824D03*
X1151098Y238714D03*
X1145222Y242078D03*
X1150579Y246874D03*
X1152799Y244297D03*
X1147590Y253198D03*
X1145587Y339148D03*
X1142440Y396718D03*
X1157451Y618288D03*
X1156275Y656321D03*
X1155146Y699491D03*
X1152512Y728543D03*
X1148962Y747253D03*
X1152485Y764552D03*
X1147468Y766093D03*
X1154652Y791056D03*
X1145910Y803642D03*
X1153485Y813142D03*
X1154985Y802897D03*
X1153229Y848581D03*
X1170447Y90615D03*
X1165135Y90650D03*
X1174768Y99961D03*
X1164885Y95236D03*
X1173630Y207978D03*
Y210478D03*
Y212978D03*
Y215478D03*
X1173559Y304948D03*
X1171445Y422088D03*
X1166868Y442956D03*
X1168685Y438323D03*
X1168398Y456309D03*
X1168851Y445873D03*
X1163298Y465874D03*
X1159535Y546712D03*
Y542712D03*
X1165400Y553300D03*
X1167900D03*
X1161451Y618288D03*
X1160275Y656321D03*
X1164275D03*
X1162863Y678519D03*
X1159173Y678462D03*
X1170465Y677836D03*
X1157646Y699491D03*
X1162646D03*
X1160146D03*
X1169256Y694983D03*
X1163774Y713347D03*
X1166115Y718469D03*
X1171934Y733857D03*
X1173034Y765060D03*
X1169697Y791935D03*
X1164925Y791607D03*
X1164732Y802269D03*
X1173122Y802759D03*
X1163579Y850774D03*
X1161535Y844167D03*
X1159887Y869106D03*
X1174461Y914515D03*
X1183682Y85193D03*
Y82593D03*
Y74793D03*
Y79993D03*
Y77393D03*
X1183726Y92874D03*
X1174818Y95236D03*
X1185753Y107649D03*
Y104249D03*
X1182775Y162368D03*
X1185375D03*
X1188158Y211695D03*
X1184086Y210713D03*
Y213213D03*
Y208213D03*
X1190958Y208695D03*
X1188158D03*
X1184086Y215713D03*
X1176959Y264180D03*
X1179459D03*
X1177035Y257919D03*
X1185853Y267526D03*
X1188653D03*
X1185853Y270026D03*
X1188653D03*
X1179901Y306366D03*
X1181706Y310131D03*
X1178045Y312193D03*
X1181379Y316049D03*
X1174929Y319167D03*
X1179761Y336380D03*
X1187996Y331992D03*
X1191748Y392676D03*
X1188598Y381500D03*
X1178083Y442856D03*
X1189122Y442606D03*
X1176699Y451108D03*
X1176138Y458455D03*
X1179184Y453881D03*
Y446595D03*
X1188739Y446606D03*
X1190046Y463479D03*
X1174595Y771744D03*
X1176500Y784933D03*
X1185516Y844248D03*
X1190968Y848703D03*
X1184340Y851072D03*
X1183012Y856553D03*
X1190213Y856816D03*
X1187431Y868340D03*
X1180239Y868430D03*
X1179858Y883455D03*
X1179727Y886197D03*
X1181654Y894671D03*
X1185058Y883475D03*
X1187151Y921000D03*
X1182000Y936500D03*
X1189219Y940703D03*
X1192007Y98551D03*
X1202561Y97475D03*
X1195557Y103783D03*
X1202492Y106186D03*
X1190319Y147540D03*
X1194091Y141247D03*
X1201558Y143740D03*
X1198938Y148277D03*
X1192475Y165393D03*
Y162793D03*
Y167993D03*
Y170493D03*
X1199980Y172190D03*
X1194683Y181366D03*
X1191472Y181426D03*
X1197478Y181009D03*
X1202653Y168697D03*
X1199399Y177616D03*
X1203741Y191941D03*
X1194297Y184012D03*
X1191680Y184221D03*
X1205750Y206767D03*
X1195716Y211359D03*
Y213859D03*
X1199419Y213132D03*
X1190658Y211695D03*
X1205295Y224421D03*
X1205880Y221708D03*
X1199419Y215632D03*
X1199663Y256303D03*
X1199422Y265896D03*
X1204438Y266114D03*
X1194335Y265701D03*
X1191153Y267526D03*
Y270026D03*
X1201911Y281982D03*
X1195970Y281716D03*
X1201113Y315039D03*
X1190127Y324142D03*
X1195800Y324000D03*
X1206531Y393858D03*
X1208173Y398583D03*
X1192702Y440489D03*
X1192957Y435158D03*
X1193000Y444841D03*
X1192686Y449961D03*
X1196403Y458572D03*
X1192431Y868620D03*
X1192152Y884399D03*
X1192367Y903785D03*
X1190210Y900909D03*
X1191151Y936296D03*
X1193219Y940703D03*
X1197173Y940645D03*
X1196352Y951033D03*
X1191219Y967757D03*
X1191928Y987314D03*
X1198644Y985289D03*
X1195757Y988131D03*
X1203419Y1011161D03*
X1200008D03*
X1196300Y998600D03*
X1202028Y998349D03*
X1199700Y1013661D03*
X1201800Y1019431D03*
X1219783Y55513D03*
X1216008Y68581D03*
X1222383Y60513D03*
X1216021Y80581D03*
X1208103Y72615D03*
Y76587D03*
X1222511Y85731D03*
X1220151Y88801D03*
X1218204Y103621D03*
X1209542Y100625D03*
X1213915Y112083D03*
X1210121Y141247D03*
X1214608Y143518D03*
X1213708Y152373D03*
X1216858Y152562D03*
X1222353Y157370D03*
X1217550Y183834D03*
X1212265Y171523D03*
X1217723Y172665D03*
X1217660Y178560D03*
X1218536Y186629D03*
X1211795Y192490D03*
X1210268Y198671D03*
X1217840Y200864D03*
X1217070Y190185D03*
X1207753Y192300D03*
X1208250Y206767D03*
X1210750D03*
X1217863Y207037D03*
X1217929Y212455D03*
X1215230Y221642D03*
X1206995Y228221D03*
X1208380Y221708D03*
X1210880D03*
X1206995Y231021D03*
X1222110Y219379D03*
X1222738Y228631D03*
X1207546Y236189D03*
X1210046D03*
X1212546D03*
X1207487Y248765D03*
X1209987D03*
X1212487D03*
X1219144Y265897D03*
X1216644D03*
X1212984Y268195D03*
X1210184D03*
X1207684D03*
X1212984Y270695D03*
X1207684D03*
X1210184D03*
X1220723Y324466D03*
X1211892Y339559D03*
X1215776Y331072D03*
X1213173Y377912D03*
X1217177Y369925D03*
X1206693Y384410D03*
X1213173Y386500D03*
X1209872Y382047D03*
X1212173Y391496D03*
X1213261Y397912D03*
X1210173Y403500D03*
X1212173Y409000D03*
X1209426Y433069D03*
Y430469D03*
Y435669D03*
Y440869D03*
Y438269D03*
X1206626Y433069D03*
Y430469D03*
Y435669D03*
Y440869D03*
Y438269D03*
X1209980Y451677D03*
X1207480Y454177D03*
X1209980D03*
X1207480Y451677D03*
X1209184Y463618D03*
Y460218D03*
X1225243Y60438D03*
X1230924Y86012D03*
Y94374D03*
X1226065Y86046D03*
X1227017Y94279D03*
X1223068Y94351D03*
X1238230Y116594D03*
X1226261D03*
X1232204Y110784D03*
X1237204D03*
X1238230Y119594D03*
X1226261D03*
X1236783Y124663D03*
X1226695Y124283D03*
X1231761Y124879D03*
X1238127Y138838D03*
X1225102Y161306D03*
X1226437Y176665D03*
Y168665D03*
Y192665D03*
X1226550Y186778D03*
X1226469Y204864D03*
Y208864D03*
X1231518Y218085D03*
X1234318D03*
X1238118Y216385D03*
X1239465Y244571D03*
X1236845Y249108D03*
X1228226Y248371D03*
X1229252Y314890D03*
X1229028Y311740D03*
X1226436Y324518D03*
X1229922Y324550D03*
X1234904Y316942D03*
X1232197Y316964D03*
X1238293Y317296D03*
X1229438Y332584D03*
X1235589Y348015D03*
X1229942Y347937D03*
X1231506Y353470D03*
X1223431Y377912D03*
X1225755Y369391D03*
X1229122Y369355D03*
X1222601Y369251D03*
X1223431Y381912D03*
Y397912D03*
X1232833Y539315D03*
X1232149Y550137D03*
X1234941D03*
X1235930Y626229D03*
X1235292Y622912D03*
X1237500Y632405D03*
X1238034Y629961D03*
X1238695Y627313D03*
X1256307Y103411D03*
X1247847Y97667D03*
X1256701D03*
X1252097Y95111D03*
X1243503Y102495D03*
X1241764Y125107D03*
X1243237Y142862D03*
X1250378Y143762D03*
X1244278Y148717D03*
X1251826Y195176D03*
X1254326D03*
X1253844Y199248D03*
X1249326Y195176D03*
X1250844Y199248D03*
X1246826Y195176D03*
X1249407Y210509D03*
X1253844Y202048D03*
X1250844Y201748D03*
X1251180Y206806D03*
X1248680D03*
X1246907Y210509D03*
X1240831Y221970D03*
X1240897Y226320D03*
X1240831Y219470D03*
Y216970D03*
X1248599Y230556D03*
X1252854Y227824D03*
X1243858Y228646D03*
X1253460Y238714D03*
X1247584Y242078D03*
X1252941Y246874D03*
X1242815Y232971D03*
X1246808Y256394D03*
X1241205Y303962D03*
X1253245Y416888D03*
Y419488D03*
Y422088D03*
X1253087Y553101D03*
X1241629Y550065D03*
X1248106Y1004700D03*
X1245400Y1003700D03*
X1246000Y1014800D03*
X1252148Y1026223D03*
X1252500Y1014288D03*
X1246300Y1027800D03*
X1253424Y1138130D03*
X1250928Y1142828D03*
X1254200Y1146600D03*
X1249363Y1173065D03*
X1256218Y1175987D03*
X1249363Y1166065D03*
X1255439Y1172008D03*
X1255628Y1188345D03*
X1253056Y1194917D03*
X1254275Y1531334D03*
X1249894Y1527805D03*
X1253904Y1519645D03*
X1254275Y1539334D03*
X1250434Y1535334D03*
X1267497Y90650D03*
X1267247Y95236D03*
X1256466Y106561D03*
X1257444Y230117D03*
X1255161Y244297D03*
X1266962Y302167D03*
X1262665Y302730D03*
X1263328Y309003D03*
X1262075Y324075D03*
X1261659Y318258D03*
X1264088Y320382D03*
X1266616Y322456D03*
X1257000Y333500D03*
X1264215Y333215D03*
X1262500Y330655D03*
X1256000Y338000D03*
X1259991Y340691D03*
X1256000Y340500D03*
X1263500Y336000D03*
X1264659Y377173D03*
X1267944Y371767D03*
X1261764Y391533D03*
X1263484Y385644D03*
X1268659Y385123D03*
X1268067Y406060D03*
X1261231Y399918D03*
X1264336Y412106D03*
X1268328Y421489D03*
Y418889D03*
Y416289D03*
X1270397Y447081D03*
X1259223Y454334D03*
X1267540Y459330D03*
X1267493Y454214D03*
X1267836Y449045D03*
X1267843Y473571D03*
Y481071D03*
Y478571D03*
Y476071D03*
X1269629Y848124D03*
X1270892Y856343D03*
X1271121Y892513D03*
X1270276Y897062D03*
X1269221Y894760D03*
X1270586Y905324D03*
X1272661Y929858D03*
X1260539Y1134729D03*
X1267921D03*
X1266718Y1142666D03*
X1263921Y1134729D03*
X1268593Y1157544D03*
X1267104Y1167768D03*
X1272123D03*
X1271246Y1178240D03*
X1271256Y1185205D03*
X1262605Y1187215D03*
X1262298Y1180175D03*
X1260800Y1191096D03*
X1268571Y1201043D03*
X1264575D03*
X1261538Y1199814D03*
X1255296Y1196056D03*
X1263449Y1217228D03*
X1266113Y1219895D03*
X1269388Y1223170D03*
X1267333Y1531334D03*
X1262891Y1527334D03*
X1267183Y1539334D03*
X1262891Y1535334D03*
X1286044Y85539D03*
Y82939D03*
Y75139D03*
Y80339D03*
Y77739D03*
X1286088Y92874D03*
X1272809Y90615D03*
X1277130Y99961D03*
X1277180Y95236D03*
X1285137Y162368D03*
X1275992Y215478D03*
Y212978D03*
Y210478D03*
Y207978D03*
X1286448Y213213D03*
Y210713D03*
Y208213D03*
Y215713D03*
X1281821Y264180D03*
X1279321D03*
X1279246Y258880D03*
X1271571Y281185D03*
X1289345Y330655D03*
X1284419Y359377D03*
X1287437Y379429D03*
X1280699Y377173D03*
X1284659D03*
X1274436Y377350D03*
X1276659Y385123D03*
X1273659D03*
X1280659D03*
X1284333Y391569D03*
X1282760Y401066D03*
X1272421Y403300D03*
X1271828Y405889D03*
Y408489D03*
Y413689D03*
Y411089D03*
Y416289D03*
Y421489D03*
Y418889D03*
Y424089D03*
X1272215Y432718D03*
Y435518D03*
X1282092Y442118D03*
Y439318D03*
X1271828Y426689D03*
X1272927Y450091D03*
X1275927D03*
X1273397Y447081D03*
X1281737Y461034D03*
Y456034D03*
X1272927Y462060D03*
X1275927D03*
X1286005Y485580D03*
X1280631Y480194D03*
Y477694D03*
X1277897Y478876D03*
Y476376D03*
X1274415Y477053D03*
X1271915D03*
X1284900Y678800D03*
X1283400Y715500D03*
X1278255Y722241D03*
X1283400Y719700D03*
X1282539Y746076D03*
X1279539Y748576D03*
X1282539Y751076D03*
X1279539Y763576D03*
X1282539Y766076D03*
X1279539Y758576D03*
X1282539Y756076D03*
Y761076D03*
X1279539Y753576D03*
Y768576D03*
Y780576D03*
Y784576D03*
X1285092Y819500D03*
X1285500Y827500D03*
X1281388Y827388D03*
X1281777Y823500D03*
X1285500Y843500D03*
X1281331Y843331D03*
X1281269Y835492D03*
X1285500Y835500D03*
X1283025Y848305D03*
X1271438Y861846D03*
X1285500Y863500D03*
Y859500D03*
Y855500D03*
Y851500D03*
X1279460Y854487D03*
Y859487D03*
Y864487D03*
X1274396Y866896D03*
X1285500Y867500D03*
X1279460Y874487D03*
Y869487D03*
Y879487D03*
X1285302Y877283D03*
X1282285Y865602D03*
X1274264Y898591D03*
X1279460Y884487D03*
X1285302Y885783D03*
X1279299Y898813D03*
X1279460Y889487D03*
X1285302Y881783D03*
X1281075Y911075D03*
X1282184Y898854D03*
X1274400Y914123D03*
X1283494Y907176D03*
X1275493Y929858D03*
X1279493D03*
X1283493D03*
X1279693Y919800D03*
X1274670Y919808D03*
X1281400Y940256D03*
X1289547Y941000D03*
X1281733Y949475D03*
X1275788Y1124088D03*
X1282421Y1137129D03*
X1271921Y1134729D03*
X1275794D03*
X1282830Y1150087D03*
X1275050Y1157404D03*
X1280306Y1170767D03*
X1275965Y1187232D03*
X1280602Y1185238D03*
X1280395Y1180235D03*
X1272541Y1201043D03*
X1276575Y1201039D03*
X1280575Y1200969D03*
X1280694Y1208993D03*
X1274446Y1228226D03*
X1272235Y1226016D03*
X1297687Y-40256D03*
Y-43656D03*
X1297785Y33768D03*
X1302139Y26325D03*
X1302785Y31168D03*
X1294369Y98551D03*
X1304923Y97475D03*
X1297919Y103783D03*
X1288115Y104249D03*
Y107649D03*
X1294837Y162793D03*
X1287737Y162368D03*
X1294837Y165393D03*
Y167993D03*
Y170493D03*
X1301761Y177616D03*
X1302342Y172190D03*
X1299840Y181009D03*
X1293834Y181426D03*
X1297045Y181366D03*
X1294042Y184221D03*
X1296659Y184012D03*
X1301781Y213132D03*
X1298078Y211359D03*
Y213859D03*
X1290520Y211695D03*
X1293020D03*
X1290520Y208695D03*
X1293320D03*
X1301781Y215632D03*
X1302025Y256303D03*
X1296697Y265701D03*
X1301784Y265896D03*
X1293515Y270026D03*
X1291015D03*
X1288215D03*
Y267526D03*
X1293515D03*
X1291015D03*
X1304273Y281982D03*
X1298332Y281716D03*
X1294000Y324000D03*
X1303000Y326692D03*
X1293000Y338500D03*
X1303000Y331000D03*
X1302896Y343797D03*
Y340397D03*
X1292500Y335000D03*
X1299959Y356954D03*
X1294080Y349820D03*
X1291410Y371060D03*
X1295410Y371076D03*
X1293048Y379088D03*
X1298346Y379028D03*
X1293100Y409539D03*
X1296100D03*
X1293100Y406739D03*
X1296100Y407039D03*
X1295764Y401981D03*
X1298264D03*
X1300037Y398278D03*
X1297537D03*
X1292618Y413611D03*
X1295118D03*
X1300118D03*
X1297618D03*
X1292383Y424067D03*
X1294883D03*
X1299883D03*
X1297383D03*
X1299757Y438293D03*
Y441093D03*
X1290092Y442118D03*
Y439318D03*
X1299757Y443893D03*
X1287719Y470001D03*
X1290219D03*
X1299867Y477318D03*
X1299466Y466409D03*
X1299807Y472020D03*
X1288144Y489036D03*
X1291005Y485580D03*
X1288505D03*
X1301314Y484882D03*
X1299304Y487382D03*
X1290380Y495636D03*
Y492836D03*
X1300817Y568635D03*
X1301194Y565518D03*
X1305836Y660009D03*
X1298963Y659609D03*
X1289811Y677612D03*
X1289317Y706932D03*
X1291604Y781576D03*
Y776576D03*
Y771435D03*
X1295491Y798821D03*
X1298720Y798975D03*
X1289730Y806845D03*
X1302140Y812625D03*
X1302501Y824747D03*
X1297667Y832150D03*
X1293500Y827500D03*
X1296770Y828775D03*
X1293500Y843500D03*
Y835500D03*
X1296687Y839500D03*
X1293500Y851500D03*
X1294000Y863500D03*
X1293500Y879800D03*
Y871800D03*
Y875800D03*
X1288164Y892354D03*
X1296866Y894993D03*
X1305250Y889250D03*
X1293272Y887800D03*
X1293500Y883800D03*
X1291129Y892267D03*
X1294264Y905595D03*
X1301657Y899129D03*
X1288500Y901254D03*
X1298966Y899610D03*
X1296466D03*
X1298000Y917000D03*
X1294075D03*
X1304949Y928546D03*
X1292500Y928000D03*
X1295453Y928047D03*
X1291059Y917000D03*
X1302000D03*
X1302500Y939500D03*
X1300882Y937144D03*
X1296500Y961500D03*
X1289500Y949500D03*
X1300500Y960000D03*
X1290792Y961363D03*
X1300500Y970187D03*
X1297558Y970216D03*
X1292836Y975244D03*
X1292631Y979845D03*
X1299717Y1024136D03*
X1297852Y1014475D03*
X1295815Y1124943D03*
X1295893Y1122182D03*
X1310853Y37543D03*
X1314887Y45448D03*
X1318859D03*
X1311904Y100625D03*
X1320566Y103621D03*
X1304854Y106186D03*
X1316277Y112083D03*
X1305015Y168697D03*
X1319912Y183834D03*
X1314627Y171523D03*
X1320085Y172665D03*
X1320022Y178560D03*
X1306103Y191941D03*
X1319432Y190185D03*
X1314157Y192490D03*
X1320202Y200864D03*
X1310115Y192300D03*
X1308112Y206767D03*
X1313112D03*
X1310612D03*
X1320225Y207037D03*
X1320291Y212455D03*
X1313242Y221708D03*
X1310742D03*
X1309357Y231021D03*
Y228221D03*
X1317592Y221642D03*
X1308242Y221708D03*
X1307657Y224421D03*
X1309908Y236189D03*
X1314908D03*
X1312408D03*
X1312349Y248765D03*
X1309849D03*
X1314849D03*
X1306800Y266114D03*
X1310046Y268195D03*
X1312546D03*
X1315346D03*
X1319006Y265897D03*
X1312546Y270695D03*
X1310046D03*
X1315346D03*
X1318362Y310562D03*
X1305928Y318250D03*
X1308428D03*
X1315256Y336510D03*
X1313103Y339606D03*
X1312240Y334681D03*
X1315397Y333709D03*
X1308012Y348109D03*
X1305910Y377581D03*
X1310172Y367956D03*
X1308410Y379591D03*
X1311283Y370801D03*
X1308826Y389402D03*
X1306113Y383817D03*
X1312626Y387702D03*
X1315426D03*
X1306113Y386317D03*
Y388817D03*
X1309750Y438293D03*
Y441093D03*
Y443893D03*
X1311488Y471560D03*
X1307819Y474382D03*
X1307835Y470382D03*
X1319474Y467560D03*
X1319974Y475560D03*
X1311488D03*
X1318160Y520053D03*
X1317945Y523058D03*
X1319000Y562500D03*
Y558500D03*
Y586500D03*
Y574500D03*
Y578500D03*
Y605000D03*
Y590500D03*
X1319323Y598454D03*
X1319000Y621000D03*
Y609000D03*
Y633000D03*
Y625000D03*
Y637000D03*
Y653500D03*
Y649500D03*
Y641000D03*
Y669500D03*
Y665500D03*
Y681500D03*
Y677500D03*
X1313979Y677726D03*
X1319000Y685500D03*
Y696500D03*
Y700500D03*
Y712500D03*
Y716500D03*
Y724500D03*
Y728500D03*
Y732500D03*
X1321000Y796000D03*
X1313000D03*
X1317000Y799000D03*
Y788000D03*
X1313000D03*
X1315000Y811620D03*
X1319000D03*
X1317000Y804000D03*
X1313000D03*
X1321000D03*
X1310715Y820491D03*
Y822991D03*
Y817991D03*
X1310687Y830206D03*
Y832706D03*
Y827706D03*
X1310971Y842319D03*
X1305786Y867704D03*
X1310994Y866859D03*
X1309753Y877589D03*
X1305740Y877534D03*
X1310535Y870775D03*
X1308220Y889253D03*
X1311061Y889361D03*
X1314500Y911500D03*
X1319500Y901500D03*
X1314500Y905000D03*
X1305356Y902597D03*
X1319500Y905000D03*
X1309103Y917000D03*
X1313867Y925605D03*
X1311325Y928918D03*
X1319554Y925585D03*
X1309103Y936559D03*
X1306500Y936500D03*
X1315779Y943743D03*
X1313152Y936605D03*
X1312575Y943974D03*
X1321256Y943815D03*
X1311000Y961500D03*
X1307000Y960500D03*
X1315441Y960000D03*
X1307000Y970000D03*
X1311000Y970124D03*
X1307707Y979870D03*
X1317254Y990777D03*
X1317053Y988111D03*
X1319874Y989856D03*
X1307561Y986951D03*
X1315606Y1042825D03*
X1315756Y1039344D03*
X1312873Y1036543D03*
X1306385Y1036646D03*
X1319221Y1058097D03*
Y1060697D03*
X1316869Y1107997D03*
X1319069Y1112397D03*
X1318969Y1109397D03*
X1316869Y1113797D03*
Y1110897D03*
X1317437Y1160834D03*
X1318178Y1192621D03*
Y1190121D03*
X1319237Y1221428D03*
X1311237D03*
X1315237D03*
X1311237Y1233428D03*
Y1229428D03*
Y1225428D03*
X1315237Y1237428D03*
Y1233428D03*
Y1229428D03*
Y1225428D03*
X1319237Y1237428D03*
Y1233428D03*
Y1229428D03*
Y1225428D03*
X1315237Y1241428D03*
X1319237D03*
X1308107Y1283395D03*
X1310773Y1282411D03*
X1303900Y1288000D03*
X1318287Y1295381D03*
Y1291381D03*
X1324120Y22742D03*
X1331073Y33400D03*
X1328003Y32403D03*
X1328318Y27333D03*
X1336623Y30483D03*
X1322853Y37530D03*
X1328799Y168665D03*
Y176665D03*
X1320898Y186629D03*
X1328799Y192665D03*
Y196665D03*
X1328912Y186778D03*
X1328831Y204864D03*
Y208864D03*
X1324472Y219379D03*
X1325100Y228631D03*
X1321506Y265897D03*
X1334110Y310562D03*
X1321762D03*
X1329636Y307562D03*
X1326236D03*
X1332563Y326356D03*
X1325573Y326719D03*
X1332359Y322685D03*
X1326489Y356945D03*
X1331005Y356670D03*
X1331922Y359836D03*
X1325007Y370951D03*
X1334109Y373401D03*
X1334285Y386567D03*
X1331606D03*
X1328896D03*
X1320594Y387151D03*
Y382151D03*
Y384651D03*
X1329097Y435321D03*
Y438121D03*
X1326297Y435321D03*
Y438121D03*
X1329097Y440921D03*
X1326297D03*
X1329097Y443721D03*
X1326297D03*
X1335440Y452799D03*
X1329083Y448931D03*
X1329606Y459170D03*
X1332974Y474513D03*
X1321450Y520268D03*
X1321164Y523130D03*
X1326993Y556788D03*
X1331096Y549931D03*
X1327043Y573346D03*
X1327000Y562500D03*
X1326946Y567906D03*
X1338000Y562500D03*
X1327000Y578500D03*
Y583826D03*
X1335000Y594500D03*
X1327000Y605000D03*
Y594500D03*
Y609000D03*
X1333224Y615484D03*
X1327000Y613000D03*
Y621000D03*
X1335532Y622260D03*
X1338000Y609000D03*
X1327000Y629000D03*
X1327003Y623940D03*
X1335000Y641000D03*
X1338000Y653500D03*
X1327000Y641000D03*
X1327011Y646064D03*
X1327000Y657500D03*
X1335000Y685500D03*
X1327000D03*
Y695500D03*
Y700500D03*
X1338000D03*
X1327000Y711500D03*
Y716500D03*
X1335000Y732500D03*
X1327000D03*
X1330295Y746328D03*
X1326970Y736464D03*
X1336661Y753675D03*
Y745675D03*
Y737675D03*
X1330295Y751328D03*
X1330086Y763758D03*
X1330324Y779030D03*
X1336746Y781675D03*
X1329000Y796000D03*
X1325000Y799000D03*
X1337000Y796000D03*
X1333000Y799000D03*
Y788000D03*
X1329000D03*
X1321000D03*
X1325000D03*
X1331000Y811620D03*
X1327000D03*
X1329000Y804000D03*
X1325000D03*
X1333000D03*
X1323000Y811620D03*
X1335000D03*
X1335803Y826500D03*
X1331056Y904557D03*
X1336096Y905042D03*
X1336000Y900500D03*
X1324000Y901000D03*
X1331078Y900500D03*
X1330500Y925500D03*
X1334500D03*
X1326500D03*
X1333425Y930925D03*
X1324000D03*
X1333132Y933781D03*
X1336000Y943500D03*
X1329199Y933825D03*
X1323000Y934075D03*
X1326500Y943500D03*
X1335343Y961727D03*
X1321028Y961749D03*
X1332500Y961500D03*
X1325550Y960445D03*
X1332000Y969500D03*
X1327000D03*
X1329503Y991088D03*
X1334909Y990340D03*
X1332404Y988215D03*
X1329834Y988132D03*
X1324735Y989966D03*
X1327267Y988271D03*
X1322427Y988221D03*
X1333974Y1033483D03*
X1320549Y1037876D03*
X1322773Y1040599D03*
X1329221Y1058097D03*
X1321721D03*
X1324221D03*
X1326721D03*
Y1060697D03*
X1329221D03*
X1321721D03*
X1324221D03*
X1326163Y1082501D03*
X1326189Y1085205D03*
X1329163Y1082501D03*
X1329189Y1085205D03*
X1326189Y1088205D03*
X1326471Y1091227D03*
X1329189Y1088205D03*
X1323189Y1085205D03*
Y1087705D03*
X1323163Y1082501D03*
X1323021Y1090956D03*
X1337514Y1104335D03*
X1334956Y1105552D03*
X1321069Y1107997D03*
X1323021Y1093956D03*
X1331162Y1104792D03*
X1332669Y1106867D03*
X1321169Y1110597D03*
X1321954Y1113648D03*
X1326254D03*
X1328754D03*
X1323405Y1118801D03*
Y1116101D03*
X1325635Y1172384D03*
Y1162384D03*
Y1164884D03*
Y1167384D03*
Y1169884D03*
X1323135Y1172384D03*
Y1162384D03*
Y1164884D03*
Y1167384D03*
Y1169884D03*
X1334793Y1179421D03*
Y1181921D03*
Y1184421D03*
Y1186921D03*
X1320493Y1186709D03*
Y1184209D03*
Y1181709D03*
Y1179209D03*
X1325635Y1174884D03*
X1323135D03*
X1331643Y1192621D03*
Y1190121D03*
X1327237Y1221428D03*
X1331237D03*
X1335237D03*
X1323237D03*
X1327237Y1237428D03*
Y1233428D03*
Y1229428D03*
Y1225428D03*
X1331237Y1237428D03*
Y1233428D03*
Y1229428D03*
Y1225428D03*
X1335237Y1237428D03*
Y1233428D03*
Y1229428D03*
Y1225428D03*
X1323237Y1237428D03*
Y1233428D03*
Y1229428D03*
Y1225428D03*
X1335237Y1241428D03*
X1323237Y1245428D03*
Y1241428D03*
X1327237Y1245428D03*
Y1241428D03*
X1331237Y1245428D03*
Y1241428D03*
X1335237Y1245428D03*
X1333876Y1257160D03*
Y1260160D03*
X1337687Y-79306D03*
Y-82706D03*
X1336646Y22627D03*
X1336551Y26534D03*
X1340320Y147540D03*
X1344092Y141247D03*
X1351559Y143740D03*
X1348939Y148277D03*
X1348419Y265222D03*
X1340104Y279117D03*
X1344007Y279054D03*
X1337510Y310562D03*
X1347990Y322539D03*
X1341169Y325926D03*
X1346009Y336080D03*
X1346093Y340805D03*
X1349636Y340862D03*
X1346065Y347106D03*
X1338471Y356959D03*
X1337509Y373401D03*
X1349763Y371908D03*
X1342810Y408104D03*
X1345610D03*
X1348410D03*
X1336388Y424939D03*
X1342527Y420375D03*
X1345327D03*
X1348127D03*
X1336388Y427439D03*
X1346443Y431112D03*
X1352008Y435101D03*
X1352271Y442114D03*
X1346613Y440101D03*
X1352251Y447121D03*
X1346248Y452718D03*
X1340820Y452987D03*
X1352259Y452601D03*
X1347846Y461607D03*
X1339846D03*
X1339049Y471334D03*
X1343846Y461607D03*
X1346738Y564492D03*
X1339289Y568461D03*
X1342053Y579339D03*
X1346533Y576780D03*
X1340522Y586133D03*
X1343000Y590458D03*
X1346533Y581898D03*
X1344129Y606914D03*
X1344433Y601201D03*
X1339289Y614961D03*
X1344680Y619085D03*
X1346738Y611192D03*
X1346533Y628398D03*
X1346378Y623734D03*
X1342053Y625839D03*
X1340522Y632633D03*
X1343000Y636958D03*
X1346738Y655492D03*
X1339289Y659461D03*
X1346533Y667780D03*
X1342053Y670339D03*
X1346533Y672898D03*
X1340522Y677133D03*
X1343000Y681458D03*
X1350929Y687043D03*
X1340299Y686243D03*
X1346738Y702492D03*
X1346533Y719898D03*
X1339289Y706461D03*
X1342053Y717339D03*
X1346533Y714780D03*
X1340522Y724133D03*
X1343000Y728458D03*
X1344768Y737675D03*
Y741675D03*
Y745675D03*
Y749675D03*
Y753675D03*
Y761675D03*
Y757675D03*
X1336450Y765675D03*
X1344768Y773675D03*
Y781350D03*
X1345226Y777675D03*
X1341000Y799000D03*
X1345000Y796000D03*
X1341000Y788000D03*
X1345000D03*
X1337000D03*
X1348917Y796000D03*
Y788000D03*
X1352817Y796000D03*
X1349000Y804000D03*
X1351000Y811620D03*
X1347000D03*
X1343000D03*
X1337000Y804000D03*
X1345000D03*
X1341000D03*
X1349976Y829000D03*
X1350000Y825500D03*
X1340000Y900000D03*
X1351500Y903000D03*
Y906500D03*
X1340000Y906000D03*
Y903000D03*
X1351511Y900000D03*
X1350500Y925500D03*
X1338500D03*
X1342500D03*
X1346500D03*
X1353948Y943603D03*
X1345948D03*
X1349848Y936755D03*
X1338500Y930500D03*
X1350500D03*
X1342500D03*
X1346500D03*
X1337514Y988259D03*
X1343465Y1026123D03*
X1340665D03*
X1343465Y1028923D03*
X1340665D03*
X1347552Y1091816D03*
Y1089316D03*
X1345052Y1081816D03*
Y1084316D03*
Y1086816D03*
X1347552D03*
Y1084316D03*
X1350418Y1090288D03*
X1347552Y1081816D03*
X1344241Y1106298D03*
X1348997Y1107997D03*
X1350418Y1093088D03*
X1339234Y1101917D03*
X1339169Y1106897D03*
X1341984Y1110092D03*
X1345650Y1115896D03*
X1348997Y1113797D03*
Y1110897D03*
X1351197Y1112397D03*
X1351097Y1109397D03*
X1345650Y1118396D03*
X1347300Y1128332D03*
X1343725Y1128738D03*
X1343905Y1162384D03*
Y1164884D03*
Y1167384D03*
Y1169884D03*
Y1172384D03*
X1341405D03*
Y1169884D03*
Y1167384D03*
Y1164884D03*
Y1162384D03*
X1350963Y1172384D03*
Y1169884D03*
Y1167384D03*
Y1164884D03*
Y1162384D03*
X1351149Y1158200D03*
X1347423Y1186709D03*
Y1184209D03*
Y1181709D03*
Y1179209D03*
X1343905Y1174884D03*
X1341405D03*
X1350963D03*
X1337108Y1192621D03*
Y1190121D03*
X1345108D03*
Y1192621D03*
X1347237Y1221428D03*
X1343237D03*
X1339237D03*
X1347237Y1237428D03*
Y1233428D03*
Y1229428D03*
X1343237D03*
Y1233428D03*
Y1237428D03*
X1339237D03*
Y1233428D03*
Y1229428D03*
Y1225428D03*
X1347237Y1245428D03*
Y1241428D03*
X1343237D03*
Y1245428D03*
X1339237D03*
Y1241428D03*
X1339876Y1257160D03*
X1342876D03*
X1345876Y1260160D03*
Y1257160D03*
X1348876Y1260160D03*
Y1257160D03*
X1351876Y1260160D03*
Y1257160D03*
X1336876Y1260160D03*
Y1257160D03*
X1342876Y1260160D03*
X1339876D03*
X1360122Y141247D03*
X1364609Y143518D03*
X1363709Y152373D03*
X1366859Y152562D03*
X1363535Y327877D03*
X1366535Y335751D03*
Y339151D03*
X1363535Y331277D03*
Y343625D03*
X1366535Y354899D03*
Y351499D03*
X1363535Y347025D03*
X1360719Y424601D03*
X1352817Y788000D03*
X1367000Y811620D03*
X1365000Y804000D03*
X1355000Y811620D03*
X1363000D03*
X1353000Y804000D03*
X1359000Y811620D03*
X1357000Y804000D03*
X1361000D03*
X1354185Y906498D03*
X1367000Y904500D03*
X1363000Y900500D03*
X1367000D03*
X1354500Y925500D03*
X1366500D03*
X1358500D03*
X1362500D03*
X1365948Y939475D03*
X1357948Y938842D03*
X1361948Y943603D03*
X1369948D03*
X1362500Y930500D03*
X1366500D03*
X1354500D03*
X1358500D03*
X1364765Y1004766D03*
X1367444Y1003763D03*
X1357765Y1019766D03*
X1361265D03*
X1365049Y1028416D03*
X1365314Y1021793D03*
X1357265Y1026266D03*
Y1034266D03*
X1366265Y1039880D03*
X1369642Y1104335D03*
X1367084Y1105552D03*
X1353197Y1107997D03*
X1363290Y1104792D03*
X1364797Y1106867D03*
X1353297Y1110597D03*
X1354082Y1113648D03*
X1355533Y1116101D03*
Y1118801D03*
X1360882Y1113648D03*
X1358382D03*
X1353463Y1172384D03*
Y1169884D03*
Y1167384D03*
Y1164884D03*
Y1162384D03*
X1361723Y1179421D03*
Y1181921D03*
Y1184421D03*
Y1186921D03*
X1353463Y1174884D03*
X1364038Y1190121D03*
Y1192621D03*
X1363876Y1260160D03*
Y1257160D03*
X1354876Y1260160D03*
X1357876D03*
X1360876D03*
Y1257160D03*
X1357876D03*
X1354876D03*
X1366876Y1260160D03*
Y1257160D03*
X1376262Y116594D03*
X1382205Y110784D03*
X1387205D03*
X1376262Y119594D03*
X1386784Y124663D03*
X1376696Y124283D03*
X1381762Y124879D03*
X1375103Y161306D03*
X1372354Y157370D03*
X1384319Y218085D03*
X1381519D03*
X1386846Y249108D03*
X1378227Y248371D03*
X1384265Y320871D03*
Y325371D03*
X1383551Y337808D03*
X1384265Y329871D03*
X1383634Y342766D03*
X1384265Y334371D03*
X1375073Y356871D03*
Y361371D03*
X1383505Y349437D03*
X1384265Y352371D03*
X1372232Y361298D03*
X1383963Y366675D03*
X1377024Y397713D03*
X1375108Y420838D03*
X1375171Y424741D03*
X1375400Y435192D03*
X1375360Y432234D03*
X1383343Y508228D03*
X1383907Y516591D03*
X1383556Y554388D03*
X1378415Y558795D03*
X1383608Y571927D03*
X1378415Y563984D03*
Y569776D03*
X1378957Y584457D03*
X1383000Y584500D03*
X1382997Y581317D03*
X1383425Y590425D03*
X1378415Y605295D03*
X1383608Y618427D03*
X1378415Y610484D03*
Y616276D03*
X1383425Y636925D03*
X1378957Y630957D03*
X1384657Y631620D03*
X1378957Y627988D03*
X1378415Y649795D03*
Y654984D03*
Y660776D03*
X1386289Y672488D03*
X1383425Y681425D03*
X1378957Y675457D03*
X1383000Y675500D03*
X1378415Y696795D03*
Y701984D03*
X1378957Y719488D03*
X1378415Y707776D03*
X1383425Y728425D03*
X1378957Y722457D03*
X1385290Y722400D03*
X1371000Y811620D03*
X1381000Y804000D03*
X1373000D03*
X1369000D03*
X1385360Y811757D03*
X1381428Y812287D03*
X1375193Y811724D03*
X1376708Y901000D03*
X1378500Y925500D03*
X1374369Y925499D03*
X1370500Y925500D03*
X1382500D03*
X1382775Y930281D03*
X1373948Y940103D03*
X1374500Y930500D03*
X1370500D03*
X1378500D03*
X1381519Y996280D03*
X1383162Y991829D03*
X1373534Y1012325D03*
Y1004680D03*
X1378938Y1000586D03*
X1374034Y1015825D03*
X1374059Y1018860D03*
X1376359Y1016825D03*
X1378559Y1038534D03*
X1384784Y1033783D03*
X1385929Y1038665D03*
X1373874Y1032266D03*
Y1035716D03*
X1385152Y1046591D03*
X1377087Y1106365D03*
X1371362Y1101917D03*
X1371297Y1106897D03*
X1382456Y1107997D03*
X1374112Y1110092D03*
X1377778Y1115896D03*
X1384656Y1112397D03*
X1382456Y1110897D03*
Y1113797D03*
X1384556Y1109397D03*
X1377778Y1118396D03*
X1369233Y1169884D03*
Y1172384D03*
X1371733D03*
Y1169884D03*
Y1167384D03*
Y1164884D03*
Y1162384D03*
X1369233D03*
Y1164884D03*
Y1167384D03*
X1376861Y1160834D03*
X1383024D03*
X1369233Y1174884D03*
X1371733D03*
X1375459Y1197471D03*
Y1193471D03*
X1379959Y1197471D03*
Y1193471D03*
X1397848Y97667D03*
X1388231Y116594D03*
X1393504Y102495D03*
X1388231Y119594D03*
X1391765Y125107D03*
X1393238Y142862D03*
X1400379Y143762D03*
X1394279Y148717D03*
X1388128Y138838D03*
X1399327Y195176D03*
X1396827D03*
X1400845Y199248D03*
Y201748D03*
X1398681Y206806D03*
X1401181D03*
X1399408Y210509D03*
X1396908D03*
X1390832Y216970D03*
Y219470D03*
X1390898Y226320D03*
X1390832Y221970D03*
X1388119Y216385D03*
X1402855Y227824D03*
X1398600Y230556D03*
X1393859Y228646D03*
X1397585Y242078D03*
X1392816Y232971D03*
X1389466Y244571D03*
X1396809Y256394D03*
X1395726Y320529D03*
X1395568Y325529D03*
X1395726Y330529D03*
X1395736Y335529D03*
X1395726Y340529D03*
Y345529D03*
Y360529D03*
Y350529D03*
Y355529D03*
X1391896Y365529D03*
X1399884Y367165D03*
X1387847Y366710D03*
X1400231Y390256D03*
X1396528Y397454D03*
X1399571Y397418D03*
X1393575Y397310D03*
X1390553Y397436D03*
X1391623Y409900D03*
X1387125Y417312D03*
X1393177Y424804D03*
X1389557Y424678D03*
X1389431Y421593D03*
X1390271Y417578D03*
X1393208Y428109D03*
X1393336Y431100D03*
X1403085Y460565D03*
X1393944Y507856D03*
X1394044Y510990D03*
X1397079Y527726D03*
Y548726D03*
Y544726D03*
X1395605Y556217D03*
X1390741Y561000D03*
Y569000D03*
Y565000D03*
X1391087Y581317D03*
X1398946Y621311D03*
X1390741Y611500D03*
Y607500D03*
Y615500D03*
X1391586Y623692D03*
X1398946Y629311D03*
Y625311D03*
X1397000Y652000D03*
Y656000D03*
Y660000D03*
Y699000D03*
Y707000D03*
Y703000D03*
X1391040Y812027D03*
X1386335Y803704D03*
X1390537Y803679D03*
X1394537Y803653D03*
X1398530Y811717D03*
X1402417Y811692D03*
X1400069Y827515D03*
X1401300Y820485D03*
X1395955Y832697D03*
X1402000Y840000D03*
Y848000D03*
X1399872Y845109D03*
X1402000Y864000D03*
X1391316Y857849D03*
X1388488Y857822D03*
X1402000Y876000D03*
X1390182Y873460D03*
X1387582Y873487D03*
X1402000Y884000D03*
Y892000D03*
X1388479Y892923D03*
X1385979D03*
X1390979D03*
X1402000Y900000D03*
X1387520Y905307D03*
X1387753Y912629D03*
X1394891Y914783D03*
X1402187Y908270D03*
X1387504Y899931D03*
X1390541Y900086D03*
X1388980Y921075D03*
X1401000Y925789D03*
X1396869Y958707D03*
X1402064Y965913D03*
X1389192Y992568D03*
X1398854Y987277D03*
X1394885Y999941D03*
X1392031Y1004375D03*
X1385732Y1029482D03*
X1389762Y1043055D03*
X1387813Y1030952D03*
X1399807Y1036155D03*
X1399852Y1039779D03*
X1388523Y1090090D03*
X1392691Y1089224D03*
X1392086Y1092743D03*
X1392691Y1086724D03*
Y1084224D03*
Y1081724D03*
X1390191D03*
Y1084224D03*
Y1086724D03*
X1403101Y1104335D03*
X1400543Y1105552D03*
X1396749Y1104792D03*
X1388451Y1093048D03*
X1386656Y1107997D03*
X1398256Y1106867D03*
X1386756Y1110597D03*
X1394341Y1113648D03*
X1388992Y1118801D03*
Y1116101D03*
X1387541Y1113648D03*
X1391841D03*
X1388722Y1162384D03*
Y1164884D03*
Y1167384D03*
Y1169884D03*
Y1172384D03*
X1391222Y1162384D03*
Y1164884D03*
Y1167384D03*
Y1169884D03*
Y1172384D03*
X1388722Y1174884D03*
X1391222D03*
X1393695Y1186709D03*
Y1184209D03*
Y1181709D03*
Y1179209D03*
X1391380Y1190121D03*
Y1192621D03*
X1385821Y1260160D03*
X1391821Y1257160D03*
X1394821D03*
X1385821D03*
X1388821D03*
X1397821Y1260160D03*
Y1257160D03*
X1400821Y1260160D03*
Y1257160D03*
X1388821Y1260160D03*
X1394821D03*
X1391821D03*
X1385052Y1303139D03*
X1389052D03*
X1406308Y103411D03*
X1406702Y97667D03*
X1417498Y90650D03*
X1417248Y95236D03*
X1402098Y95111D03*
X1406467Y106561D03*
X1403845Y199248D03*
X1401827Y195176D03*
X1404327D03*
X1403845Y202048D03*
X1407445Y230117D03*
X1403461Y238714D03*
X1402942Y246874D03*
X1405162Y244297D03*
X1402921Y322403D03*
X1409830Y347649D03*
X1404690Y362209D03*
X1416912Y386903D03*
X1408854Y381207D03*
X1416470Y381397D03*
X1402968Y390177D03*
X1414369Y398056D03*
X1408254Y398041D03*
X1407844Y411033D03*
X1415610Y417644D03*
X1415674Y421278D03*
X1417856Y448419D03*
X1414903Y469905D03*
X1410903Y470419D03*
Y461919D03*
X1418903Y461419D03*
X1411269Y481467D03*
X1415623Y492268D03*
X1415823Y482165D03*
X1416061Y504825D03*
X1413561D03*
X1411061D03*
X1415064Y500202D03*
X1406910Y495982D03*
X1416413Y495649D03*
X1406910Y491982D03*
X1416002Y517401D03*
X1413502D03*
X1411002D03*
X1416553Y522569D03*
Y525369D03*
X1415168Y531882D03*
X1412668D03*
X1409618Y531948D03*
X1401438Y534211D03*
X1405992Y534909D03*
X1405619Y541135D03*
X1405685Y546553D03*
X1405708Y552726D03*
X1415103Y555194D03*
Y563194D03*
Y571194D03*
X1416660Y581222D03*
Y591215D03*
X1401383Y611071D03*
X1416832Y610562D03*
Y607762D03*
X1411622Y610548D03*
X1407566Y622285D03*
X1407754Y616905D03*
X1418439Y633736D03*
X1407952Y633724D03*
X1413432Y633716D03*
X1407835Y627713D03*
X1405229Y652028D03*
X1405000Y660000D03*
X1410000Y685000D03*
Y681000D03*
X1404500Y675000D03*
X1410000Y701000D03*
Y697000D03*
X1418000Y696000D03*
Y701000D03*
X1410000Y709000D03*
Y713000D03*
X1405000Y707000D03*
Y703000D03*
X1418000Y717000D03*
X1410000D03*
X1404500Y722000D03*
X1410000Y729000D03*
Y725000D03*
X1418000Y724000D03*
Y729000D03*
X1404249Y735858D03*
X1410000Y745000D03*
Y741000D03*
X1418000Y740000D03*
Y745000D03*
X1407482Y750853D03*
X1410000Y757000D03*
Y753000D03*
Y761000D03*
X1418000D03*
X1406867Y783273D03*
X1409115Y773520D03*
X1414597Y792375D03*
X1406483Y811717D03*
X1413500Y832000D03*
Y828000D03*
X1413449Y823934D03*
X1405402Y819917D03*
X1405500Y844000D03*
Y836000D03*
X1413500Y848000D03*
Y840000D03*
Y836000D03*
Y844000D03*
X1405500Y860000D03*
X1413500Y864000D03*
Y860000D03*
Y856000D03*
Y852000D03*
X1405500Y880000D03*
Y868000D03*
X1413500Y876000D03*
X1417797Y879501D03*
X1413500Y872000D03*
Y868000D03*
X1405500Y888000D03*
Y896000D03*
X1417081D03*
X1413500Y892000D03*
Y884000D03*
Y888000D03*
X1413733Y911137D03*
X1412376Y907848D03*
X1414876D03*
X1417376D03*
X1409876D03*
X1405500Y904000D03*
X1404760Y915186D03*
X1413500Y904000D03*
Y900000D03*
X1417284Y911009D03*
X1416802Y936845D03*
X1416244Y942285D03*
X1419337D03*
X1405214Y965074D03*
X1419446Y977192D03*
X1416618Y992307D03*
X1401265Y989465D03*
X1407265D03*
X1414143Y985486D03*
X1412698Y997590D03*
X1412609Y1008766D03*
X1412759Y1016266D03*
X1402215Y1020440D03*
X1414851Y1058097D03*
X1412351D03*
X1407351D03*
X1409851D03*
X1417351D03*
X1414851Y1060697D03*
X1412351D03*
X1407351D03*
X1409851D03*
X1417351D03*
X1405677Y1086796D03*
X1408177D03*
X1410677D03*
X1413177D03*
X1415677D03*
Y1084296D03*
X1413177D03*
X1410677D03*
X1408177D03*
X1405677D03*
X1416005Y1090288D03*
X1410546Y1106298D03*
X1404821Y1101917D03*
X1404756Y1106897D03*
X1416005Y1093088D03*
X1414584Y1107997D03*
X1411237Y1115896D03*
X1407571Y1110092D03*
X1414584Y1113797D03*
X1416784Y1112397D03*
X1414584Y1110897D03*
X1416684Y1109397D03*
X1411237Y1118396D03*
X1409425Y1129238D03*
X1413177Y1128894D03*
X1409492Y1167384D03*
Y1169884D03*
Y1172384D03*
X1406992D03*
Y1169884D03*
X1416550Y1162384D03*
Y1164884D03*
Y1167384D03*
Y1169884D03*
Y1172384D03*
X1406992Y1167384D03*
Y1164884D03*
Y1162384D03*
X1409492D03*
Y1164884D03*
X1416736Y1158200D03*
X1416550Y1174884D03*
X1409492D03*
X1406992D03*
X1407995Y1179421D03*
Y1181921D03*
Y1184421D03*
Y1186921D03*
X1410310Y1192621D03*
Y1190121D03*
X1404845D03*
Y1192621D03*
X1408736Y1222194D03*
X1412736D03*
X1416736D03*
X1408736Y1238194D03*
Y1234194D03*
Y1230194D03*
Y1226194D03*
X1412736Y1238194D03*
Y1234194D03*
Y1230194D03*
Y1226194D03*
X1416736Y1238194D03*
Y1234194D03*
Y1230194D03*
Y1226194D03*
X1412736Y1246194D03*
Y1242194D03*
X1416736Y1246194D03*
Y1242194D03*
X1408736D03*
Y1246194D03*
X1409821Y1260160D03*
X1412821D03*
Y1257160D03*
X1409821D03*
X1406821D03*
X1403821D03*
X1415821Y1260160D03*
Y1257160D03*
X1403821Y1260160D03*
X1406821D03*
X1417711Y1301729D03*
X1410817Y1305417D03*
X1407825Y1426975D03*
X1408536Y1536570D03*
X1407747Y1549054D03*
X1408044Y1559306D03*
X1407255Y1571732D03*
X1422810Y90615D03*
X1427131Y99961D03*
X1427181Y95236D03*
X1425993Y212978D03*
Y207978D03*
Y210478D03*
Y215478D03*
X1429322Y264180D03*
X1431822D03*
X1429247Y258880D03*
X1434166Y325361D03*
X1434164Y339232D03*
X1434038Y334114D03*
X1435818Y352361D03*
X1421005Y407616D03*
X1417903Y439919D03*
X1434997Y442603D03*
X1427117Y443071D03*
X1423427Y456839D03*
X1425927D03*
X1423427Y454339D03*
X1425927D03*
X1432414Y459371D03*
X1423427Y459339D03*
X1425927D03*
X1418903Y469905D03*
X1431484Y470045D03*
X1427484Y462004D03*
X1422499Y485138D03*
X1419650Y485128D03*
X1426384Y478625D03*
X1428084Y482425D03*
X1427499Y485138D03*
X1424999D03*
X1426384Y476125D03*
X1418253Y529169D03*
X1417668Y531882D03*
X1424129Y537658D03*
X1427832Y539731D03*
X1424129Y540458D03*
X1432590Y544895D03*
X1435390D03*
X1427832Y542231D03*
X1432890Y541895D03*
X1417903Y555194D03*
Y563194D03*
Y571194D03*
X1422260Y581222D03*
X1419460D03*
X1435119Y590801D03*
X1422260Y591215D03*
X1419460D03*
X1431000Y591000D03*
X1434944Y597130D03*
X1433114Y620653D03*
Y617853D03*
X1419632Y607762D03*
X1422432D03*
X1425232Y610562D03*
Y607762D03*
X1422432Y610562D03*
X1419632D03*
X1430944Y605443D03*
X1420452Y628078D03*
X1430175Y627852D03*
X1425452Y633473D03*
X1430481Y658153D03*
X1433529Y660564D03*
X1426615Y674112D03*
X1429000Y685000D03*
X1418000D03*
Y681000D03*
X1425909Y691120D03*
X1433464Y692658D03*
X1418000Y689000D03*
X1433053Y701839D03*
X1426000Y717000D03*
X1418000Y705000D03*
X1431522Y708633D03*
X1434000Y712958D03*
X1430289Y734961D03*
X1418000Y733000D03*
X1417969Y720894D03*
X1429000Y729000D03*
X1434000Y751958D03*
X1433153Y745839D03*
X1427000Y766500D03*
X1426000Y761000D03*
X1435000Y765500D03*
X1434000Y756958D03*
X1418023Y765343D03*
X1427000Y781834D03*
Y770500D03*
X1435000D03*
X1427000Y794500D03*
X1435000Y802500D03*
X1427000Y810500D03*
Y814500D03*
X1435000D03*
Y809500D03*
X1427000Y802500D03*
Y830500D03*
Y826500D03*
X1434975Y830500D03*
X1435000Y825500D03*
X1427000Y842500D03*
Y838500D03*
X1435000Y846500D03*
X1427000D03*
X1435043Y874694D03*
X1435082Y869475D03*
X1423190Y905295D03*
X1429059Y908579D03*
X1426085Y910281D03*
X1429907Y936998D03*
X1424897Y936777D03*
X1435516Y936000D03*
X1420699Y958452D03*
X1430839Y965546D03*
X1420740Y1008766D03*
X1428740Y1000766D03*
X1420740Y996766D03*
X1428864D03*
X1420740Y1012266D03*
X1428740Y1016266D03*
X1428823Y1020266D03*
X1435229Y1104335D03*
X1432671Y1105552D03*
X1428877Y1104792D03*
X1418784Y1107997D03*
X1430384Y1106867D03*
X1418884Y1110597D03*
X1421120Y1116101D03*
Y1118801D03*
X1426469Y1113648D03*
X1423969D03*
X1419669D03*
X1419050Y1162384D03*
Y1164884D03*
Y1167384D03*
Y1169884D03*
Y1172384D03*
Y1174884D03*
X1420625Y1186709D03*
Y1184209D03*
Y1181709D03*
Y1179209D03*
X1418310Y1192621D03*
Y1190121D03*
X1420736Y1222194D03*
X1424736D03*
X1428736D03*
X1432736D03*
X1420736Y1238194D03*
Y1234194D03*
Y1230194D03*
Y1226194D03*
X1424736Y1238194D03*
Y1234194D03*
Y1230194D03*
Y1226194D03*
X1428736Y1238194D03*
Y1234194D03*
Y1230194D03*
Y1226194D03*
X1432736Y1234194D03*
Y1230194D03*
Y1226194D03*
X1420736Y1246194D03*
Y1242194D03*
X1424736Y1246194D03*
Y1242194D03*
X1428736Y1246194D03*
Y1242194D03*
X1421821Y1257160D03*
X1418821D03*
Y1260160D03*
X1421821D03*
X1431080Y1301702D03*
X1421238Y1301712D03*
X1428009Y1301760D03*
X1424732Y1301603D03*
X1432258Y1414600D03*
X1430374Y1492474D03*
X1420877Y1494706D03*
X1421964Y1502813D03*
X1423930Y1520364D03*
X1429587Y1527450D03*
X1433405Y1546001D03*
X1432913Y1568679D03*
X1449685Y34228D03*
X1436045Y77393D03*
Y74793D03*
Y85193D03*
Y82593D03*
Y79993D03*
X1444370Y98551D03*
X1436089Y92874D03*
X1447920Y103783D03*
X1438116Y107649D03*
Y104249D03*
X1442682Y147540D03*
X1446454Y141247D03*
X1451301Y148277D03*
X1435138Y162368D03*
X1437738D03*
X1444838Y162793D03*
Y165393D03*
Y170493D03*
Y167993D03*
X1451762Y177616D03*
X1449841Y181009D03*
X1447046Y181366D03*
X1443835Y181426D03*
X1444043Y184221D03*
X1446660Y184012D03*
X1448079Y211359D03*
Y213859D03*
X1436449Y213213D03*
Y210713D03*
X1440521Y211695D03*
X1443021D03*
X1440521Y208695D03*
X1443321D03*
X1436449Y208213D03*
Y215713D03*
X1451785Y265896D03*
X1446698Y265701D03*
X1441016Y267526D03*
Y270026D03*
X1443516D03*
X1438216D03*
X1443516Y267526D03*
X1438216D03*
X1448333Y281716D03*
X1449060Y329861D03*
X1448948Y326448D03*
X1449060Y320861D03*
X1438829Y329861D03*
X1437064Y320861D03*
X1448822Y345324D03*
X1448734Y332910D03*
X1448500Y340575D03*
X1439712Y336673D03*
X1440420Y346833D03*
X1449060Y356861D03*
X1441180Y354909D03*
X1448572Y349441D03*
X1449060Y352361D03*
X1447502Y360785D03*
X1434697Y347125D03*
X1439719Y350387D03*
X1443041Y363648D03*
X1434608Y362584D03*
X1438768Y371655D03*
X1442633Y371502D03*
X1445906Y366030D03*
X1440523Y382747D03*
X1435424Y430361D03*
X1440390Y456652D03*
X1442890D03*
Y459152D03*
Y461652D03*
X1440390Y459152D03*
Y461652D03*
X1436930Y461818D03*
X1433960Y491214D03*
X1449293Y491133D03*
X1442721Y495151D03*
X1437663Y492987D03*
X1442421Y498151D03*
X1433960Y493714D03*
X1437663Y495487D03*
X1445221Y498151D03*
X1449293Y493633D03*
Y496133D03*
Y498633D03*
X1445221Y495151D03*
X1439462Y537877D03*
X1449393Y553297D03*
Y555897D03*
X1446988Y548418D03*
X1439462Y540377D03*
X1435390Y541895D03*
X1444488Y548418D03*
X1439488D03*
X1441988D03*
X1439462Y542877D03*
Y545377D03*
X1449393Y558497D03*
Y566797D03*
Y563697D03*
Y561097D03*
X1443388Y570686D03*
X1446183Y570478D03*
X1435668Y582747D03*
X1446600Y576484D03*
X1446243Y573689D03*
X1443597Y573303D03*
X1449993Y578405D03*
X1438944Y597232D03*
X1443775Y596089D03*
X1448994Y596782D03*
X1440930Y613913D03*
Y616713D03*
Y619513D03*
X1434944Y605443D03*
X1438944Y605637D03*
X1437790Y625013D03*
X1435952Y642184D03*
X1446323Y673183D03*
X1437738Y686992D03*
X1448991Y694392D03*
X1451976Y693844D03*
X1437533Y704398D03*
Y699280D03*
X1438930Y716363D03*
X1446860Y730735D03*
X1446538Y719548D03*
X1437738Y730992D03*
X1446717Y735536D03*
X1437533Y743280D03*
Y748398D03*
X1447289Y776461D03*
X1446000Y770500D03*
X1451000Y793458D03*
Y798458D03*
X1450253Y787339D03*
X1443000Y802500D03*
X1447000Y810500D03*
Y818500D03*
X1435000D03*
X1448000Y834500D03*
X1443000Y846500D03*
X1435000Y834500D03*
X1449000Y844500D03*
X1435212Y854042D03*
X1448726Y864400D03*
X1439891Y873821D03*
X1445367Y891888D03*
X1441223Y891957D03*
X1435745Y901500D03*
X1443231Y899006D03*
X1439103Y898564D03*
X1447261Y898571D03*
X1446022Y927000D03*
X1448137Y949440D03*
X1439031Y957683D03*
X1441088Y976409D03*
X1433996Y981437D03*
X1440700Y981763D03*
X1435669Y1005366D03*
X1440869Y1010256D03*
X1435197Y1028372D03*
X1442674Y1106365D03*
X1436949Y1101917D03*
X1436884Y1106897D03*
X1439699Y1110092D03*
X1443365Y1115896D03*
Y1118396D03*
X1442448Y1160834D03*
X1434820Y1162384D03*
Y1164884D03*
Y1167384D03*
Y1169884D03*
Y1172384D03*
X1437320D03*
Y1169884D03*
Y1167384D03*
Y1164884D03*
Y1162384D03*
X1434925Y1179421D03*
Y1181921D03*
Y1184421D03*
Y1186921D03*
X1434820Y1174884D03*
X1437320D03*
X1437240Y1192621D03*
Y1190121D03*
X1436736Y1222194D03*
Y1226194D03*
X1443660Y1310698D03*
X1440260D03*
X1446817Y1335846D03*
X1441200Y1338700D03*
X1435900Y1340800D03*
X1439258Y1414600D03*
X1446135Y1530876D03*
X1443103Y1527201D03*
X1441145Y1540415D03*
X1440153Y1563093D03*
X1443769Y1562173D03*
X1452717Y34052D03*
X1457347Y31518D03*
X1457829Y26425D03*
X1455013Y43128D03*
X1460466Y76587D03*
Y72615D03*
X1461905Y100625D03*
X1454924Y97475D03*
X1454855Y106186D03*
X1462484Y141247D03*
X1466971Y143518D03*
X1453921Y143740D03*
X1466071Y152373D03*
X1455016Y168697D03*
X1452343Y172190D03*
X1464628Y171523D03*
X1456104Y191941D03*
X1464158Y192490D03*
X1458113Y206767D03*
X1463113D03*
X1460613D03*
X1451782Y213132D03*
X1463243Y221708D03*
X1460743D03*
X1458243D03*
X1457658Y224421D03*
X1459358Y231021D03*
Y228221D03*
X1451782Y215632D03*
X1459909Y236189D03*
X1464909D03*
X1462409D03*
X1459850Y248765D03*
X1464850D03*
X1462350D03*
X1452026Y256303D03*
X1456801Y266114D03*
X1460047Y270695D03*
Y268195D03*
X1462547Y270695D03*
Y268195D03*
X1465347Y270695D03*
Y268195D03*
X1454274Y281982D03*
X1459060Y320861D03*
Y325361D03*
Y329861D03*
Y338861D03*
Y343361D03*
Y334361D03*
Y347861D03*
Y352361D03*
X1459873Y391705D03*
X1463145Y391579D03*
X1458214Y406231D03*
X1464536Y433114D03*
X1458912Y581659D03*
X1455419Y578986D03*
X1454944Y596729D03*
X1453000Y614158D03*
Y616958D03*
Y619758D03*
X1450944Y605443D03*
X1458944D03*
X1461474Y655807D03*
X1455761Y683448D03*
X1468372Y673812D03*
X1460111Y683536D03*
X1451428Y673252D03*
X1460816Y727964D03*
X1455291Y759656D03*
X1455159Y763714D03*
X1454504Y777575D03*
X1454533Y784780D03*
X1454738Y772492D03*
X1454533Y789898D03*
X1453102Y821102D03*
X1454541Y831339D03*
X1453102Y826500D03*
X1452619Y836457D03*
X1461113Y871389D03*
X1457218Y888764D03*
X1452641Y888033D03*
X1451286Y898549D03*
X1462500Y905295D03*
X1461888Y936055D03*
X1462000Y957000D03*
X1458202Y960288D03*
X1457937Y966712D03*
X1457352Y976277D03*
X1459519Y989432D03*
X1467096Y988813D03*
X1456966Y998507D03*
X1458892Y1007522D03*
X1465658Y1006648D03*
X1465846Y1023900D03*
X1463025Y1018307D03*
X1459267Y1013678D03*
X1456280Y1023405D03*
X1459683Y1028377D03*
X1481905Y-79278D03*
Y-82678D03*
X1479972Y40780D03*
X1472146Y55513D03*
X1468371Y68581D03*
X1474746Y60513D03*
X1477606Y60438D03*
X1468384Y80581D03*
X1474874Y85731D03*
X1483287Y86012D03*
X1472514Y88801D03*
X1478428Y86046D03*
X1475431Y94351D03*
X1479380Y94279D03*
X1470567Y103621D03*
X1478624Y116594D03*
X1466278Y112083D03*
X1484567Y110784D03*
X1478624Y119594D03*
X1479058Y124283D03*
X1484124Y124879D03*
X1477465Y161306D03*
X1469221Y152562D03*
X1474716Y157370D03*
X1478800Y168665D03*
Y176665D03*
X1469913Y183834D03*
X1470023Y178560D03*
X1470086Y172665D03*
X1470899Y186629D03*
X1469433Y190185D03*
X1478800Y192665D03*
Y196665D03*
X1470203Y200864D03*
X1478913Y186778D03*
X1478832Y204864D03*
X1470292Y212455D03*
X1470226Y207037D03*
X1478832Y208864D03*
X1467593Y221642D03*
X1474473Y219379D03*
X1475101Y228631D03*
X1480589Y248371D03*
X1471507Y265897D03*
X1469007D03*
X1477549Y327200D03*
Y322700D03*
Y345200D03*
Y340700D03*
Y331700D03*
Y358700D03*
Y349700D03*
Y354200D03*
X1480702Y368516D03*
X1468309Y408861D03*
X1475236Y412482D03*
X1466231Y423671D03*
X1469538Y416795D03*
X1466653Y428582D03*
X1471375Y433115D03*
X1477597Y682997D03*
X1475264Y680933D03*
X1474713Y685247D03*
X1479297Y693630D03*
X1476794Y691447D03*
X1476716Y704398D03*
X1479500Y689630D03*
Y697630D03*
X1474425Y712925D03*
X1479759Y720885D03*
X1469957Y706957D03*
X1474000Y707000D03*
X1479794Y709388D03*
X1472000Y727500D03*
X1469116Y719055D03*
X1480000Y731500D03*
X1479759Y743500D03*
X1479657Y735500D03*
X1469957Y750957D03*
X1476716Y748398D03*
X1480000Y739500D03*
X1471006Y744818D03*
X1470801Y739280D03*
X1474425Y756925D03*
X1479665Y754555D03*
X1474000Y753093D03*
X1476677Y827626D03*
X1473489Y861354D03*
X1474060Y877196D03*
X1473468Y874267D03*
X1482387Y872940D03*
X1474883Y868206D03*
X1473433Y891043D03*
X1473387Y897425D03*
X1482195Y885807D03*
X1470925Y920575D03*
X1480343Y914776D03*
X1480109Y943496D03*
X1480144Y946880D03*
X1479441Y961941D03*
X1480414Y952214D03*
X1476500Y974000D03*
X1482237Y966028D03*
X1479196Y970000D03*
X1480414Y975064D03*
X1475096Y980330D03*
X1471096D03*
X1479096Y988813D03*
X1471296D03*
X1475096D03*
X1483096D03*
X1475062Y1008300D03*
Y1002453D03*
X1482535Y1024254D03*
X1468869Y1018469D03*
X1476230Y1030672D03*
X1473230D03*
X1471374Y1118654D03*
X1474384Y1109564D03*
X1480231D03*
X1474384Y1122164D03*
X1480231D03*
X1474384Y1134764D03*
X1480231D03*
X1474384Y1147364D03*
X1480231D03*
X1474384Y1172564D03*
X1480231D03*
X1474384Y1159964D03*
X1480231D03*
X1474384Y1185164D03*
X1480231D03*
X1483308Y1214372D03*
X1479063Y1218169D03*
X1498621Y19043D03*
X1489556Y17645D03*
X1498621Y31043D03*
Y23043D03*
X1489829Y29424D03*
X1490563Y23043D03*
X1500210Y97667D03*
X1483287Y94374D03*
X1490593Y116594D03*
X1495866Y102495D03*
X1489567Y110784D03*
X1490593Y119594D03*
X1494127Y125107D03*
X1489146Y124663D03*
X1495600Y142862D03*
X1496641Y148717D03*
X1490490Y138838D03*
X1493260Y226320D03*
X1493194Y221970D03*
X1490481Y216385D03*
X1493194Y216970D03*
Y219470D03*
X1486681Y218085D03*
X1483881D03*
X1496221Y228646D03*
X1495178Y232971D03*
X1491828Y244571D03*
X1489208Y249108D03*
X1499171Y256394D03*
X1497446Y295877D03*
X1486860Y327200D03*
X1500659Y330024D03*
X1495605Y322700D03*
X1487318Y318200D03*
X1486360Y322700D03*
Y345200D03*
X1500386Y344642D03*
X1486913Y340327D03*
X1487152Y331272D03*
X1495689Y332534D03*
X1495521Y340700D03*
X1486360Y349700D03*
X1495521Y349681D03*
X1495925Y358700D03*
X1499839Y354001D03*
X1486890Y368576D03*
X1494286Y372699D03*
X1488000Y731500D03*
X1495500Y750500D03*
X1488731Y739500D03*
X1496629Y765000D03*
X1496763Y777000D03*
X1493301Y776911D03*
X1496814Y773000D03*
X1497000Y781000D03*
X1496756Y785000D03*
X1491425Y798425D03*
X1499633Y787794D03*
X1493716Y789898D03*
X1486957Y792457D03*
X1495170Y796670D03*
X1487050Y809413D03*
X1496845Y809000D03*
X1496806Y817000D03*
X1496621Y829000D03*
X1496447Y821000D03*
X1486386Y825296D03*
X1493092Y820444D03*
X1493038Y833898D03*
X1495240Y825000D03*
X1491425Y842425D03*
X1486957Y836457D03*
X1492625Y837324D03*
X1488138Y878339D03*
Y872839D03*
X1482566Y882154D03*
X1494954Y895264D03*
X1484824Y927324D03*
X1487240Y924453D03*
X1497063Y934000D03*
X1496072Y940201D03*
X1483324Y939324D03*
X1482921Y931324D03*
X1485500Y932500D03*
X1497075Y961000D03*
X1487240Y952012D03*
X1496072Y953981D03*
X1495500Y972500D03*
X1489500D03*
X1487096Y988813D03*
X1491096D03*
X1495096D03*
X1499096D03*
X1490235Y1004816D03*
X1487266Y1002046D03*
X1486030Y1016827D03*
X1491877D03*
X1486030Y1029427D03*
X1491877D03*
X1496140Y1105091D03*
X1496185Y1102091D03*
X1496140Y1117691D03*
X1496185Y1114691D03*
Y1127291D03*
X1496140Y1130291D03*
X1496185Y1139891D03*
X1496140Y1155491D03*
Y1142891D03*
X1496185Y1152491D03*
X1496140Y1168091D03*
X1496185Y1165091D03*
X1496140Y1180691D03*
X1496185Y1177691D03*
X1482705Y1200001D03*
X1489793Y1207737D03*
X1497693Y1230407D03*
X1508670Y103411D03*
X1509064Y97667D03*
X1504460Y95111D03*
X1508829Y106561D03*
X1502741Y143762D03*
X1506689Y195176D03*
X1506207Y199248D03*
X1501689Y195176D03*
X1503207Y199248D03*
X1499189Y195176D03*
X1504189D03*
X1506207Y202048D03*
X1503207Y201748D03*
X1499270Y210509D03*
X1501043Y206806D03*
X1501770Y210509D03*
X1503543Y206806D03*
X1509807Y230117D03*
X1500962Y230556D03*
X1505217Y227824D03*
X1505823Y238714D03*
X1499947Y242078D03*
X1505304Y246874D03*
X1507524Y244297D03*
X1503884Y295549D03*
X1501500Y321000D03*
X1501000Y317500D03*
X1501684Y336561D03*
X1516838Y347422D03*
X1515909Y354601D03*
X1516636Y458711D03*
X1513284Y552466D03*
X1504495Y796844D03*
X1510527Y833500D03*
X1504938Y859711D03*
X1500353Y859855D03*
X1500638Y873839D03*
X1512712Y867418D03*
X1502158Y899479D03*
X1510527Y908951D03*
X1513927D03*
X1504208Y909740D03*
X1509274Y921226D03*
X1505337Y921240D03*
X1509500Y937000D03*
Y944138D03*
X1516500Y947500D03*
X1501812Y938397D03*
X1512161Y957541D03*
X1509500Y950500D03*
X1498973Y975443D03*
X1511000Y970500D03*
X1511096Y988813D03*
X1507096D03*
X1503096D03*
X1515096D03*
X1513286Y1012354D03*
X1507831Y1009354D03*
X1507786Y1012354D03*
Y1024954D03*
X1513286D03*
X1507831Y1021954D03*
X1503572Y1034538D03*
X1501640Y1105091D03*
Y1117691D03*
Y1130291D03*
Y1142891D03*
Y1155491D03*
Y1168091D03*
Y1180691D03*
X1508356Y1220068D03*
X1500675Y1227300D03*
X1506807Y1234921D03*
X1507692Y1224472D03*
X1507058Y1229402D03*
X1517261Y-40358D03*
Y-43758D03*
X1525172Y90615D03*
X1519860Y90650D03*
X1529493Y99961D03*
X1529543Y95236D03*
X1519610D03*
X1528355Y210478D03*
Y215478D03*
Y212978D03*
Y207978D03*
X1519321Y378600D03*
Y382600D03*
X1519436Y458711D03*
X1521963Y453682D03*
X1520200Y455921D03*
X1518780Y463600D03*
X1519185Y603600D03*
Y619600D03*
Y623600D03*
X1520729Y634190D03*
X1524200Y646098D03*
X1518517Y878898D03*
X1518452Y873780D03*
X1525022Y909558D03*
X1522881Y901034D03*
X1522954Y897951D03*
X1521085Y921094D03*
X1515179D03*
X1527267Y932647D03*
X1522209Y937846D03*
X1521500Y947500D03*
X1528500Y947612D03*
X1529128Y952978D03*
X1521085Y957340D03*
X1525583Y968500D03*
X1530767Y972981D03*
X1519863Y977637D03*
X1525005Y974323D03*
X1530594Y979952D03*
X1531096Y988813D03*
X1523096D03*
X1519096D03*
X1527096Y997860D03*
X1526810Y1025090D03*
X1522904Y1021256D03*
X1521939Y1040818D03*
X1522099Y1035521D03*
X1531993Y1056453D03*
X1531961Y1050849D03*
X1524953Y1051037D03*
X1517855Y1053457D03*
X1538407Y85539D03*
Y82939D03*
Y75139D03*
Y80339D03*
Y77739D03*
X1546732Y98551D03*
X1538451Y92874D03*
X1540478Y107649D03*
Y104249D03*
X1545044Y147540D03*
X1540100Y162368D03*
X1537500D03*
X1547200Y162793D03*
Y165393D03*
Y167993D03*
Y170493D03*
X1546197Y181426D03*
X1546405Y184221D03*
X1538811Y213213D03*
Y210713D03*
X1542883Y211695D03*
X1545383D03*
X1542883Y208695D03*
X1545683D03*
X1538811Y208213D03*
Y215713D03*
X1534184Y264180D03*
X1531684D03*
X1531609Y258880D03*
X1549060Y265701D03*
X1545878Y270026D03*
X1543378D03*
X1540578D03*
X1543378Y267526D03*
X1540578D03*
X1545878D03*
X1544736Y305156D03*
X1545583Y316363D03*
X1539140Y320863D03*
X1545636Y325363D03*
X1542797Y329863D03*
X1545846Y334363D03*
X1544951Y343363D03*
X1538133Y354553D03*
X1545434Y352363D03*
X1546183Y541863D03*
Y545263D03*
X1544375Y553407D03*
X1546875D03*
X1544375Y550907D03*
X1546875D03*
X1542704Y572162D03*
X1543946Y569928D03*
X1546293Y570962D03*
X1546036Y568475D03*
X1548080Y910757D03*
X1547644Y903060D03*
X1532067Y1041832D03*
X1531947Y1046212D03*
X1531546Y1062769D03*
X1536909Y1151870D03*
Y1159350D03*
X1540649Y1155610D03*
X1562828Y72615D03*
Y76587D03*
X1564267Y100625D03*
X1557286Y97475D03*
X1557217Y106186D03*
X1550282Y103783D03*
X1548816Y141247D03*
X1564846D03*
X1556283Y143740D03*
X1553663Y148277D03*
X1552203Y181009D03*
X1549408Y181366D03*
X1557378Y168697D03*
X1554705Y172190D03*
X1554124Y177616D03*
X1558466Y191941D03*
X1549022Y184012D03*
X1560475Y206767D03*
X1562975D03*
X1554144Y213132D03*
X1550441Y211359D03*
Y213859D03*
X1560605Y221708D03*
X1560020Y224421D03*
X1563105Y221708D03*
X1561720Y231021D03*
Y228221D03*
X1554144Y215632D03*
X1562271Y236189D03*
X1562212Y248765D03*
X1554388Y256303D03*
X1559163Y266114D03*
X1554147Y265896D03*
X1562409Y268195D03*
Y270695D03*
X1556636Y281982D03*
X1550695Y281716D03*
X1550931Y305158D03*
X1554403Y316363D03*
X1553534Y327337D03*
X1553910Y331798D03*
X1553597Y336601D03*
X1553862Y344867D03*
X1551175Y347283D03*
X1556588Y545528D03*
X1548359Y569426D03*
X1548645Y566929D03*
X1562385Y610400D03*
X1564670Y650122D03*
X1565132Y668153D03*
X1561552Y665455D03*
X1548629Y927836D03*
X1548504Y915689D03*
X1548616Y931602D03*
X1551163Y952888D03*
X1552000Y969850D03*
X1571895Y58013D03*
X1570733Y68581D03*
X1577108Y60513D03*
X1570746Y80581D03*
X1577236Y85731D03*
X1574876Y88801D03*
X1581742Y94279D03*
X1577793Y94351D03*
X1572929Y103621D03*
X1568640Y112083D03*
X1581420Y124283D03*
X1569333Y143518D03*
X1568433Y152373D03*
X1579827Y161306D03*
X1571583Y152562D03*
X1577078Y157370D03*
X1572275Y183834D03*
X1566990Y171523D03*
X1572385Y178560D03*
X1572448Y172665D03*
X1573261Y186629D03*
X1571795Y190185D03*
X1566520Y192490D03*
X1572565Y200864D03*
X1565475Y206767D03*
X1572654Y212455D03*
X1572588Y207037D03*
X1581194Y208864D03*
X1565605Y221708D03*
X1569955Y221642D03*
X1576835Y219379D03*
X1577463Y228631D03*
X1564771Y236189D03*
X1567271D03*
X1564712Y248765D03*
X1567212D03*
X1567709Y270695D03*
X1573869Y265897D03*
X1571369D03*
X1567709Y268195D03*
X1564909Y270695D03*
Y268195D03*
X1563877Y325363D03*
Y316363D03*
X1571625Y344131D03*
X1574775Y333549D03*
X1563877Y329863D03*
Y343363D03*
Y334363D03*
X1578587Y341787D03*
X1578420Y338309D03*
X1574775Y344127D03*
X1563877Y352363D03*
X1575935Y382109D03*
X1577862Y554121D03*
X1575934Y561420D03*
Y558917D03*
X1565323Y577716D03*
X1571755Y577937D03*
X1579760Y595500D03*
X1574760Y606929D03*
X1579260Y604567D03*
X1574720Y618400D03*
X1575001Y612592D03*
X1580418Y610072D03*
X1580354Y616317D03*
X1576297Y627600D03*
X1577077Y631712D03*
X1574880Y645891D03*
X1571888Y649380D03*
X1572141Y662981D03*
X1578000Y678776D03*
X1569434Y677111D03*
X1568872Y686971D03*
X1575192Y707592D03*
X1592187Y-79306D03*
Y-82706D03*
X1582187Y-43786D03*
Y-40386D03*
X1579968Y60438D03*
X1585649Y86012D03*
Y94374D03*
X1580790Y86046D03*
X1592955Y116594D03*
X1580986D03*
X1586929Y110784D03*
X1591929D03*
X1592955Y119594D03*
X1580986D03*
X1596489Y125107D03*
X1586486Y124879D03*
X1591508Y124663D03*
X1592852Y138838D03*
X1581162Y168665D03*
Y176665D03*
Y192665D03*
Y196665D03*
X1581275Y186778D03*
X1581194Y204864D03*
X1586243Y218085D03*
X1595622Y226320D03*
X1592843Y216385D03*
X1595556Y216970D03*
Y219470D03*
Y221970D03*
X1589043Y218085D03*
X1594190Y244571D03*
X1591570Y249108D03*
X1582951Y248371D03*
X1595069Y337361D03*
X1595109Y342663D03*
X1594466Y350984D03*
X1592635Y455911D03*
X1591443Y465332D03*
X1595460Y549800D03*
X1595260Y547075D03*
X1594760Y568000D03*
X1595364Y562800D03*
X1595300Y558800D03*
X1596790Y1442557D03*
X1592643Y1460707D03*
X1593019Y1457557D03*
X1591775Y1473090D03*
X1596038Y1492000D03*
X1591925Y1512075D03*
X1591333Y1501980D03*
X1590748Y1523377D03*
X1602572Y97667D03*
X1611032Y103411D03*
X1611426Y97667D03*
X1606822Y95111D03*
X1598228Y102495D03*
X1611191Y106561D03*
X1597962Y142862D03*
X1605103Y143762D03*
X1599003Y148717D03*
X1604051Y195176D03*
X1605569Y199248D03*
X1601551Y195176D03*
X1606551D03*
X1609051D03*
X1608569Y199248D03*
X1603405Y206806D03*
X1605905D03*
X1601632Y210509D03*
X1604132D03*
X1608569Y202048D03*
X1605569Y201748D03*
X1603324Y230556D03*
X1607579Y227824D03*
X1612169Y230117D03*
X1598583Y228646D03*
X1608185Y238714D03*
X1602309Y242078D03*
X1607666Y246874D03*
X1597540Y232971D03*
X1609886Y244297D03*
X1604677Y253198D03*
X1596691Y287397D03*
X1596197Y293477D03*
X1607947Y332326D03*
X1605966Y343794D03*
X1602138Y351047D03*
X1596253Y375633D03*
X1596534Y379760D03*
X1599527Y396718D03*
X1596760Y530000D03*
X1596260Y540500D03*
X1611316Y685800D03*
X1611027Y722427D03*
X1611327Y735973D03*
X1611627Y780327D03*
X1609500Y776100D03*
X1611873Y795127D03*
X1606190Y803774D03*
X1606709Y819165D03*
X1600333Y1440504D03*
X1596836Y1446488D03*
X1600333Y1449068D03*
X1601968Y1453442D03*
X1597457Y1460662D03*
X1605430Y1468023D03*
X1597039Y1475100D03*
X1599726Y1474990D03*
X1600008Y1488492D03*
X1601500Y1514500D03*
X1608500Y1506000D03*
Y1515000D03*
X1613790Y1531334D03*
X1609348Y1527334D03*
X1613790Y1523334D03*
X1604000Y1519000D03*
X1600732Y1539334D03*
X1609348Y1535334D03*
X1598574Y1543373D03*
X1622222Y90650D03*
X1627534Y90615D03*
X1621972Y95236D03*
X1626147Y351033D03*
X1628636Y422088D03*
X1623955Y442956D03*
X1625772Y438323D03*
X1621596Y456386D03*
X1625938Y445873D03*
X1620385Y465874D03*
X1616622Y546712D03*
Y542712D03*
X1618538Y618288D03*
X1614538D03*
X1627224Y643252D03*
X1613362Y656321D03*
X1621362D03*
X1617362D03*
X1616260Y678462D03*
X1619950Y678519D03*
X1615913Y692245D03*
X1628200Y711417D03*
X1612800Y705900D03*
X1620600D03*
X1620500Y723200D03*
X1628343Y747288D03*
X1616683Y744517D03*
X1620100Y738300D03*
X1624000Y760900D03*
X1612573Y761427D03*
X1628027Y801427D03*
X1613117Y828117D03*
X1640769Y85539D03*
Y82939D03*
Y75139D03*
Y80339D03*
Y77739D03*
X1640813Y92874D03*
X1631905Y95236D03*
X1631855Y99961D03*
X1642840Y104249D03*
Y107649D03*
X1639862Y162368D03*
X1642462D03*
X1641173Y213213D03*
Y210713D03*
Y208213D03*
X1630717Y210478D03*
Y215478D03*
Y212978D03*
Y207978D03*
X1641173Y215713D03*
X1634046Y264180D03*
X1636546D03*
X1633971Y258880D03*
X1642940Y267526D03*
Y270026D03*
X1629553Y329067D03*
X1629302Y334402D03*
X1640030Y335550D03*
X1636561Y343072D03*
X1629514Y331727D03*
X1630691Y347432D03*
X1640197Y374690D03*
X1638340Y379536D03*
X1641615Y379600D03*
X1635170Y442856D03*
X1632439Y452265D03*
X1633225Y458455D03*
X1636271Y453881D03*
X1635185Y446595D03*
X1635283Y728117D03*
X1630327Y774627D03*
X1629927Y787327D03*
X1644552Y871353D03*
X1635176Y886761D03*
X1644718Y909263D03*
X1635000Y919263D03*
X1644325Y942120D03*
X1637771Y952120D03*
X1640581Y1551907D03*
X1649094Y98551D03*
X1659648Y97475D03*
X1652644Y103783D03*
X1659579Y106186D03*
X1647406Y147540D03*
X1651178Y141247D03*
X1658645Y143740D03*
X1656025Y148277D03*
X1649562Y162793D03*
Y165393D03*
Y167993D03*
Y170493D03*
X1656486Y177616D03*
X1654565Y181009D03*
X1648559Y181426D03*
X1651770Y181366D03*
X1659740Y168697D03*
X1657067Y172190D03*
X1660828Y191941D03*
X1651384Y184012D03*
X1648767Y184221D03*
X1647745Y211695D03*
X1645245Y208695D03*
X1648045D03*
X1656506Y213132D03*
X1652803Y211359D03*
Y213859D03*
X1645245Y211695D03*
X1656506Y215632D03*
X1656750Y256303D03*
X1656509Y265896D03*
X1661525Y266114D03*
X1651422Y265701D03*
X1648240Y267526D03*
X1645740D03*
Y270026D03*
X1648240D03*
X1653057Y281716D03*
X1658998Y281982D03*
X1658200Y315039D03*
X1654771Y352088D03*
X1645685Y381500D03*
X1648835Y390500D03*
X1650044Y435158D03*
X1649789Y440489D03*
X1646209Y442606D03*
X1650087Y444841D03*
X1649773Y449961D03*
X1653490Y458572D03*
X1645826Y446606D03*
X1647133Y463479D03*
X1647604Y467367D03*
X1656112Y768669D03*
X1657042Y773604D03*
X1647402Y881460D03*
X1648375Y886766D03*
X1650205Y925911D03*
X1647763Y919268D03*
X1648387Y945554D03*
X1647470Y952125D03*
X1651443Y981515D03*
X1647565Y981432D03*
X1652944Y993796D03*
X1653414Y990590D03*
X1676870Y55513D03*
X1673095Y68581D03*
X1679470Y60513D03*
X1673108Y80581D03*
X1665190Y76587D03*
Y72615D03*
X1679598Y85731D03*
X1677238Y88801D03*
X1675291Y103621D03*
X1666629Y100625D03*
X1671002Y112083D03*
X1667208Y141247D03*
X1671695Y143518D03*
X1670795Y152373D03*
X1673945Y152562D03*
X1674637Y183834D03*
X1669352Y171523D03*
X1674810Y172665D03*
X1674747Y178560D03*
X1675623Y186629D03*
X1674157Y190185D03*
X1668882Y192490D03*
X1667318Y198828D03*
X1674927Y200864D03*
X1664840Y192300D03*
X1662837Y206767D03*
X1667837D03*
X1665337D03*
X1674950Y207037D03*
X1675016Y212455D03*
X1667967Y221708D03*
X1665467D03*
X1664082Y231021D03*
Y228221D03*
X1672317Y221642D03*
X1662967Y221708D03*
X1662382Y224421D03*
X1669633Y236189D03*
X1667133D03*
X1664633D03*
X1667074Y248765D03*
X1664574D03*
X1669574D03*
X1676231Y265897D03*
X1673731D03*
X1670071Y268195D03*
Y270695D03*
X1667271Y268195D03*
X1664771D03*
Y270695D03*
X1667271D03*
X1673203Y328867D03*
X1668979Y339559D03*
X1666860Y353661D03*
X1663650Y353283D03*
X1673723Y353881D03*
X1670323Y353534D03*
X1670260Y377912D03*
X1669260Y391496D03*
X1663618Y393858D03*
X1663780Y384410D03*
X1666959Y382047D03*
X1670260Y386500D03*
X1669260Y409000D03*
X1665260Y398583D03*
X1670348Y397912D03*
X1667260Y403500D03*
X1663713Y440869D03*
Y438269D03*
X1666513Y433069D03*
Y430469D03*
Y435669D03*
Y440869D03*
Y438269D03*
X1663713Y433069D03*
Y430469D03*
Y435669D03*
X1664567Y451677D03*
X1667067D03*
X1664567Y454177D03*
X1667067D03*
X1666271Y460218D03*
Y463618D03*
X1682330Y60438D03*
X1688011Y86012D03*
Y94374D03*
X1683152Y86046D03*
X1680155Y94351D03*
X1684104Y94279D03*
X1683348Y116594D03*
X1694291Y110784D03*
X1689291D03*
X1683348Y119594D03*
X1683782Y124283D03*
X1693870Y124663D03*
X1688848Y124879D03*
X1695214Y138838D03*
X1682189Y161306D03*
X1679440Y157370D03*
X1683524Y168665D03*
Y176665D03*
Y192665D03*
X1683637Y186778D03*
X1683556Y204864D03*
Y208864D03*
X1688605Y218085D03*
X1691405D03*
X1679197Y219379D03*
X1679825Y228631D03*
X1693932Y249108D03*
X1685313Y248371D03*
X1686339Y314890D03*
X1686115Y311740D03*
X1683523Y324518D03*
X1677810Y324466D03*
X1686408Y332584D03*
X1687424Y347937D03*
X1692676Y348015D03*
X1688593Y353470D03*
X1691182Y357016D03*
X1680518Y377912D03*
Y381912D03*
Y397912D03*
X1689920Y539315D03*
X1689236Y550137D03*
X1692028D03*
X1693000Y626912D03*
X1692379Y622912D03*
X1704934Y97667D03*
X1709184Y95111D03*
X1695317Y116594D03*
X1700590Y102495D03*
X1695317Y119594D03*
X1698851Y125107D03*
X1700324Y142862D03*
X1707465Y143762D03*
X1701365Y148717D03*
X1708913Y195176D03*
X1710931Y199248D03*
X1706413Y195176D03*
X1703913D03*
X1707931Y199248D03*
Y201748D03*
X1706494Y210509D03*
X1703994D03*
X1705767Y206806D03*
X1708267D03*
X1697984Y226320D03*
X1695205Y216385D03*
X1697918Y216970D03*
Y219470D03*
Y221970D03*
X1705686Y230556D03*
X1709941Y228747D03*
X1700945Y228646D03*
X1704671Y242078D03*
X1699902Y232971D03*
X1696552Y244571D03*
X1703895Y256394D03*
X1700223Y292141D03*
X1703609Y287320D03*
X1698292Y303962D03*
X1698716Y550065D03*
X1708015Y1142700D03*
X1711333Y1146609D03*
X1706450Y1173065D03*
X1703400Y1174400D03*
X1713394Y103411D03*
X1713788Y97667D03*
X1724584Y90650D03*
X1724334Y95236D03*
X1713553Y106561D03*
X1711413Y195176D03*
X1710931Y202048D03*
X1714531Y230117D03*
X1710547Y238714D03*
X1710028Y246874D03*
X1712248Y244297D03*
X1716755Y326179D03*
X1712226Y344028D03*
X1715930Y340969D03*
X1715590Y331719D03*
X1721746Y377173D03*
X1715228Y387966D03*
X1718851Y391533D03*
X1720571Y385644D03*
X1725746Y385123D03*
X1718318Y399918D03*
X1725154Y406060D03*
X1725415Y416289D03*
Y418889D03*
Y421489D03*
X1721423Y412106D03*
X1716310Y454334D03*
X1724627Y459330D03*
X1724580Y454214D03*
X1724923Y449045D03*
X1724930Y473571D03*
Y476071D03*
Y478571D03*
Y481071D03*
X1710174Y553101D03*
X1717626Y1134729D03*
X1710511Y1138130D03*
X1721008Y1134729D03*
X1723805Y1142666D03*
X1725008Y1134636D03*
X1725680Y1157544D03*
X1724191Y1167768D03*
X1713239Y1176038D03*
X1712526Y1171950D03*
X1728343Y1185205D03*
X1719692Y1187215D03*
X1719385Y1180175D03*
X1712715Y1188500D03*
X1721662Y1201043D03*
X1725658D03*
X1718625Y1199814D03*
X1712542Y1196600D03*
X1720536Y1217228D03*
X1723200Y1219895D03*
X1710825Y1231688D03*
X1712966Y1229841D03*
X1736405Y-79278D03*
Y-82678D03*
X1743175Y92874D03*
X1729896Y90615D03*
X1734267Y95236D03*
X1734217Y99961D03*
X1742224Y162368D03*
X1733079Y207978D03*
Y210478D03*
Y215478D03*
Y212978D03*
X1736408Y264180D03*
X1738908D03*
X1736333Y258880D03*
X1744524Y379429D03*
X1741746Y377173D03*
X1737786D03*
X1729751D03*
X1733746Y385123D03*
X1730746D03*
X1737746D03*
X1741420Y391569D03*
X1739847Y401066D03*
X1729508Y403300D03*
X1728915Y405889D03*
Y408489D03*
Y413689D03*
Y411089D03*
Y416289D03*
Y421489D03*
Y418889D03*
Y424089D03*
X1729302Y432718D03*
Y435518D03*
X1739179Y439318D03*
X1728915Y426689D03*
X1739179Y442118D03*
X1733014Y450091D03*
X1730014D03*
X1727404Y447209D03*
X1730404D03*
X1738824Y456034D03*
Y461034D03*
X1733014Y462060D03*
X1730014D03*
X1734952Y479217D03*
X1737646Y477213D03*
Y479713D03*
X1729002Y477053D03*
X1731502D03*
X1734952Y476717D03*
X1741800Y917900D03*
X1742029Y1116251D03*
X1739508Y1137129D03*
X1729008Y1134729D03*
X1732881D03*
X1739917Y1150087D03*
X1732137Y1157404D03*
X1737393Y1170767D03*
X1729210Y1167768D03*
X1728333Y1178240D03*
X1733052Y1187310D03*
X1737689Y1185238D03*
X1737482Y1180235D03*
X1733662Y1201039D03*
X1729628Y1201043D03*
X1737662Y1200969D03*
X1737781Y1208993D03*
X1726475Y1223170D03*
X1731533Y1228226D03*
X1729322Y1226016D03*
X1743131Y85539D03*
Y82939D03*
Y75139D03*
Y80339D03*
Y77739D03*
X1751456Y98551D03*
X1755006Y103783D03*
X1745202Y104249D03*
Y107649D03*
X1744824Y162368D03*
X1751924Y162793D03*
Y165393D03*
Y167993D03*
Y170493D03*
X1758848Y177616D03*
X1759429Y172190D03*
X1756927Y181009D03*
X1750921Y181426D03*
X1754132Y181366D03*
X1751129Y184221D03*
X1753746Y184012D03*
X1747607Y211695D03*
X1755165Y211359D03*
Y213859D03*
X1750107Y211695D03*
X1747607Y208695D03*
X1750407D03*
X1743535Y208213D03*
Y213213D03*
Y210713D03*
Y215713D03*
X1753784Y265701D03*
X1758871Y265896D03*
X1750602Y267526D03*
X1745302D03*
X1748102D03*
X1745302Y270026D03*
X1748102D03*
X1750602D03*
X1755419Y281716D03*
X1748497Y371060D03*
X1752497Y371076D03*
X1750135Y379088D03*
X1755433Y379028D03*
X1744180Y383966D03*
X1750187Y409539D03*
X1753187D03*
X1750187Y406739D03*
X1753187Y407039D03*
X1752851Y401981D03*
X1755351D03*
X1757124Y398278D03*
X1754624D03*
X1749470Y424067D03*
X1751970D03*
X1756970D03*
X1754470D03*
X1749705Y413611D03*
X1752205D03*
X1757205D03*
X1754705D03*
X1756844Y438293D03*
X1747179Y439318D03*
X1756844Y441093D03*
X1747179Y442118D03*
X1756844Y443893D03*
X1747306Y470001D03*
X1744806D03*
X1756894Y472020D03*
X1756553Y466409D03*
X1756954Y477318D03*
X1745231Y489036D03*
X1743092Y485580D03*
X1745592D03*
X1748092D03*
X1758401Y484882D03*
X1756391Y487382D03*
X1747467Y492836D03*
Y495636D03*
X1756089Y542952D03*
X1750879Y541940D03*
X1754906Y824333D03*
Y820737D03*
X1746897Y879199D03*
X1746884Y884649D03*
X1747900Y900160D03*
X1744900D03*
X1750915Y902055D03*
X1749267Y918413D03*
X1751200Y931100D03*
X1746600Y935100D03*
X1751854Y991297D03*
X1749314Y987904D03*
X1745824Y987058D03*
X1748677Y993986D03*
X1753860Y997271D03*
X1759569Y1021944D03*
X1744529Y1116251D03*
X1758390Y1577905D03*
X1759947Y1599029D03*
X1750685Y1621654D03*
X1767552Y76587D03*
Y72615D03*
X1762010Y97475D03*
X1768991Y100625D03*
X1761941Y106186D03*
X1773364Y112083D03*
X1771714Y171523D03*
X1776999Y183834D03*
X1762102Y168697D03*
X1763190Y191941D03*
X1771244Y192490D03*
X1776519Y190185D03*
X1767202Y192300D03*
X1765199Y206767D03*
X1770199D03*
X1767699D03*
X1758868Y213132D03*
X1765329Y221708D03*
X1770329D03*
X1767829D03*
X1764744Y224421D03*
X1766444Y231021D03*
Y228221D03*
X1774679Y221642D03*
X1758868Y215632D03*
X1771995Y236189D03*
X1769495D03*
X1766995D03*
X1771936Y248765D03*
X1769436D03*
X1766936D03*
X1759112Y256303D03*
X1763887Y266114D03*
X1767133Y270695D03*
X1769633D03*
X1772433Y268195D03*
Y270695D03*
X1769633Y268195D03*
X1767133D03*
X1761360Y281982D03*
X1762997Y377581D03*
X1765497Y379591D03*
X1772513Y387702D03*
X1769713D03*
X1765913Y389402D03*
X1763200Y388817D03*
Y383817D03*
Y386317D03*
X1766837Y438293D03*
Y441093D03*
Y443893D03*
X1768586Y467560D03*
X1764903Y470382D03*
X1764906Y474382D03*
X1776561Y467560D03*
X1777061Y475560D03*
X1768575D03*
X1770135Y490711D03*
X1758957Y543036D03*
X1773789Y927663D03*
X1765664Y923724D03*
X1769064D03*
X1773789Y930663D03*
X1774476Y995049D03*
X1773810Y990821D03*
X1762486Y990260D03*
X1760201Y992475D03*
X1758881Y995633D03*
X1769004Y1019395D03*
X1768844Y1023694D03*
Y1027248D03*
X1771773Y1028829D03*
X1772188Y1428369D03*
X1766313Y1580198D03*
X1761072Y1590719D03*
X1765040Y1599511D03*
X1760422Y1640303D03*
X1768422D03*
X1772422D03*
X1762041Y1631511D03*
X1768422Y1632245D03*
X1773820Y1631238D03*
X1779232Y55513D03*
X1775457Y68581D03*
X1785246Y60660D03*
X1781832Y60513D03*
X1775470Y80581D03*
X1781960Y85731D03*
X1790712Y81713D03*
X1790664Y71908D03*
X1779600Y88801D03*
X1790373Y94663D03*
X1786466Y85923D03*
Y94279D03*
X1782517Y94351D03*
X1777653Y103621D03*
X1785886Y168665D03*
Y176665D03*
X1777172Y172665D03*
X1777109Y178560D03*
X1777985Y186629D03*
X1785779Y192665D03*
X1785886Y196665D03*
X1777289Y200864D03*
X1785999Y186778D03*
X1785918Y204864D03*
X1777378Y212455D03*
X1777312Y207037D03*
X1785918Y208864D03*
X1781559Y219379D03*
X1782187Y228631D03*
X1778593Y265897D03*
X1776093D03*
X1787674Y303130D03*
X1777681Y387151D03*
Y382151D03*
Y384651D03*
X1786184Y435321D03*
Y438121D03*
X1783384Y435321D03*
Y438121D03*
X1786184Y440921D03*
X1783384D03*
X1786184Y443721D03*
X1783384D03*
X1786170Y448931D03*
X1792527Y452799D03*
X1786693Y459170D03*
X1790061Y474513D03*
X1779404Y826570D03*
X1791041Y818795D03*
X1780016Y874400D03*
X1775904Y924546D03*
X1778047Y916120D03*
X1789537Y930498D03*
X1780158Y953295D03*
X1785758Y956095D03*
Y953295D03*
X1782958D03*
Y956095D03*
X1780158D03*
X1789363Y969160D03*
X1782563Y979660D03*
X1785663D03*
X1779363D03*
X1786863Y985060D03*
X1779143Y995203D03*
X1779033Y1023432D03*
X1786740Y1019237D03*
X1780802Y1019474D03*
X1774863Y1019237D03*
X1774844Y1023694D03*
X1783844D03*
X1786844Y1027248D03*
X1780844D03*
X1774844D03*
X1789844Y1023694D03*
X1775998Y1074707D03*
Y1072207D03*
X1781198Y1074707D03*
X1778598D03*
X1783798D03*
Y1072207D03*
X1778598D03*
X1781198D03*
X1790736Y1072090D03*
Y1074590D03*
X1780326Y1089851D03*
X1777726D03*
X1782926D03*
Y1092351D03*
X1777726D03*
X1780326D03*
X1775126Y1089851D03*
Y1092351D03*
X1790639Y1082585D03*
X1790572Y1085152D03*
X1780662Y1108413D03*
X1783262D03*
X1778062D03*
X1775462D03*
X1785321Y1121122D03*
X1787921D03*
X1790521D03*
X1780566Y1111038D03*
X1783166D03*
X1777966D03*
X1775366D03*
X1790521Y1130822D03*
X1781874Y1139822D03*
X1787921Y1130822D03*
X1785321D03*
X1784374Y1139822D03*
X1781802Y1147822D03*
X1784302D03*
X1783278Y1208140D03*
X1778227Y1438099D03*
X1786091Y1443715D03*
X1787745Y1437765D03*
X1783178Y1437550D03*
X1778104Y1470289D03*
X1801761Y-43888D03*
Y-40488D03*
X1791088Y77296D03*
X1804758Y294429D03*
X1793524Y303343D03*
X1805196Y300952D03*
X1799897Y408104D03*
X1802697D03*
X1805497D03*
X1793475Y424939D03*
X1799614Y420375D03*
X1802414D03*
X1805214D03*
X1793475Y427439D03*
X1809095Y435101D03*
X1803700Y440101D03*
X1803530Y431112D03*
X1809358Y442114D03*
X1803335Y452718D03*
X1809346Y452601D03*
X1797907Y452987D03*
X1809338Y447121D03*
X1804933Y461607D03*
X1796933D03*
X1796136Y471334D03*
X1800933Y461607D03*
X1802000Y892447D03*
X1797365Y930761D03*
X1793474Y930374D03*
X1805463Y969260D03*
X1801963Y969160D03*
X1802363Y989660D03*
X1803351Y1027471D03*
X1805188Y1019078D03*
X1799646Y1018999D03*
X1793470Y1018762D03*
X1801844Y1023694D03*
X1795844D03*
X1798844Y1027248D03*
X1792844D03*
X1795936Y1072090D03*
X1793336D03*
X1798536D03*
Y1074590D03*
X1793336D03*
X1795936D03*
X1801961Y1081717D03*
X1795819Y1088553D03*
X1800813Y1103246D03*
X1806206Y1114589D03*
X1803506D03*
X1800906D03*
X1798306D03*
X1798702Y1124328D03*
X1801302D03*
X1803902D03*
X1806602D03*
X1793221Y1121122D03*
Y1130822D03*
X1804532Y1133356D03*
X1807232D03*
X1807035Y1136912D03*
Y1144912D03*
X1806835Y1214668D03*
X1800489Y1220598D03*
X1807243Y1219955D03*
X1802670Y1210905D03*
X1805126Y1225745D03*
X1799845Y1261044D03*
X1794845D03*
X1797345D03*
X1799845Y1263544D03*
X1797345D03*
X1794845D03*
X1803885Y1435046D03*
X1806428Y1444543D03*
X1795374D03*
X1802813Y1464015D03*
X1803762Y1467236D03*
X1819900Y906900D03*
X1807663Y966660D03*
Y963860D03*
X1808014Y984832D03*
X1812538Y1026859D03*
X1811468Y1021084D03*
X1807844Y1023694D03*
Y1027248D03*
X1810349Y1031264D03*
X1816756Y1089145D03*
Y1094145D03*
X1816235Y1083970D03*
X1810346Y1082250D03*
X1816756Y1097145D03*
Y1101145D03*
X1810310Y1104819D03*
X1809535Y1136912D03*
Y1144912D03*
X1812130Y1205349D03*
X1822594Y1211054D03*
Y1215324D03*
X1814741Y1217093D03*
X1811482Y1226423D03*
X1810018Y1295944D03*
X1812818D03*
X1815618Y1298744D03*
Y1295944D03*
X1812818Y1298744D03*
X1810018D03*
X1812202Y1432624D03*
X1809342Y1476733D03*
X1824706Y1085145D03*
X1824949Y1077145D03*
X1824706Y1100185D03*
Y1106145D03*
X1828272Y1095968D03*
X1824706Y1093150D03*
X1830915Y1109146D03*
X1834665Y1213239D03*
G54D23*
X51750Y617861D03*
X48207D03*
X44664D03*
X51750Y620661D03*
X48207D03*
X44664D03*
X55294Y617861D03*
Y620661D03*
X146948Y1088287D03*
X143208D03*
X146948Y1099507D03*
X143208D03*
X146948Y1106988D03*
X143208D03*
X146948Y1114468D03*
Y1121948D03*
X143208Y1114468D03*
Y1121948D03*
X146948Y1129429D03*
X143208D03*
X146948Y1148129D03*
X143208D03*
X146947Y1170570D03*
X143207D03*
X146947Y1178051D03*
X143207D03*
X165649Y1073326D03*
X158169D03*
X150689D03*
X165649Y1092027D03*
X158169D03*
X150689D03*
X165649Y1077066D03*
X161909Y1084547D03*
X158169Y1077066D03*
X154429Y1084547D03*
X161909Y1080807D03*
X154429D03*
X165649Y1095767D03*
X161909Y1103247D03*
X158169Y1095767D03*
X154429Y1103247D03*
X150689Y1095767D03*
X161909Y1099507D03*
X154429D03*
X161909Y1118208D03*
Y1121948D03*
X165649Y1110728D03*
X161909D03*
X154429D03*
Y1118208D03*
X150689Y1110728D03*
Y1118208D03*
X154429Y1125688D03*
X150689D03*
X165649Y1148129D03*
Y1144389D03*
Y1155610D03*
X160039Y1176180D03*
X156299D03*
X169389Y1084547D03*
Y1080807D03*
Y1103247D03*
X176870Y1151870D03*
Y1148129D03*
Y1144389D03*
X169389Y1151870D03*
Y1148129D03*
X176870Y1166830D03*
Y1159350D03*
X169389D03*
X176870Y1174310D03*
Y1178051D03*
Y1181791D03*
X188090Y1114468D03*
X184350D03*
X191830D03*
X195570D03*
X191830Y1140649D03*
Y1136909D03*
X195570Y1140649D03*
X184350Y1136909D03*
X191830Y1133169D03*
Y1129429D03*
Y1144389D03*
Y1151869D03*
X195570Y1148129D03*
Y1155610D03*
X184350Y1144389D03*
X188090Y1155610D03*
X184350Y1151870D03*
X188090Y1148129D03*
X191830Y1159350D03*
Y1170570D03*
X195570Y1166830D03*
X184350Y1159350D03*
Y1170570D03*
X188090Y1166830D03*
X191830Y1185531D03*
Y1178051D03*
X195570Y1181791D03*
Y1174310D03*
X184350Y1185531D03*
X188090Y1181791D03*
Y1174310D03*
X184350Y1178051D03*
X191830Y1193011D03*
X195570Y1215452D03*
X197440Y1217322D03*
X186220D03*
X189960D03*
Y1213582D03*
X203051Y1114468D03*
X199311D03*
X206791D03*
X210531D03*
X206791Y1136909D03*
X203051D03*
X199311D03*
X214271D03*
X210531D03*
X199311Y1129429D03*
X206791D03*
X214271D03*
X210531D03*
X203051D03*
X210531Y1155610D03*
X203051D03*
X206791Y1144389D03*
X203051D03*
X199311D03*
X214271D03*
X210531D03*
X214271Y1151870D03*
X210531D03*
X206791D03*
X203051D03*
X199311D03*
X214271Y1170570D03*
X210531Y1166830D03*
X214271Y1159350D03*
X206791Y1170570D03*
X203051Y1166830D03*
X199311Y1170570D03*
X206791Y1159350D03*
X199311D03*
X203051Y1174310D03*
X210531D03*
X203051Y1185531D03*
X199311D03*
X206791D03*
X214271D03*
X210531D03*
X206791Y1178051D03*
X203051D03*
X199311D03*
X214271D03*
X210531D03*
X214271Y1193011D03*
X210531D03*
X199311D03*
X203051D03*
X206791D03*
X214271Y1200491D03*
X210531D03*
X199311D03*
X206791D03*
X203051D03*
X201181Y1213582D03*
X214271Y1211712D03*
X208661Y1213582D03*
X203051Y1215452D03*
X214271D03*
X201181Y1217322D03*
X208661D03*
X210531Y1215452D03*
X204921Y1213582D03*
X225492Y1114468D03*
X221752D03*
X218011D03*
X225492Y1136909D03*
X221751D03*
X218011D03*
X229232D03*
Y1129429D03*
X218011D03*
X221751D03*
X225492D03*
X218011Y1155610D03*
X225492D03*
Y1144389D03*
X221751D03*
X218011D03*
X229232D03*
Y1151870D03*
X221752D03*
X218011D03*
X225492D03*
Y1166830D03*
X221751Y1170570D03*
X218011Y1166830D03*
X221751Y1159350D03*
X229232Y1170570D03*
Y1159350D03*
X225492Y1174310D03*
X218011D03*
X225492Y1185531D03*
X218011D03*
X221751D03*
X229232D03*
X225492Y1178051D03*
X221751D03*
X218011D03*
X229232D03*
X218011Y1193011D03*
X221751D03*
X225492D03*
X229232D03*
X218011Y1200491D03*
X221751D03*
X225492D03*
X229232D03*
X218011Y1215452D03*
X229232Y1211712D03*
Y1215452D03*
X225492Y1211712D03*
X221752D03*
Y1215452D03*
X240452Y1114468D03*
X244192D03*
X236712Y1118208D03*
X244192D03*
X236712Y1114468D03*
X240452Y1118208D03*
Y1136909D03*
X236712D03*
X244192D03*
Y1129429D03*
X240452D03*
X236712D03*
Y1155610D03*
X244192D03*
X240452Y1151869D03*
X236712D03*
X244192D03*
X240452Y1144389D03*
X236712D03*
X244192D03*
X236712Y1166830D03*
X240452Y1170570D03*
Y1159350D03*
X244192Y1166830D03*
X236712Y1174310D03*
X244192D03*
X240452Y1185531D03*
X236712D03*
X244192D03*
X240452Y1178051D03*
X236712D03*
X244192D03*
X240452Y1193011D03*
X236712D03*
X244192D03*
X236712Y1200491D03*
X244192D03*
X240452D03*
X244192Y1215452D03*
X240452D03*
X242322Y1217322D03*
X236712Y1211712D03*
Y1215452D03*
X238582Y1217322D03*
X262893Y1118208D03*
X259153Y1114468D03*
X262893D03*
X255413Y1118208D03*
Y1114468D03*
X247933D03*
X259153Y1118208D03*
X251673Y1114468D03*
X247933Y1118208D03*
X251673D03*
X255413Y1136909D03*
X251673D03*
X247933D03*
X259153D03*
X262893D03*
X247933Y1129429D03*
X259153D03*
X262893D03*
X255413D03*
X251673D03*
Y1155610D03*
X259153D03*
X251673Y1144389D03*
X247933D03*
X255413D03*
X259153Y1151869D03*
X262893D03*
X247933D03*
X255413D03*
X251673D03*
X262893Y1144389D03*
X259153D03*
X251673Y1166830D03*
X255413Y1170570D03*
X247933D03*
X255413Y1159350D03*
X247933D03*
X259153Y1166830D03*
X262893Y1170570D03*
Y1159350D03*
X251673Y1174310D03*
X259153D03*
X247933Y1185531D03*
X255413D03*
X251673D03*
X259153D03*
X262893D03*
X251673Y1178051D03*
X247933D03*
X255413D03*
X259153D03*
X262893D03*
X251673Y1193011D03*
X255413D03*
X247933D03*
X262893D03*
X259153D03*
Y1200491D03*
X262893D03*
X251673D03*
X247933D03*
X255413D03*
Y1215452D03*
X262893D03*
X247932Y1215451D03*
X259153Y1215452D03*
X251673D03*
X247932Y1211711D03*
X251673D03*
X270373Y1114468D03*
X274114D03*
X277854D03*
X266633Y1136909D03*
Y1129429D03*
X274114D03*
Y1140649D03*
Y1136909D03*
X266633Y1155610D03*
X277854D03*
X266633Y1151869D03*
Y1144389D03*
X274114D03*
X277854Y1159350D03*
Y1166830D03*
Y1170570D03*
X266633D03*
X270373D03*
X266633Y1159350D03*
X270373D03*
Y1166830D03*
X266633D03*
Y1174310D03*
X277854D03*
X266633Y1185531D03*
Y1178051D03*
X270373Y1181791D03*
X274114Y1185531D03*
Y1189271D03*
Y1178051D03*
X266633Y1193011D03*
Y1200491D03*
X274114D03*
Y1193011D03*
X277854Y1204232D03*
Y1196751D03*
Y1200491D03*
X274114Y1215452D03*
X277854D03*
X266633D03*
X274114Y1211712D03*
X277854Y1207972D03*
X285334Y1118208D03*
X281594D03*
X285334Y1114468D03*
X281594D03*
X289074Y1140649D03*
X285334D03*
Y1136909D03*
X292815Y1140649D03*
X285334Y1155610D03*
X281594Y1144389D03*
X285334Y1148129D03*
Y1144389D03*
X289074Y1148129D03*
X292815D03*
Y1155610D03*
X285334Y1170570D03*
Y1166830D03*
Y1159350D03*
X292815Y1170570D03*
X285334Y1174310D03*
X289074Y1189271D03*
X285334D03*
X281594Y1181791D03*
X285334Y1178051D03*
X289074Y1181791D03*
X285334Y1196751D03*
Y1204232D03*
X281594Y1200491D03*
X285334D03*
Y1207972D03*
Y1215452D03*
Y1211712D03*
X281594Y1215452D03*
Y1207972D03*
X294685Y1254724D03*
Y1250984D03*
X290944Y1247243D03*
Y1243503D03*
X311515Y1140649D03*
X304035Y1144389D03*
Y1151869D03*
X307775Y1144389D03*
Y1151869D03*
X296555Y1155610D03*
X311515Y1148129D03*
Y1155610D03*
X304035Y1166830D03*
Y1159350D03*
X307775Y1166830D03*
X296555Y1170570D03*
X311515D03*
X304035Y1174310D03*
Y1181791D03*
Y1189271D03*
X307775Y1174310D03*
Y1181791D03*
Y1189271D03*
X311515Y1178051D03*
Y1185531D03*
Y1193011D03*
X309645Y1254724D03*
X298425Y1247243D03*
X309645Y1250984D03*
X298425Y1243503D03*
X305905D03*
Y1247243D03*
X302165Y1254724D03*
Y1250984D03*
X322736Y1136909D03*
X326476D03*
X315255Y1140649D03*
X322736Y1144389D03*
Y1151870D03*
X326476Y1144389D03*
X315255Y1148129D03*
X326476Y1151870D03*
X315255Y1155610D03*
X322736Y1159350D03*
X326476D03*
X315255Y1170570D03*
X322736Y1174310D03*
Y1181791D03*
Y1189271D03*
X326476Y1174310D03*
X315255Y1178051D03*
X326476Y1181791D03*
X315255Y1185531D03*
X326476Y1189271D03*
X320866Y1198621D03*
X313385Y1202362D03*
X324606Y1198621D03*
X317125Y1202362D03*
X315255Y1193011D03*
X317125Y1217322D03*
Y1209842D03*
X324606Y1213582D03*
X320866Y1221062D03*
X313385Y1209842D03*
X320866Y1206102D03*
Y1213582D03*
X324606Y1221062D03*
Y1206102D03*
X313385Y1217322D03*
X317125Y1254724D03*
X313385Y1247243D03*
X320866D03*
X317125Y1250984D03*
X313385Y1243503D03*
X324606Y1247243D03*
X425023Y441086D03*
Y433999D03*
Y437543D03*
X422223Y441086D03*
Y433999D03*
Y437543D03*
X425023Y444629D03*
X422223D03*
X501750Y620661D03*
X505293D03*
X501750Y617861D03*
X505293D03*
X512380D03*
X508836Y620661D03*
Y617861D03*
X512380Y620661D03*
X600295Y1088287D03*
X604035D03*
X600295Y1099507D03*
X604035D03*
X600295Y1106988D03*
X604035D03*
Y1121948D03*
X600295D03*
Y1114468D03*
X604035D03*
X600295Y1136909D03*
X604035D03*
X600295Y1129429D03*
X604035D03*
Y1148129D03*
X600295D03*
X604034Y1170570D03*
X600294D03*
X604034Y1178051D03*
X600294D03*
X615256Y1073326D03*
X607776D03*
X618996Y1084547D03*
Y1080807D03*
X615256Y1077066D03*
X611516Y1080807D03*
Y1084547D03*
X607776Y1092027D03*
X615256D03*
X607776Y1095767D03*
X615256D03*
X618996Y1103247D03*
X611516D03*
X618996Y1099507D03*
X611516D03*
X618996Y1118208D03*
Y1121948D03*
X611516Y1118208D03*
X607776D03*
X611516Y1110728D03*
X618996D03*
X607776D03*
X611516Y1125688D03*
X607776D03*
Y1133169D03*
X615256Y1178051D03*
X611516D03*
X622736Y1073326D03*
Y1077066D03*
X626476Y1084547D03*
X622736Y1092027D03*
X626476Y1080807D03*
X622736Y1095767D03*
X626476Y1103247D03*
X622736Y1118208D03*
X626476Y1114468D03*
X622736Y1110728D03*
X630216Y1114468D03*
X633957Y1151870D03*
Y1148129D03*
Y1144389D03*
X626476Y1148129D03*
X622736Y1144389D03*
Y1148129D03*
X626476Y1151870D03*
X622736Y1155610D03*
X633957Y1166830D03*
Y1159350D03*
X626476D03*
X633957Y1174310D03*
Y1178051D03*
Y1181791D03*
X632086Y1254724D03*
X635827Y1243503D03*
X632086Y1250984D03*
X635827Y1247243D03*
X628346Y1243503D03*
Y1247243D03*
X645177Y1114468D03*
X641437D03*
X648917D03*
X652657D03*
X648917Y1140649D03*
Y1136909D03*
X652657Y1140649D03*
X641437Y1136909D03*
X648917Y1129429D03*
Y1133169D03*
X652657Y1148129D03*
Y1155610D03*
X648917Y1144389D03*
Y1151869D03*
X641437Y1144389D03*
Y1151870D03*
X645177Y1155610D03*
Y1148129D03*
X648917Y1159350D03*
Y1170570D03*
X652657Y1166830D03*
X641437Y1170570D03*
X645177Y1166830D03*
X641437Y1159350D03*
X648917Y1185531D03*
Y1178051D03*
X652657Y1181791D03*
Y1174310D03*
X641437Y1185531D03*
Y1178051D03*
X645177Y1181791D03*
Y1174310D03*
X648917Y1193011D03*
X652657Y1215452D03*
Y1219192D03*
X641437Y1215452D03*
X648917D03*
X645177D03*
X639567Y1250984D03*
Y1254724D03*
X650787Y1247243D03*
Y1243503D03*
X647047Y1254724D03*
Y1250984D03*
X643307Y1247243D03*
Y1243503D03*
X660138Y1114468D03*
X656398D03*
X663878D03*
X667618D03*
Y1129429D03*
X660138D03*
X656398D03*
X663878D03*
Y1136909D03*
X660138D03*
X656398D03*
X667618D03*
X660138Y1155610D03*
X667618D03*
Y1144389D03*
X663878D03*
X660138D03*
X656398D03*
X667618Y1151870D03*
X663878D03*
X660138D03*
X656398D03*
X663878Y1170570D03*
X660138Y1166830D03*
X656398Y1170570D03*
X663878Y1159350D03*
X656398D03*
X667618Y1166830D03*
Y1174310D03*
X660138D03*
X667618Y1185531D03*
X660138D03*
X656398D03*
X663878D03*
X667618Y1178051D03*
X663878D03*
X660138D03*
X656398D03*
X667618Y1200491D03*
X656398D03*
X663878D03*
X660138D03*
X663878Y1193011D03*
X660138D03*
X656398D03*
X667618D03*
X663878Y1211712D03*
X656398D03*
X660138Y1215452D03*
X656398D03*
X663878D03*
X667618D03*
X660138Y1211712D03*
X654527Y1254724D03*
Y1250984D03*
X682579Y1114468D03*
X678839D03*
X675098D03*
Y1129429D03*
X671358D03*
X678838D03*
X682579D03*
Y1136909D03*
X678838D03*
X675098D03*
X671358D03*
X682579Y1155610D03*
X675098D03*
X678839Y1151870D03*
X675098D03*
X671358D03*
X682579D03*
Y1144389D03*
X671358D03*
X678838D03*
X675098D03*
X682579Y1166830D03*
X678838Y1170570D03*
X671358D03*
X675098Y1166830D03*
X671358Y1159350D03*
X678838D03*
X682579Y1174310D03*
X675098D03*
X682579Y1185531D03*
X675098D03*
X671358D03*
X678838D03*
X682579Y1178051D03*
X678838D03*
X675098D03*
X671358D03*
X675098Y1200491D03*
X671358D03*
X678838D03*
X682579D03*
Y1193011D03*
X678838D03*
X675098D03*
X671358D03*
X682579Y1211712D03*
X678839D03*
Y1215452D03*
X671358Y1211712D03*
Y1215452D03*
X675098D03*
X693799Y1114468D03*
Y1118208D03*
X701279Y1114468D03*
X697539Y1118208D03*
Y1114468D03*
X701279Y1118208D03*
Y1129429D03*
X697539D03*
X693799D03*
X686319D03*
X697539Y1136909D03*
X693799D03*
X701279D03*
X686319D03*
X701279Y1155610D03*
X693799D03*
X701279Y1151869D03*
X697539D03*
X693799D03*
X701279Y1144389D03*
X697539D03*
X693799D03*
X686319D03*
Y1151870D03*
X693799Y1166830D03*
X697539Y1170570D03*
Y1159350D03*
X701279Y1166830D03*
X686319Y1170570D03*
Y1159350D03*
X701279Y1174310D03*
X693799D03*
X701279Y1185531D03*
X697539D03*
X693799D03*
X701279Y1178051D03*
X697539D03*
X693799D03*
X686319Y1185531D03*
Y1178051D03*
X701279Y1200491D03*
X697539D03*
X693799D03*
X686319D03*
X701279Y1193011D03*
X697539D03*
X693799D03*
X686319D03*
Y1211712D03*
Y1215452D03*
X699409Y1217322D03*
X697539Y1215452D03*
X693799D03*
Y1211712D03*
X701279Y1215452D03*
X695669Y1217322D03*
X708760Y1114468D03*
X716240Y1118208D03*
X705020Y1114468D03*
X712500D03*
X716240D03*
X705020Y1118208D03*
X712500D03*
X708760D03*
X705020Y1129429D03*
X708760D03*
X712500D03*
X716240D03*
Y1136909D03*
X705020D03*
X708760D03*
X712500D03*
X708760Y1155610D03*
X716240D03*
Y1151869D03*
X708760D03*
X712500D03*
X705020D03*
X712500Y1144389D03*
X705020D03*
X708760D03*
X716240D03*
Y1166830D03*
X705020Y1159350D03*
X712500D03*
X705020Y1170570D03*
X712500D03*
X708760Y1166830D03*
X716240Y1174310D03*
X708760D03*
X716240Y1185531D03*
X708760D03*
X712500D03*
X705020D03*
X716240Y1178051D03*
X712500D03*
X705020D03*
X708760D03*
X712500Y1200491D03*
X705020D03*
X708760D03*
X716240D03*
X708760Y1193011D03*
X712500D03*
X705020D03*
X716240D03*
Y1215452D03*
X708760D03*
X712500D03*
X705019Y1215451D03*
Y1211711D03*
X708760D03*
X718110Y1243503D03*
Y1247243D03*
X731201Y1114468D03*
X734941D03*
X727460D03*
X719980Y1118208D03*
Y1114468D03*
Y1129429D03*
X723720D03*
X731201D03*
X719980Y1136909D03*
X723720D03*
X731201D03*
Y1140649D03*
X723720Y1155610D03*
X719980Y1151869D03*
X723720D03*
Y1144389D03*
X719980D03*
X734941Y1155610D03*
X731201Y1144389D03*
X719980Y1159350D03*
X727460D03*
X723720D03*
Y1166830D03*
X727460D03*
X719980Y1170570D03*
X727460D03*
X723720D03*
X734941Y1159350D03*
Y1166830D03*
Y1170570D03*
X723720Y1174310D03*
X727460Y1181791D03*
X719980Y1185531D03*
Y1178051D03*
X723720D03*
Y1185531D03*
X734941Y1174310D03*
X731201Y1189271D03*
Y1185531D03*
Y1178051D03*
X719980Y1200491D03*
X723720D03*
X731201D03*
X719980Y1193011D03*
X723720D03*
X731201D03*
X734941Y1196751D03*
Y1204232D03*
Y1200491D03*
X731201Y1215452D03*
X734941D03*
X723720D03*
X719980D03*
X731201Y1211712D03*
X734941Y1207972D03*
X727461Y1215452D03*
X729331Y1250984D03*
X733071Y1247243D03*
X721850Y1250984D03*
Y1254724D03*
X725590Y1243503D03*
X729331Y1254724D03*
X733071Y1243503D03*
X725590Y1247243D03*
X738681Y1118208D03*
X742421D03*
X738681Y1114468D03*
X742421D03*
Y1140649D03*
Y1136909D03*
X746161Y1140649D03*
X749902D03*
X742421Y1155610D03*
X746161Y1148129D03*
X738681Y1144389D03*
X742421Y1148129D03*
Y1144389D03*
X749902Y1155610D03*
Y1148129D03*
X742421Y1159350D03*
Y1166830D03*
Y1170570D03*
X749902D03*
X742421Y1189271D03*
X746161D03*
X742421Y1174310D03*
X738681Y1181791D03*
X746161D03*
X742421Y1178051D03*
Y1196751D03*
X738681Y1200491D03*
X742421Y1204232D03*
Y1200491D03*
Y1211712D03*
Y1215452D03*
Y1207972D03*
X738681Y1215452D03*
Y1207972D03*
Y1211712D03*
X744291Y1254724D03*
X740551Y1243503D03*
Y1247243D03*
X744291Y1250984D03*
X736811Y1254724D03*
Y1250984D03*
X761122Y1144389D03*
Y1151869D03*
X753642Y1155610D03*
X764862Y1151869D03*
Y1144389D03*
Y1166830D03*
X761122D03*
Y1159350D03*
X753642Y1170570D03*
X764862Y1174310D03*
X761122Y1181791D03*
X764862D03*
X761122Y1174310D03*
X768602Y1140649D03*
X772342D03*
Y1148129D03*
Y1155610D03*
X783563Y1151870D03*
X779823D03*
Y1144389D03*
X783563D03*
X768602Y1155610D03*
Y1148129D03*
X779823Y1159350D03*
X772342Y1170570D03*
X768602D03*
X783563Y1159350D03*
Y1189271D03*
X768602Y1185531D03*
X772342Y1178051D03*
X779823Y1189271D03*
X772342Y1185531D03*
X783563Y1174310D03*
X779823D03*
X783563Y1181791D03*
X768602Y1178051D03*
X779823Y1181791D03*
X768602Y1193011D03*
X772342D03*
X920349Y450340D03*
X917549D03*
X920349Y453884D03*
Y457427D03*
X917549Y453884D03*
Y457427D03*
X920349Y460970D03*
X917549D03*
X962380Y617861D03*
X958837D03*
X962380Y620661D03*
X958837D03*
X969467D03*
X965923Y617861D03*
Y620661D03*
X969467Y617861D03*
X1057381Y1088287D03*
Y1106988D03*
Y1099507D03*
Y1114468D03*
Y1121948D03*
Y1129429D03*
Y1136909D03*
Y1148129D03*
X1057380Y1170570D03*
Y1178051D03*
X1072342Y1073326D03*
X1064862D03*
Y1092027D03*
X1072342Y1077066D03*
X1068602Y1084547D03*
Y1080807D03*
X1061121Y1088287D03*
X1072342Y1092027D03*
X1068602Y1099507D03*
X1072342Y1095767D03*
X1061121Y1106988D03*
X1068602Y1103247D03*
X1064862Y1095767D03*
X1061121Y1099507D03*
Y1114468D03*
X1068602Y1110728D03*
Y1118208D03*
X1064862Y1110728D03*
Y1118208D03*
X1061121Y1121948D03*
X1064862Y1125688D03*
X1068602D03*
X1061121Y1129429D03*
X1064862Y1133169D03*
X1061121Y1136909D03*
Y1148129D03*
X1061120Y1170570D03*
X1072342Y1178051D03*
X1068602D03*
X1061120D03*
X1079822Y1073326D03*
Y1092027D03*
X1083562Y1084547D03*
X1079822Y1077066D03*
X1076082Y1084547D03*
Y1080807D03*
X1083562D03*
X1076082Y1103247D03*
X1079822Y1095767D03*
X1076082Y1099507D03*
X1083562Y1103247D03*
X1079822Y1118208D03*
X1076082Y1121948D03*
Y1118208D03*
X1079822Y1110728D03*
X1083562Y1114468D03*
X1087302D03*
X1076082Y1110728D03*
X1091043Y1151870D03*
Y1148129D03*
Y1144389D03*
X1083562Y1148129D03*
X1079822Y1144389D03*
Y1148129D03*
X1083562Y1151870D03*
X1079822Y1155610D03*
X1091043Y1166830D03*
Y1159350D03*
X1083562D03*
X1091043Y1181791D03*
Y1178051D03*
Y1174310D03*
X1102263Y1114468D03*
X1098523D03*
X1106003D03*
Y1140649D03*
Y1136909D03*
X1098523D03*
X1106003Y1129429D03*
Y1133169D03*
Y1151869D03*
Y1144389D03*
X1098523D03*
Y1151870D03*
X1102263Y1148129D03*
Y1155610D03*
X1106003Y1170570D03*
Y1159350D03*
X1102263Y1166830D03*
X1098523Y1159350D03*
Y1170570D03*
X1106003Y1178051D03*
Y1185531D03*
X1098523D03*
X1102263Y1174310D03*
X1098523Y1178051D03*
X1102263Y1181791D03*
X1106003Y1193011D03*
Y1215452D03*
X1098523D03*
X1102263D03*
X1117224Y1114468D03*
X1113484D03*
X1120964D03*
X1124704D03*
X1109743D03*
X1120964Y1129429D03*
X1113484D03*
X1117224D03*
X1124704D03*
Y1136909D03*
X1113484D03*
X1117224D03*
X1120964D03*
X1109743Y1140649D03*
X1124704Y1144389D03*
X1113484D03*
X1117224D03*
X1120964D03*
X1113484Y1151870D03*
X1117224D03*
X1120964D03*
X1124704D03*
Y1155610D03*
X1109743D03*
Y1148129D03*
X1117224Y1155610D03*
X1113484Y1159350D03*
X1120964D03*
X1109743Y1166830D03*
X1113484Y1170570D03*
X1117224Y1166830D03*
X1120964Y1170570D03*
X1124704Y1166830D03*
X1113484Y1178051D03*
X1117224D03*
X1120964D03*
X1124704D03*
X1120964Y1185531D03*
X1113484D03*
X1117224D03*
X1124704D03*
X1109743Y1174310D03*
Y1181791D03*
X1117224Y1174310D03*
X1124704D03*
X1117224Y1200491D03*
X1120964D03*
X1113484D03*
X1124704D03*
X1120964Y1193011D03*
X1117224D03*
X1113484D03*
X1124704D03*
Y1215452D03*
X1120964D03*
Y1211712D03*
X1117224Y1215452D03*
X1109743D03*
X1113484Y1211712D03*
X1111613Y1217322D03*
X1115354D03*
X1117224Y1211712D03*
X1139665Y1114468D03*
X1135925D03*
X1132184D03*
Y1129429D03*
X1128444D03*
X1135924D03*
X1139665D03*
Y1136909D03*
X1135924D03*
X1132184D03*
X1128444D03*
Y1144389D03*
X1135924D03*
X1132184D03*
X1139665D03*
X1135925Y1151870D03*
X1132184D03*
X1128444D03*
X1139665D03*
Y1155610D03*
X1132184D03*
X1139665Y1166830D03*
X1135924Y1170570D03*
X1128444D03*
X1132184Y1166830D03*
X1128444Y1159350D03*
X1135924D03*
X1139665Y1178051D03*
X1135924D03*
X1132184D03*
X1128444D03*
X1139665Y1185531D03*
X1132184D03*
X1128444D03*
X1135924D03*
X1139665Y1174310D03*
X1132184D03*
Y1200491D03*
X1128444D03*
X1135924D03*
X1139665D03*
X1128444Y1193011D03*
X1132184D03*
X1135924D03*
X1139665D03*
Y1211712D03*
X1135925D03*
Y1215452D03*
X1128444D03*
X1132184D03*
X1128444Y1211712D03*
X1154625Y1118208D03*
X1150885D03*
X1154625Y1114468D03*
X1150885D03*
X1154625Y1129429D03*
X1150885D03*
X1143405D03*
Y1136909D03*
X1154625D03*
X1150885D03*
X1143405Y1144389D03*
X1150885Y1151869D03*
X1154625D03*
Y1144389D03*
X1150885D03*
X1143405Y1151870D03*
X1150885Y1155610D03*
X1143405Y1170570D03*
X1154625Y1159350D03*
X1143405D03*
X1150885Y1166830D03*
X1154625Y1170570D03*
X1143405Y1178051D03*
Y1185531D03*
X1154625D03*
X1150885D03*
X1154625Y1178051D03*
X1150885D03*
Y1174310D03*
X1143405Y1200491D03*
X1154625D03*
X1150885D03*
Y1193011D03*
X1154625D03*
X1143405D03*
Y1211712D03*
Y1215452D03*
X1150885Y1211712D03*
Y1215452D03*
X1154625D03*
X1156495Y1217322D03*
X1152755D03*
X1162106Y1114468D03*
X1169586D03*
X1162106Y1118208D03*
X1173326Y1114468D03*
X1158365Y1118208D03*
X1173326D03*
X1165846Y1114468D03*
X1158365D03*
X1169586Y1118208D03*
X1165846D03*
X1169586Y1129429D03*
X1165846D03*
X1162106D03*
X1158365D03*
X1173326D03*
Y1136909D03*
X1169586D03*
X1165846D03*
X1158365D03*
X1162106D03*
X1173326Y1151869D03*
X1158365D03*
X1162106D03*
X1169586D03*
X1165846D03*
X1173326Y1144389D03*
X1165846D03*
X1158365D03*
X1162106D03*
X1169586D03*
X1173326Y1155610D03*
X1165846D03*
X1158365D03*
X1173326Y1166830D03*
X1165846D03*
X1169586Y1170570D03*
X1158365Y1166830D03*
X1162106Y1170570D03*
X1169586Y1159350D03*
X1162106D03*
X1158365Y1185531D03*
X1162106D03*
X1169586D03*
X1165846D03*
X1173326D03*
X1165846Y1178051D03*
X1158365D03*
X1162106D03*
X1169586D03*
X1173326D03*
X1165846Y1174310D03*
X1158365D03*
X1173326D03*
Y1200491D03*
X1165846D03*
X1162106D03*
X1158365D03*
X1169586D03*
X1165846Y1193011D03*
X1169586D03*
X1158365D03*
X1162106D03*
X1173326D03*
Y1215452D03*
X1165846D03*
X1169586D03*
X1162105Y1215451D03*
X1158365Y1215452D03*
X1162105Y1211711D03*
X1165846D03*
X1188287Y1114468D03*
X1177066D03*
Y1118208D03*
X1184546Y1114468D03*
X1180806Y1129429D03*
X1177066D03*
X1188287D03*
X1180806Y1136909D03*
X1177066D03*
X1188287D03*
Y1140649D03*
X1180806Y1151869D03*
X1177066D03*
Y1144389D03*
X1180806D03*
Y1155610D03*
X1188287Y1144389D03*
X1180806Y1170570D03*
X1184546D03*
X1177066D03*
X1184546Y1166830D03*
X1180806D03*
X1177066Y1159350D03*
X1180806D03*
X1184546D03*
X1177066Y1185531D03*
Y1178051D03*
X1180806Y1185531D03*
Y1178051D03*
Y1174310D03*
X1184546Y1181791D03*
X1188287Y1185531D03*
Y1189271D03*
Y1178051D03*
X1180806Y1200491D03*
X1177066D03*
X1188287D03*
X1177066Y1193011D03*
X1180806D03*
X1188287D03*
Y1215452D03*
X1180806D03*
X1177066D03*
X1188287Y1211712D03*
X1199507Y1118208D03*
X1195767D03*
Y1114468D03*
X1192027D03*
X1199507D03*
Y1140649D03*
Y1136909D03*
X1203247Y1140649D03*
X1199507Y1155610D03*
X1192027D03*
X1203247Y1148129D03*
X1195767Y1144389D03*
X1199507Y1148129D03*
Y1144389D03*
Y1170570D03*
Y1166830D03*
Y1159350D03*
X1192027Y1166830D03*
Y1170570D03*
Y1159350D03*
X1203247Y1189271D03*
X1199507D03*
Y1174310D03*
X1195767Y1181791D03*
X1192027Y1174310D03*
X1199507Y1178051D03*
X1203247Y1181791D03*
X1199507Y1196751D03*
Y1204232D03*
X1195767Y1200491D03*
X1192027Y1196751D03*
Y1200491D03*
Y1204232D03*
X1199507Y1200491D03*
X1192027Y1215452D03*
X1199507Y1211712D03*
Y1215452D03*
Y1207972D03*
X1195767Y1215452D03*
X1192027Y1207972D03*
X1195767D03*
Y1211712D03*
X1205117Y1243503D03*
Y1247243D03*
X1206988Y1140649D03*
X1218208Y1144389D03*
Y1151869D03*
X1206988Y1155610D03*
Y1148129D03*
X1210728Y1155610D03*
X1221948Y1151869D03*
Y1144389D03*
X1218208Y1166830D03*
Y1159350D03*
X1221948Y1166830D03*
X1210728Y1170570D03*
X1206988D03*
X1218208Y1189271D03*
Y1174310D03*
X1221948Y1181791D03*
Y1174310D03*
X1218208Y1181791D03*
X1221948Y1189271D03*
X1212598Y1243503D03*
X1220078Y1247243D03*
Y1243503D03*
X1212598Y1247243D03*
X1208858Y1254724D03*
Y1250984D03*
X1216338Y1254724D03*
Y1250984D03*
X1236909Y1136909D03*
X1225688Y1140649D03*
X1229428D03*
X1236909Y1151870D03*
X1225688Y1148129D03*
X1229428D03*
X1225688Y1155610D03*
X1236909Y1144389D03*
X1229428Y1155610D03*
Y1170570D03*
X1225688D03*
X1236909Y1159350D03*
Y1181791D03*
X1225688Y1185531D03*
X1236909Y1189271D03*
X1229428Y1178051D03*
Y1185531D03*
X1236909Y1174310D03*
X1225688Y1178051D03*
X1231298Y1202362D03*
X1235039Y1198621D03*
X1227558Y1202362D03*
X1225688Y1193011D03*
X1229428D03*
X1235039Y1213582D03*
X1231298Y1209842D03*
X1227558D03*
X1235039Y1221062D03*
X1231298Y1217322D03*
X1235039Y1206102D03*
X1227558Y1217322D03*
Y1247243D03*
X1231298Y1254724D03*
X1223818D03*
Y1250984D03*
X1227558Y1243503D03*
X1231298Y1250984D03*
X1235039Y1247243D03*
X1240649Y1136909D03*
Y1151870D03*
Y1144389D03*
Y1159350D03*
Y1174310D03*
Y1181791D03*
Y1189271D03*
X1238779Y1198621D03*
Y1221062D03*
Y1206102D03*
Y1213582D03*
Y1247243D03*
X1339196Y441086D03*
Y433999D03*
Y437543D03*
X1336396Y441086D03*
Y433999D03*
Y437543D03*
X1339196Y444629D03*
X1336396D03*
X1415924Y620661D03*
Y617861D03*
X1423010Y620661D03*
X1419467Y617861D03*
X1423010D03*
X1426554Y620661D03*
Y617861D03*
X1419467Y620661D03*
X1514468Y1088287D03*
Y1099507D03*
Y1106988D03*
Y1121948D03*
Y1114468D03*
Y1129429D03*
Y1136909D03*
Y1148129D03*
Y1155610D03*
X1514467Y1170570D03*
Y1178051D03*
X1521949Y1073326D03*
X1529429D03*
Y1077066D03*
X1525689Y1084547D03*
X1529429Y1092027D03*
X1521949D03*
X1518208Y1088287D03*
X1525689Y1080807D03*
X1518208Y1099507D03*
X1525689D03*
X1529429Y1095767D03*
X1525689Y1103247D03*
X1518208Y1106988D03*
X1521949Y1095767D03*
Y1110728D03*
X1518208Y1114468D03*
X1525689Y1110728D03*
X1518208Y1121948D03*
X1521949Y1118208D03*
X1525689D03*
Y1125688D03*
X1518208Y1129429D03*
X1521949Y1125688D03*
X1518208Y1136909D03*
X1521949Y1133169D03*
X1518208Y1148129D03*
Y1155610D03*
X1518207Y1170570D03*
X1527559Y1176180D03*
X1518207Y1178051D03*
X1536909Y1073326D03*
X1533169Y1080807D03*
Y1084547D03*
X1540649Y1080807D03*
X1536909Y1077066D03*
X1540649Y1084547D03*
X1536909Y1092027D03*
Y1095767D03*
X1533169Y1099507D03*
X1540649Y1103247D03*
X1533169D03*
X1536909Y1118208D03*
X1533169D03*
Y1121948D03*
X1544389Y1114468D03*
X1536909Y1110728D03*
X1533169D03*
X1540649Y1114468D03*
X1536909Y1148129D03*
X1540649Y1151870D03*
Y1148129D03*
X1536909Y1144389D03*
Y1155610D03*
X1540649Y1159350D03*
Y1170570D03*
Y1174310D03*
Y1178050D03*
X1531299Y1176180D03*
X1546259Y1250984D03*
X1542519Y1243503D03*
X1546259Y1254724D03*
X1542519Y1247243D03*
X1559350Y1114468D03*
X1555610D03*
X1563090D03*
Y1140649D03*
Y1136909D03*
X1555610D03*
X1563090Y1129429D03*
Y1133169D03*
Y1144389D03*
Y1151869D03*
X1555610Y1144389D03*
X1548130Y1151870D03*
Y1148129D03*
Y1144389D03*
X1559350Y1155610D03*
X1555610Y1151870D03*
X1559350Y1148129D03*
X1563090Y1159350D03*
Y1170570D03*
X1548130Y1166830D03*
Y1159350D03*
X1555610Y1170570D03*
X1559350Y1166830D03*
X1555610Y1159350D03*
X1548130Y1174310D03*
Y1178051D03*
Y1181791D03*
X1563090Y1185531D03*
Y1178051D03*
X1555610Y1185531D03*
X1559350Y1174310D03*
Y1181791D03*
X1555610Y1178051D03*
X1563090Y1193011D03*
X1555610Y1215452D03*
X1563090D03*
X1559350D03*
X1561220Y1250984D03*
Y1254724D03*
X1550000Y1243503D03*
X1557480Y1247243D03*
X1550000D03*
X1557480Y1243503D03*
X1553740Y1250984D03*
Y1254724D03*
X1574311Y1114468D03*
X1570571D03*
X1578051D03*
X1566830D03*
X1578051Y1136909D03*
X1574311D03*
X1570571D03*
X1574311Y1129429D03*
X1570571D03*
X1578051D03*
X1566830Y1140649D03*
X1578051Y1144389D03*
X1574311D03*
X1570571D03*
X1578051Y1151870D03*
X1574311D03*
X1570571D03*
X1574311Y1155610D03*
X1566830Y1148129D03*
Y1155610D03*
X1578051Y1170570D03*
X1574311Y1166830D03*
X1570571Y1170570D03*
X1566830Y1166830D03*
X1578051Y1159350D03*
X1570571D03*
X1574311Y1185531D03*
X1570571D03*
X1578051D03*
Y1178051D03*
X1574311D03*
X1570571D03*
X1574311Y1174310D03*
X1566830Y1181791D03*
Y1174310D03*
X1570571Y1193011D03*
X1574311D03*
X1578051D03*
X1570571Y1200491D03*
X1578051D03*
X1574311D03*
X1578051Y1215452D03*
X1566830D03*
X1570571Y1211712D03*
X1566830Y1219192D03*
X1574311Y1215452D03*
X1570571D03*
X1578051Y1211712D03*
X1574311D03*
X1568700Y1254724D03*
X1564960Y1243503D03*
Y1247243D03*
X1568700Y1250984D03*
X1593012Y1114468D03*
X1589271D03*
X1581791D03*
X1593011Y1136909D03*
X1589271D03*
X1585531D03*
X1581791D03*
X1589271Y1129429D03*
X1585531D03*
X1581791D03*
X1593011D03*
X1585531Y1144389D03*
X1581791D03*
X1593011D03*
X1589271D03*
X1593012Y1151870D03*
X1589271D03*
X1585531D03*
X1581791D03*
Y1155610D03*
X1589271D03*
X1593011Y1170570D03*
X1585531D03*
X1589271Y1166830D03*
X1581791D03*
X1585531Y1159350D03*
X1593011D03*
X1589271Y1185531D03*
X1585531D03*
X1581791D03*
X1593011D03*
X1581791Y1178051D03*
X1593011D03*
X1589271D03*
X1585531D03*
X1589271Y1174310D03*
X1581791D03*
X1585531Y1193011D03*
X1589271D03*
X1593011D03*
X1581791D03*
X1589271Y1200491D03*
X1585531D03*
X1581791D03*
X1593011D03*
X1593012Y1211712D03*
Y1215452D03*
X1581791D03*
X1589271D03*
X1585531D03*
Y1211712D03*
X1596752Y1114468D03*
X1607972D03*
X1611712Y1118208D03*
X1607972D03*
X1611712Y1114468D03*
X1600492Y1136909D03*
X1596752D03*
X1611712D03*
X1607972D03*
X1611712Y1129429D03*
X1607972D03*
X1600492D03*
X1596752D03*
X1600492Y1144389D03*
X1596752D03*
X1611712Y1151869D03*
X1607972D03*
X1611712Y1144389D03*
X1607972D03*
X1600492Y1151870D03*
X1596752D03*
Y1155610D03*
X1607972D03*
Y1166830D03*
X1611712Y1170570D03*
X1600492D03*
X1596752Y1166830D03*
X1611712Y1159350D03*
X1600492D03*
Y1185531D03*
X1596752D03*
X1600492Y1178051D03*
X1596752D03*
X1611712Y1185531D03*
X1607972D03*
X1611712Y1178051D03*
X1607972D03*
Y1174310D03*
X1596752D03*
X1607972Y1193011D03*
X1611712D03*
X1600492D03*
X1596752D03*
X1600492Y1200491D03*
X1596752D03*
X1611712D03*
X1607972D03*
X1600492Y1211712D03*
Y1215452D03*
X1596752Y1211712D03*
X1611712Y1215452D03*
X1607972D03*
Y1211712D03*
X1609842Y1217322D03*
X1615452Y1118208D03*
X1619193D03*
X1615452Y1114468D03*
X1619193D03*
X1622933D03*
X1626673D03*
Y1118208D03*
X1622933D03*
X1626673Y1136909D03*
X1622933D03*
X1615452D03*
X1619193D03*
X1626673Y1129429D03*
X1622933D03*
X1619193D03*
X1615452D03*
Y1151869D03*
X1619193D03*
X1626673D03*
X1622933D03*
Y1144389D03*
X1615452D03*
X1619193D03*
X1626673D03*
X1622933Y1155610D03*
X1615452D03*
Y1166830D03*
X1619193Y1170570D03*
X1626673Y1159350D03*
X1619193D03*
X1622933Y1166830D03*
X1626673Y1170570D03*
X1619193Y1185531D03*
X1626673D03*
X1622933D03*
Y1178051D03*
X1615452D03*
X1619193D03*
X1626673D03*
X1615452Y1185531D03*
X1622933Y1174310D03*
X1615452D03*
X1622933Y1193011D03*
X1626673D03*
X1615452D03*
X1619193D03*
X1622933Y1200491D03*
X1619193D03*
X1615452D03*
X1626673D03*
X1622933Y1215452D03*
X1619192Y1215451D03*
X1626673Y1215452D03*
X1615452D03*
X1613582Y1217322D03*
X1619192Y1211711D03*
X1622933D03*
X1637893Y1118208D03*
Y1114468D03*
X1634153D03*
X1630413D03*
X1641633D03*
X1634153Y1118208D03*
X1630413D03*
Y1136909D03*
X1637893D03*
X1634153D03*
X1630413Y1129429D03*
X1637893D03*
X1634153D03*
X1630413Y1151869D03*
X1637893D03*
X1634153D03*
Y1144389D03*
X1630413D03*
X1637893D03*
Y1155610D03*
X1630413D03*
X1637893Y1170570D03*
X1641633D03*
X1634153D03*
X1641633Y1166830D03*
X1637893D03*
Y1159350D03*
X1641633D03*
X1634153D03*
X1630413Y1166830D03*
X1641633Y1181791D03*
X1630413Y1185531D03*
X1634153D03*
X1630413Y1178051D03*
X1634153D03*
X1637893Y1185531D03*
Y1178051D03*
Y1174310D03*
X1630413D03*
X1634153Y1193011D03*
X1637893D03*
X1630413D03*
Y1200491D03*
X1637893D03*
X1634153D03*
X1630413Y1215452D03*
X1637893D03*
X1634153D03*
X1632283Y1243503D03*
X1636023Y1254724D03*
X1639763Y1243503D03*
X1636023Y1250984D03*
X1632283Y1247243D03*
X1643504Y1250984D03*
X1639763Y1247243D03*
X1643504Y1254724D03*
X1656594Y1118208D03*
X1652854D03*
Y1114468D03*
X1645374D03*
X1649114D03*
X1656594D03*
X1645374Y1129429D03*
Y1136909D03*
Y1140649D03*
X1656594Y1133169D03*
Y1140649D03*
Y1136909D03*
X1660334Y1140649D03*
X1649114Y1155610D03*
X1656594D03*
X1645374Y1144389D03*
X1660334Y1148129D03*
X1652854Y1144389D03*
X1656594Y1148129D03*
Y1144389D03*
X1649114Y1159350D03*
Y1170570D03*
Y1166830D03*
X1656594Y1170570D03*
Y1166830D03*
Y1159350D03*
Y1189271D03*
X1649114Y1174310D03*
X1656594D03*
X1652854Y1181791D03*
X1660334Y1189271D03*
X1645374Y1185531D03*
Y1189271D03*
X1660334Y1181791D03*
X1656594Y1178051D03*
X1645374D03*
Y1200491D03*
Y1193011D03*
X1656594Y1196751D03*
Y1204232D03*
X1652854Y1200491D03*
X1649114Y1204232D03*
Y1196751D03*
Y1200491D03*
X1656594D03*
X1645374Y1215452D03*
X1649114D03*
X1652854D03*
X1656594Y1211712D03*
X1645374D03*
X1656594Y1215452D03*
Y1207972D03*
X1649114D03*
X1652854D03*
Y1211712D03*
X1654724Y1243503D03*
X1650984Y1250984D03*
X1647244Y1247243D03*
X1654724D03*
X1647244Y1243503D03*
X1650984Y1254724D03*
X1658464D03*
Y1250984D03*
X1664075Y1140649D03*
X1667815Y1155610D03*
X1664075Y1148129D03*
Y1155610D03*
X1675295Y1144389D03*
Y1151869D03*
Y1166830D03*
Y1159350D03*
X1664075Y1170570D03*
X1667815D03*
X1675295Y1189271D03*
Y1174310D03*
Y1181791D03*
X1686515Y1140649D03*
X1682775D03*
X1679035Y1151869D03*
Y1144389D03*
X1682775Y1148129D03*
X1686515Y1155610D03*
Y1148129D03*
X1682775Y1155610D03*
X1679035Y1166830D03*
X1686515Y1170570D03*
X1682775D03*
X1679035Y1181791D03*
Y1189271D03*
Y1174310D03*
X1686515Y1185531D03*
X1682775Y1178051D03*
X1686515D03*
X1682775Y1185531D03*
X1686515Y1193011D03*
X1682775D03*
Y1222932D03*
X1693996Y1136909D03*
X1697736D03*
X1693996Y1151870D03*
X1697736D03*
X1693996Y1144389D03*
X1697736D03*
Y1159350D03*
X1693996D03*
X1697736Y1174310D03*
X1693996Y1189271D03*
X1697736D03*
Y1181791D03*
X1693996D03*
Y1174310D03*
X1796283Y441086D03*
Y433999D03*
Y437543D03*
X1793483Y441086D03*
Y433999D03*
Y437543D03*
X1796283Y444629D03*
X1793483D03*
G54D53*
X970071Y1365652D03*
Y1409152D03*
G54D33*
X109882Y1489331D03*
Y1494449D03*
Y1591693D03*
Y1596811D03*
Y1622402D03*
X118543Y1452717D03*
X127205Y1489331D03*
Y1494449D03*
X118543Y1493662D03*
Y1498780D03*
X127205Y1591693D03*
X118543Y1596024D03*
X127205Y1596811D03*
X118543Y1601142D03*
X127205Y1622402D03*
X135866Y1452717D03*
X144528Y1489331D03*
Y1494449D03*
X135866Y1493662D03*
Y1498780D03*
X144528Y1591693D03*
X135866Y1596024D03*
X144528Y1596811D03*
X135866Y1601142D03*
X144528Y1622402D03*
X153189Y1452717D03*
X161850Y1489331D03*
Y1494449D03*
X153189Y1493662D03*
Y1498780D03*
X161850Y1591693D03*
X153189Y1596024D03*
X161850Y1596811D03*
X153189Y1601142D03*
X161850Y1622402D03*
X179173Y1458622D03*
Y1463741D03*
X170512Y1452717D03*
X179173Y1489331D03*
Y1494449D03*
X170512Y1493662D03*
Y1498780D03*
X179173Y1504685D03*
Y1509804D03*
Y1560985D03*
Y1566103D03*
Y1576339D03*
Y1581457D03*
Y1591693D03*
X170512Y1596024D03*
X179173Y1596811D03*
Y1607048D03*
Y1612166D03*
X170512Y1601142D03*
X179173Y1622402D03*
X187835Y1452717D03*
Y1462953D03*
Y1468071D03*
Y1493662D03*
Y1498780D03*
Y1509016D03*
Y1514134D03*
Y1565315D03*
Y1570434D03*
Y1580670D03*
Y1585788D03*
X291771Y1452717D03*
X283110Y1622402D03*
X309094Y1452717D03*
X300433Y1622402D03*
X326417Y1452717D03*
X317756Y1622402D03*
X343740Y1452717D03*
X335078Y1622402D03*
X361063Y1452717D03*
X352401Y1458622D03*
Y1463741D03*
X361063Y1462953D03*
Y1468071D03*
X352401Y1473977D03*
Y1479095D03*
X361063Y1478308D03*
Y1483426D03*
X352401Y1489331D03*
Y1494449D03*
X361063Y1493662D03*
Y1498780D03*
X352401Y1504685D03*
Y1509804D03*
X361063Y1509016D03*
Y1514134D03*
X352401Y1560985D03*
Y1566103D03*
X361063Y1565315D03*
Y1570434D03*
X352401Y1576339D03*
Y1581457D03*
X361063Y1580670D03*
Y1585788D03*
X352401Y1591693D03*
Y1596811D03*
Y1607048D03*
Y1612166D03*
Y1622402D03*
X456339Y1458622D03*
Y1463741D03*
Y1576339D03*
Y1581457D03*
Y1622402D03*
X473662Y1458622D03*
Y1463741D03*
X465000Y1452717D03*
Y1462953D03*
Y1468071D03*
X473662Y1576339D03*
Y1581457D03*
X465000Y1580670D03*
Y1585788D03*
X473662Y1622402D03*
X490985Y1458622D03*
Y1463741D03*
X482323Y1452717D03*
Y1462953D03*
Y1468071D03*
X490985Y1576339D03*
Y1581457D03*
X482323Y1580670D03*
Y1585788D03*
X490985Y1622402D03*
X499646Y1452717D03*
Y1462953D03*
Y1468071D03*
Y1580670D03*
Y1585788D03*
X516969Y1452717D03*
X508307Y1458622D03*
X516969Y1462953D03*
X508307Y1463741D03*
X516969Y1468071D03*
X508307Y1576339D03*
X516969Y1580670D03*
X508307Y1581457D03*
X516969Y1585788D03*
X508307Y1622402D03*
X534292Y1452717D03*
X525630Y1458622D03*
Y1463741D03*
X534292Y1462953D03*
Y1468071D03*
X525630Y1473977D03*
Y1479095D03*
X534292Y1478308D03*
Y1483426D03*
X525630Y1489331D03*
Y1494449D03*
X534292Y1493662D03*
Y1498780D03*
X525630Y1504685D03*
Y1509804D03*
X534292Y1509016D03*
Y1514134D03*
X525630Y1560985D03*
Y1566103D03*
X534292Y1565315D03*
Y1570434D03*
X525630Y1576339D03*
Y1581457D03*
X534292Y1580670D03*
Y1585788D03*
X525630Y1591693D03*
X534292Y1596024D03*
X525630Y1596811D03*
X534292Y1601142D03*
X525630Y1607048D03*
Y1612166D03*
X534292Y1611378D03*
Y1616496D03*
X525630Y1622402D03*
X629567D03*
X638228Y1452717D03*
X646890Y1622402D03*
X655551Y1452717D03*
X664213Y1622402D03*
X672874Y1452717D03*
X681535Y1622402D03*
X698858Y1458622D03*
Y1463741D03*
X690197Y1452717D03*
X698858Y1473977D03*
Y1479095D03*
Y1489331D03*
Y1494449D03*
Y1504685D03*
Y1509804D03*
Y1560985D03*
Y1566103D03*
Y1576339D03*
Y1581457D03*
Y1591693D03*
Y1596811D03*
Y1607048D03*
Y1612166D03*
Y1622402D03*
X707520Y1452717D03*
Y1462953D03*
Y1468071D03*
Y1478308D03*
Y1483426D03*
Y1493662D03*
Y1498780D03*
Y1509016D03*
Y1514134D03*
Y1565315D03*
Y1570434D03*
Y1580670D03*
Y1585788D03*
Y1596024D03*
Y1601142D03*
Y1611378D03*
Y1616496D03*
X1140511Y1452717D03*
X1131850Y1489331D03*
X1140511Y1493662D03*
X1131850Y1494449D03*
X1140511Y1498780D03*
X1131850Y1591693D03*
X1140511Y1596024D03*
X1131850Y1596811D03*
X1140511Y1601142D03*
X1131850Y1622402D03*
X1149173Y1489331D03*
Y1494449D03*
Y1591693D03*
Y1596811D03*
Y1622402D03*
X1157834Y1452717D03*
X1166496Y1489331D03*
Y1494449D03*
X1157834Y1493662D03*
Y1498780D03*
X1166496Y1591693D03*
X1157834Y1596024D03*
X1166496Y1596811D03*
X1157834Y1601142D03*
X1166496Y1622402D03*
X1175157Y1452717D03*
X1183818Y1489331D03*
Y1494449D03*
X1175157Y1493662D03*
Y1498780D03*
X1183818Y1591693D03*
X1175157Y1596024D03*
X1183818Y1596811D03*
X1175157Y1601142D03*
X1183818Y1622402D03*
X1201141Y1458622D03*
Y1463741D03*
X1192480Y1452717D03*
X1201141Y1473977D03*
Y1479095D03*
Y1489331D03*
Y1494449D03*
X1192480Y1493662D03*
Y1498780D03*
X1201141Y1504685D03*
Y1509804D03*
Y1560985D03*
Y1566103D03*
Y1576339D03*
Y1581457D03*
Y1591693D03*
X1192480Y1596024D03*
X1201141Y1596811D03*
Y1607048D03*
Y1612166D03*
X1192480Y1601142D03*
X1201141Y1622402D03*
X1209803Y1452717D03*
Y1462953D03*
Y1468071D03*
Y1478308D03*
Y1483426D03*
Y1493662D03*
Y1498780D03*
Y1509016D03*
Y1514134D03*
Y1565315D03*
Y1570434D03*
Y1580670D03*
Y1585788D03*
Y1596024D03*
Y1601142D03*
Y1611378D03*
Y1616496D03*
X1313740Y1452717D03*
X1305079Y1622402D03*
X1331063Y1452717D03*
X1322402Y1622402D03*
X1348386Y1452717D03*
X1339725Y1622402D03*
X1365709Y1452717D03*
X1357047Y1622402D03*
X1383032Y1452717D03*
X1374370Y1458622D03*
Y1463741D03*
X1383032Y1462953D03*
Y1468071D03*
X1374370Y1473977D03*
Y1479095D03*
X1383032Y1478308D03*
Y1483426D03*
X1374370Y1489331D03*
Y1494449D03*
X1383032Y1493662D03*
Y1498780D03*
X1374370Y1504685D03*
Y1509804D03*
X1383032Y1509016D03*
Y1514134D03*
X1374370Y1560985D03*
Y1566103D03*
X1383032Y1565315D03*
Y1570434D03*
X1374370Y1576339D03*
Y1581457D03*
X1383032Y1580670D03*
Y1585788D03*
X1374370Y1591693D03*
X1383032Y1596024D03*
X1374370Y1596811D03*
X1383032Y1601142D03*
X1374370Y1607048D03*
Y1612166D03*
X1383032Y1611378D03*
Y1616496D03*
X1374370Y1622402D03*
X1478307Y1458622D03*
Y1463741D03*
Y1576339D03*
Y1581457D03*
Y1622402D03*
X1495630Y1458622D03*
Y1463741D03*
X1486968Y1452717D03*
Y1462953D03*
Y1468071D03*
X1495630Y1576339D03*
Y1581457D03*
X1486968Y1580670D03*
Y1585788D03*
X1495630Y1622402D03*
X1512953Y1458622D03*
Y1463741D03*
X1504291Y1452717D03*
Y1462953D03*
Y1468071D03*
X1512953Y1576339D03*
Y1581457D03*
X1504291Y1580670D03*
Y1585788D03*
X1512953Y1622402D03*
X1530275Y1458622D03*
Y1463741D03*
X1521614Y1452717D03*
Y1462953D03*
Y1468071D03*
X1530275Y1576339D03*
Y1581457D03*
X1521614Y1580670D03*
Y1585788D03*
X1530275Y1622402D03*
X1538937Y1452717D03*
Y1462953D03*
Y1468071D03*
Y1580670D03*
Y1585788D03*
X1556260Y1452717D03*
X1547598Y1458622D03*
Y1463741D03*
X1556260Y1462953D03*
Y1468071D03*
X1547598Y1473977D03*
Y1479095D03*
X1556260Y1478308D03*
Y1483426D03*
X1547598Y1489331D03*
Y1494449D03*
X1556260Y1493662D03*
Y1498780D03*
X1547598Y1504685D03*
Y1509804D03*
X1556260Y1509016D03*
Y1514134D03*
X1547598Y1560985D03*
Y1566103D03*
X1556260Y1565315D03*
Y1570434D03*
X1547598Y1576339D03*
Y1581457D03*
X1556260Y1580670D03*
Y1585788D03*
X1547598Y1591693D03*
X1556260Y1596024D03*
X1547598Y1596811D03*
X1556260Y1601142D03*
X1547598Y1607048D03*
Y1612166D03*
X1556260Y1611378D03*
Y1616496D03*
X1547598Y1622402D03*
X1660196Y1452717D03*
X1651535Y1622402D03*
X1668858D03*
X1677519Y1452717D03*
X1686181Y1622402D03*
X1694842Y1452717D03*
X1703503Y1622402D03*
X1720826Y1458622D03*
Y1463741D03*
X1712165Y1452717D03*
X1720826Y1473977D03*
Y1479095D03*
Y1489331D03*
Y1494449D03*
Y1504685D03*
Y1509804D03*
Y1560985D03*
Y1566103D03*
Y1576339D03*
Y1581457D03*
Y1591693D03*
Y1596811D03*
Y1607048D03*
Y1612166D03*
Y1622402D03*
X1729488Y1452717D03*
Y1462953D03*
Y1468071D03*
Y1478308D03*
Y1483426D03*
Y1493662D03*
Y1498780D03*
Y1509016D03*
Y1514134D03*
Y1565315D03*
Y1570434D03*
Y1580670D03*
Y1585788D03*
Y1596024D03*
Y1601142D03*
Y1611378D03*
Y1616496D03*
G54D54*
X1030635Y754546D03*
Y774546D03*
Y784546D03*
Y794546D03*
Y804546D03*
Y814546D03*
Y824546D03*
G54D28*
X116731Y1052235D03*
X106619Y1056423D03*
X102431Y1066535D03*
X106619Y1076647D03*
X116731Y1080835D03*
Y1249086D03*
X106619Y1253274D03*
X102431Y1263386D03*
X106619Y1273498D03*
X116731Y1277686D03*
X126843Y1056423D03*
Y1076647D03*
X131031Y1066535D03*
X126843Y1253274D03*
X131031Y1263386D03*
X126843Y1273498D03*
X342840Y1056423D03*
X338652Y1066535D03*
X342840Y1076647D03*
Y1253274D03*
X338652Y1263386D03*
X342840Y1273498D03*
X352952Y1052235D03*
Y1080835D03*
Y1249086D03*
Y1277686D03*
X363064Y1056423D03*
Y1076647D03*
X367252Y1066535D03*
X363064Y1253274D03*
X367252Y1263386D03*
X363064Y1273498D03*
X563706Y1056423D03*
X559518Y1066535D03*
X563706Y1076647D03*
Y1253274D03*
X559518Y1263386D03*
X563706Y1273498D03*
X583930Y1056423D03*
X573818Y1052235D03*
X583930Y1076647D03*
X588118Y1066535D03*
X573818Y1080835D03*
X583930Y1253274D03*
X573818Y1249086D03*
X588118Y1263386D03*
X573818Y1277686D03*
X583930Y1273498D03*
X760433Y1480906D03*
X756274Y1490945D03*
X760433Y1500984D03*
X780511Y1480906D03*
X770472Y1476747D03*
Y1505143D03*
X780511Y1500984D03*
X799926Y1056423D03*
X795738Y1066535D03*
X799926Y1076647D03*
Y1253274D03*
X795738Y1263386D03*
X799926Y1273498D03*
X784670Y1490945D03*
X810040Y378544D03*
X805881Y388583D03*
X810040Y398622D03*
X810038Y1052235D03*
Y1080835D03*
Y1249086D03*
Y1277686D03*
X820079Y374385D03*
X830118Y378544D03*
X820079Y402781D03*
X830118Y398622D03*
X820150Y1056423D03*
Y1076647D03*
X824338Y1066535D03*
X820150Y1253274D03*
X824338Y1263386D03*
X820150Y1273498D03*
X834277Y388583D03*
X1010827Y378544D03*
X1006668Y388583D03*
X1010827Y398622D03*
X1020866Y374385D03*
Y402781D03*
X1020793Y1056423D03*
X1016605Y1066535D03*
X1020793Y1076647D03*
Y1253274D03*
X1016605Y1263386D03*
X1020793Y1273498D03*
X1030905Y378544D03*
X1035064Y388583D03*
X1030905Y398622D03*
X1041017Y1056423D03*
X1030905Y1052235D03*
X1041017Y1076647D03*
X1030905Y1080835D03*
X1041017Y1253274D03*
X1030905Y1249086D03*
Y1277686D03*
X1041017Y1273498D03*
X1045205Y1066535D03*
Y1263386D03*
X1060433Y1480906D03*
X1056274Y1490945D03*
X1060433Y1500984D03*
X1070472Y1476747D03*
Y1505143D03*
X1080511Y1480906D03*
X1084670Y1490945D03*
X1080511Y1500984D03*
X1252825Y1066535D03*
Y1263386D03*
X1267125Y1052235D03*
X1257013Y1056423D03*
Y1076647D03*
X1267125Y1080835D03*
Y1249086D03*
X1257013Y1253274D03*
Y1273498D03*
X1267125Y1277686D03*
X1277237Y1056423D03*
Y1076647D03*
X1281425Y1066535D03*
X1277237Y1253274D03*
X1281425Y1263386D03*
X1277237Y1273498D03*
X1477879Y1056423D03*
X1473691Y1066535D03*
X1477879Y1076647D03*
Y1253274D03*
X1473691Y1263386D03*
X1477879Y1273498D03*
X1498103Y1056423D03*
X1487991Y1052235D03*
X1498103Y1076647D03*
X1487991Y1080835D03*
X1498103Y1253274D03*
X1487991Y1249086D03*
Y1277686D03*
X1498103Y1273498D03*
X1502291Y1066535D03*
Y1263386D03*
X1709912Y1066535D03*
Y1263386D03*
X1724212Y1052235D03*
X1714100Y1056423D03*
Y1076647D03*
X1724212Y1080835D03*
Y1249086D03*
X1714100Y1253274D03*
Y1273498D03*
X1724212Y1277686D03*
X1734324Y1056423D03*
Y1076647D03*
X1738512Y1066535D03*
X1734324Y1253274D03*
X1738512Y1263386D03*
X1734324Y1273498D03*
G54D41*
X281594Y1211712D03*
X270374Y1215452D03*
X393094Y1423600D03*
X395894D03*
X878220Y848442D03*
Y845293D03*
Y835844D03*
Y851592D03*
X877800Y876500D03*
X897118Y848442D03*
X881370Y835844D03*
X893968Y845293D03*
X884519Y848442D03*
X897118Y842143D03*
X893968D03*
X887669Y848442D03*
X886093Y835318D03*
X897118Y845293D03*
X893968Y838994D03*
X890818Y842143D03*
X893968Y835846D03*
X887669Y845293D03*
X890818D03*
X893968Y848442D03*
X884519Y845293D03*
X881370D03*
X884519Y842143D03*
X887669D03*
X881370Y848442D03*
X890818D03*
X887669Y851592D03*
X890818Y854742D03*
X887669D03*
X897118Y851592D03*
X890818Y864189D03*
Y857891D03*
X887669Y864189D03*
X884519Y854742D03*
Y851592D03*
Y857891D03*
X887669D03*
X890818Y851592D03*
X893967Y851591D03*
X881370Y851592D03*
X887669Y867338D03*
X890818Y870488D03*
X887669D03*
X897118Y876787D03*
X890818Y867338D03*
X881370D03*
X897118Y879937D03*
X884519Y873638D03*
X887669D03*
X884519Y876787D03*
X890818Y879937D03*
X881370Y876787D03*
X887669Y879937D03*
X884519Y867338D03*
X890818Y873638D03*
X893968Y876787D03*
Y879937D03*
X890818Y876787D03*
X884519Y879937D03*
Y870488D03*
X881370D03*
Y883086D03*
X884585Y886354D03*
X885126Y889742D03*
X881370Y886236D03*
X906565Y848442D03*
X900267D03*
X906565Y838994D03*
X900267Y838992D03*
X909714Y848442D03*
X906565Y842143D03*
X900267Y845293D03*
Y842143D03*
X906565Y845293D03*
X900266Y835844D03*
X900267Y851592D03*
X906565D03*
X909714D03*
Y876787D03*
X900267Y879937D03*
Y876787D03*
X906565D03*
X912864Y873638D03*
Y879937D03*
X909714D03*
X906565D03*
X912864Y876787D03*
X922313Y845293D03*
X916014Y848442D03*
Y842143D03*
X919163Y845293D03*
X922313Y842143D03*
X916014Y845293D03*
X919163Y835844D03*
Y838994D03*
Y842143D03*
X925462Y845293D03*
X919163Y854742D03*
Y857891D03*
X922313Y854742D03*
X916014Y857891D03*
Y854742D03*
Y851592D03*
Y864189D03*
X925462Y851592D03*
X922313Y864189D03*
Y857891D03*
X925462D03*
X928612Y864189D03*
X919163D03*
X925462D03*
X916014Y870488D03*
X925462Y873638D03*
X922313Y876787D03*
X928612Y870488D03*
X925462D03*
X916014Y873638D03*
X922313D03*
X916014Y876787D03*
X928612Y873638D03*
X925462Y876787D03*
X928612D03*
Y879937D03*
X916014D03*
X922313D03*
X919163D03*
X925462D03*
X916014Y867338D03*
X919163Y873638D03*
Y870488D03*
X922313D03*
X919163Y876787D03*
X922313Y867338D03*
X919163D03*
X925462D03*
X922313Y883086D03*
Y886236D03*
X925462D03*
X919163Y883086D03*
X928612Y886236D03*
X925462Y883086D03*
X928612D03*
X1184547Y1215452D03*
X1316906Y829871D03*
Y833021D03*
Y848769D03*
X1313756Y833021D03*
Y836170D03*
X1316906Y839320D03*
X1310555Y848675D03*
X1313756Y848769D03*
X1316906Y836170D03*
X1313756Y842470D03*
Y858218D03*
X1316906Y855068D03*
X1313756Y855066D03*
X1316906Y858218D03*
X1335803Y829871D03*
X1323205D03*
X1326355Y839320D03*
X1335803D03*
X1329504Y833021D03*
X1332654Y842470D03*
X1329504Y845619D03*
X1332654D03*
X1326355Y836170D03*
X1335803Y842470D03*
X1329504Y836170D03*
X1335803Y845619D03*
Y848769D03*
X1329504Y839320D03*
X1323205Y836170D03*
X1335803D03*
X1329504Y842470D03*
X1335803Y833021D03*
X1323205D03*
X1320055Y845619D03*
X1326355D03*
X1320055Y836170D03*
X1326355Y842470D03*
X1320055Y848769D03*
X1323205Y845619D03*
X1332654Y848769D03*
X1320055Y839320D03*
X1326355Y848769D03*
X1323205D03*
X1329504D03*
X1323204Y839319D03*
X1332654Y839320D03*
X1320055Y842470D03*
X1323205D03*
X1329504Y855068D03*
Y858218D03*
X1320055Y851918D03*
X1332654Y855068D03*
X1326355D03*
Y858218D03*
X1329504Y861367D03*
X1323205Y858218D03*
X1320055D03*
X1332654Y861367D03*
X1329504Y851918D03*
X1323205D03*
X1326355Y861367D03*
X1320055Y855068D03*
X1332654Y858218D03*
X1335803Y855068D03*
Y858218D03*
Y861367D03*
X1320055D03*
X1323204Y855067D03*
X1326355Y851918D03*
X1332654D03*
X1326355Y880263D03*
X1329504Y877114D03*
X1335803Y880263D03*
X1326355Y867665D03*
Y870814D03*
X1323205D03*
X1320055D03*
X1329504Y867665D03*
X1326355Y873964D03*
X1332654Y880263D03*
X1329504D03*
X1332654Y877114D03*
X1326355D03*
X1329504Y870814D03*
X1320055Y873964D03*
X1332654Y870814D03*
X1323204Y873965D03*
X1332654Y867665D03*
X1320055Y880263D03*
Y867665D03*
X1323205Y880263D03*
Y877114D03*
X1320055D03*
X1335803Y867665D03*
Y873964D03*
Y870814D03*
X1332654Y873964D03*
X1329504D03*
X1323205Y867665D03*
Y886562D03*
X1326355Y889712D03*
X1335803Y883413D03*
X1329504Y892862D03*
X1332654Y889712D03*
X1335803Y892862D03*
Y889712D03*
X1326355Y892862D03*
X1329504Y889712D03*
X1320055Y892862D03*
X1323205D03*
X1329504Y886562D03*
X1332654Y883413D03*
X1320055Y886562D03*
X1326355Y883413D03*
X1323205D03*
X1332654Y892862D03*
X1320055Y883413D03*
X1332654Y886562D03*
X1335803D03*
X1320055Y889712D03*
X1323204Y889713D03*
X1329504Y883413D03*
X1342103Y845619D03*
X1345252Y836170D03*
X1338953Y845619D03*
X1345252Y833021D03*
X1342103Y836170D03*
X1351550D03*
X1342103Y842470D03*
X1345252Y845619D03*
X1342103Y839320D03*
X1338953Y848769D03*
X1338952Y839319D03*
X1345252Y842470D03*
X1342103Y848769D03*
X1338953Y842470D03*
X1345252Y848769D03*
X1338953Y836170D03*
X1351550Y842470D03*
Y848769D03*
Y845619D03*
X1345252Y839320D03*
X1351550Y858218D03*
X1345252D03*
Y861367D03*
X1342103Y858218D03*
X1351550Y861367D03*
X1338953Y851918D03*
X1342103D03*
X1345252D03*
X1351550D03*
X1338953Y880263D03*
X1351550D03*
X1345252D03*
X1342103Y870814D03*
X1345252D03*
Y867665D03*
X1351550Y870814D03*
Y867665D03*
X1338953Y877114D03*
X1345252D03*
X1351550D03*
X1342103Y880263D03*
X1338953Y883413D03*
X1345252Y889712D03*
Y886562D03*
X1342103Y883413D03*
X1345252D03*
X1338952Y889713D03*
X1338953Y892862D03*
X1342103Y886562D03*
Y892862D03*
Y889712D03*
X1338953Y886562D03*
X1351550Y883413D03*
Y889712D03*
Y886562D03*
Y892862D03*
X1364148Y829871D03*
X1367298D03*
X1359425Y829000D03*
X1354699Y842470D03*
Y848769D03*
X1357849D03*
X1364148Y845619D03*
X1354699Y836170D03*
X1357849Y833021D03*
X1367298Y845619D03*
X1364148Y842470D03*
X1357850Y839319D03*
X1357849Y836170D03*
X1360999Y842470D03*
X1354699Y845619D03*
X1357849D03*
X1360999Y839320D03*
X1367298Y842470D03*
X1360999Y848769D03*
Y845619D03*
X1367298Y833021D03*
X1354699Y839320D03*
X1360999Y836170D03*
X1367298Y848769D03*
X1364148Y839320D03*
X1357849Y842470D03*
X1364148Y833021D03*
X1367298Y836170D03*
Y839320D03*
X1364148Y848769D03*
Y851918D03*
X1367298Y861367D03*
X1364148Y858218D03*
Y855068D03*
Y861367D03*
X1367298Y858218D03*
Y851918D03*
X1354699Y858218D03*
X1367298Y855068D03*
X1360999D03*
Y858218D03*
Y861367D03*
X1354699Y851918D03*
X1357849D03*
X1364148Y867665D03*
X1367298Y877114D03*
X1364148Y870814D03*
X1367298Y873964D03*
X1364148D03*
Y877114D03*
X1367298Y870814D03*
X1364148Y880263D03*
X1367298D03*
X1357849D03*
X1360999D03*
X1367298Y867665D03*
X1354699Y870814D03*
X1357849Y877114D03*
X1354699Y880263D03*
X1360999Y867665D03*
Y870814D03*
Y873964D03*
X1367298Y883413D03*
X1354699Y892862D03*
X1360999D03*
X1367298D03*
X1360999Y883413D03*
X1357850Y889713D03*
X1364148Y889712D03*
X1357849Y883413D03*
X1367298Y889712D03*
X1354699D03*
X1357849Y886562D03*
X1364148D03*
X1357849Y892862D03*
X1360999Y889712D03*
X1354699Y883413D03*
X1360999Y886562D03*
X1364148Y892862D03*
Y883413D03*
X1367298Y886562D03*
X1354699D03*
X1370447Y829871D03*
Y839320D03*
X1383046Y845619D03*
X1379896D03*
X1373597D03*
Y842470D03*
X1370447Y848769D03*
X1379896D03*
Y839320D03*
X1373597Y848769D03*
X1376747D03*
X1373597Y833021D03*
X1370447D03*
X1373597Y836170D03*
X1370447D03*
X1373598Y839319D03*
X1370447Y842470D03*
Y845619D03*
X1383046Y842470D03*
X1376747Y836170D03*
Y842470D03*
X1379896Y833021D03*
X1383046Y839320D03*
X1376747Y845619D03*
Y839320D03*
X1379896Y855068D03*
Y861367D03*
X1376747Y858218D03*
Y851918D03*
X1373597Y861367D03*
X1376747Y855068D03*
X1373597Y858218D03*
X1376747Y861367D03*
X1383046Y851918D03*
X1373597D03*
X1373598Y855067D03*
X1379896Y851918D03*
X1370447D03*
Y858218D03*
X1383046D03*
Y861367D03*
X1370447Y855068D03*
Y861367D03*
X1383046Y873964D03*
X1376747Y880263D03*
X1370447Y877114D03*
X1373598Y873965D03*
X1370447Y873964D03*
X1379896Y877114D03*
X1373597Y880263D03*
X1383046Y877114D03*
X1370447Y880263D03*
X1376747Y873964D03*
X1383046Y880263D03*
X1370447Y870814D03*
X1376747D03*
X1373597D03*
X1376747Y867665D03*
Y877114D03*
X1373597Y867665D03*
X1379896D03*
X1383046Y870814D03*
X1379896Y880263D03*
X1373597Y877114D03*
X1379896Y873964D03*
X1383046Y892862D03*
X1379896Y886562D03*
X1370447Y883413D03*
X1373598Y889713D03*
X1376747Y886562D03*
X1383046Y883413D03*
X1376747Y889712D03*
X1383046D03*
X1379896D03*
X1373597Y883413D03*
Y886562D03*
X1370447Y892862D03*
X1376747D03*
X1370447Y889712D03*
X1373597Y892862D03*
X1383046Y886562D03*
X1379896Y892862D03*
X1376747Y883413D03*
X1641634Y1215452D03*
G54D45*
X710406Y-26826D03*
Y-36826D03*
D03*
Y-26826D03*
X735406D03*
Y-36826D03*
D03*
Y-26826D03*
X830406Y-76006D03*
D03*
Y-66006D03*
D03*
X855406Y-76006D03*
D03*
Y-66006D03*
D03*
X939542Y-36798D03*
Y-26798D03*
D03*
Y-36798D03*
X964386Y-75978D03*
D03*
Y-65978D03*
D03*
X964542Y-36798D03*
Y-26798D03*
D03*
Y-36798D03*
X989386Y-75978D03*
D03*
Y-65978D03*
D03*
X993906Y-46826D03*
Y-36826D03*
D03*
Y-26826D03*
X1018906Y-46826D03*
Y-36826D03*
D03*
Y-26826D03*
X1063906Y-76006D03*
Y-86006D03*
Y-76006D03*
Y-66006D03*
X1088906Y-76006D03*
Y-86006D03*
Y-76006D03*
Y-66006D03*
X1217686Y-85978D03*
Y-75978D03*
D03*
Y-65978D03*
X1223042Y-46928D03*
Y-36928D03*
Y-26928D03*
Y-36928D03*
X1242686Y-85978D03*
Y-75978D03*
D03*
Y-65978D03*
X1248042Y-46928D03*
Y-36928D03*
Y-26928D03*
Y-36928D03*
X1280406Y-46956D03*
Y-36956D03*
D03*
Y-26956D03*
X1305406Y-46956D03*
Y-36956D03*
D03*
Y-26956D03*
X1320406Y-76006D03*
Y-86006D03*
Y-76006D03*
Y-66006D03*
X1345406Y-76006D03*
Y-86006D03*
Y-76006D03*
Y-66006D03*
X1474186Y-85978D03*
Y-75978D03*
D03*
Y-65978D03*
X1499186Y-85978D03*
Y-75978D03*
D03*
Y-65978D03*
X1509542Y-47058D03*
Y-37058D03*
Y-27058D03*
Y-37058D03*
X1534542Y-47058D03*
Y-37058D03*
Y-27058D03*
Y-37058D03*
X1564906Y-47086D03*
Y-37086D03*
D03*
Y-27086D03*
X1574906Y-76006D03*
Y-86006D03*
Y-76006D03*
Y-66006D03*
X1589906Y-47086D03*
Y-37086D03*
D03*
Y-27086D03*
X1599906Y-76006D03*
Y-86006D03*
Y-76006D03*
Y-66006D03*
X1728686Y-85978D03*
Y-75978D03*
D03*
Y-65978D03*
X1753686Y-85978D03*
Y-75978D03*
D03*
Y-65978D03*
X1794042Y-47188D03*
Y-37188D03*
Y-27188D03*
Y-37188D03*
X1819042Y-47188D03*
Y-37188D03*
Y-27188D03*
Y-37188D03*
G54D10*
X3704Y5374D03*
X3017Y24773D03*
Y44773D03*
Y64773D03*
Y84773D03*
Y104773D03*
Y124773D03*
Y144773D03*
Y164773D03*
Y184773D03*
Y204773D03*
Y224773D03*
Y244773D03*
Y264773D03*
Y284773D03*
Y304773D03*
X3221Y324773D03*
X3035Y978036D03*
Y998036D03*
Y1018036D03*
Y1038036D03*
Y1058036D03*
Y1078036D03*
Y1098036D03*
Y1118036D03*
Y1138036D03*
Y1158036D03*
Y1178036D03*
Y1198036D03*
Y1238036D03*
Y1258036D03*
Y1278036D03*
Y1298036D03*
Y1318036D03*
Y1338036D03*
Y1358036D03*
Y1378036D03*
Y1398036D03*
Y1418036D03*
Y1438036D03*
Y1458036D03*
Y1478036D03*
Y1498036D03*
Y1538036D03*
Y1558036D03*
X15972Y3000D03*
X10971Y333342D03*
X17964Y349298D03*
Y369298D03*
Y389298D03*
Y409298D03*
Y429298D03*
Y449298D03*
Y469298D03*
Y489298D03*
Y509298D03*
Y529298D03*
Y549298D03*
Y569298D03*
Y589298D03*
Y609298D03*
Y629298D03*
Y649298D03*
Y669298D03*
Y689298D03*
Y709298D03*
Y729298D03*
Y749298D03*
Y769298D03*
Y789298D03*
Y809298D03*
Y829298D03*
Y849298D03*
Y869298D03*
Y889298D03*
Y909298D03*
Y929298D03*
X9554Y961954D03*
X17964Y949298D03*
X6161Y1075991D03*
X6108Y1070611D03*
Y1065318D03*
X6059Y1091964D03*
X6055Y1086546D03*
X6053Y1081305D03*
X8042Y1522199D03*
X7922Y1532494D03*
X26956Y4469D03*
X28317Y24773D03*
Y44773D03*
X35638Y53597D03*
X36692Y641817D03*
X27934Y1204311D03*
X30934D03*
X27934Y1215511D03*
X30934D03*
X27934Y1212711D03*
Y1209911D03*
Y1207111D03*
X30934Y1212711D03*
Y1209911D03*
Y1207111D03*
X21544Y1479662D03*
X33536Y1467485D03*
X21544Y1489648D03*
X42192Y641817D03*
X51449Y822718D03*
X47949D03*
X44960Y1190619D03*
X49638Y1203884D03*
X40996Y1467703D03*
X40195Y1511279D03*
X55638Y53597D03*
X66371Y482134D03*
Y484634D03*
X60233Y521804D03*
X68202Y522129D03*
X60233Y524304D03*
X56540Y531378D03*
Y528878D03*
X68202Y527129D03*
Y524629D03*
Y529629D03*
X62789Y608311D03*
X66510Y628242D03*
X60849Y826818D03*
X64649D03*
X58949Y821018D03*
X64849Y840418D03*
X60249D03*
X74432Y5374D03*
X73745Y24773D03*
Y44773D03*
X73509Y110445D03*
Y115401D03*
X83911Y117557D03*
X80660Y103783D03*
X73509Y129574D03*
Y124618D03*
X83911Y122513D03*
Y131731D03*
Y136687D03*
X69816Y475946D03*
Y478446D03*
X78033Y478586D03*
Y481086D03*
Y476086D03*
Y483586D03*
X72549Y838818D03*
X93334Y3000D03*
X95943Y377953D03*
X113334Y3000D03*
X129318Y4469D03*
X130679Y24773D03*
Y44773D03*
X138000Y53597D03*
X146196Y390223D03*
X138194Y397335D03*
X146196Y395179D03*
Y404396D03*
Y409352D03*
X138194Y402291D03*
X135794Y416465D03*
Y411509D03*
X146196Y418569D03*
Y423525D03*
X135794Y425682D03*
Y430638D03*
X146196Y432743D03*
Y437699D03*
X135794Y439855D03*
Y444811D03*
Y468609D03*
Y473565D03*
X146196Y489895D03*
X135794Y487738D03*
X146196Y480677D03*
Y475721D03*
X135794Y482782D03*
X146196Y494851D03*
X135794Y512743D03*
Y517699D03*
X146196Y519855D03*
X135794Y526916D03*
Y531872D03*
X146196Y524811D03*
Y538984D03*
Y534028D03*
X158000Y53597D03*
X176794Y5374D03*
X176107Y24773D03*
Y44773D03*
X195697Y3000D03*
X183022Y103783D03*
X215697Y3000D03*
X231681Y4469D03*
X229745Y1446675D03*
X224753D03*
Y1462631D03*
X229745Y1457675D03*
X224753D03*
X229745Y1451631D03*
Y1462631D03*
X224753Y1451631D03*
X233042Y24773D03*
Y44773D03*
X240363Y53597D03*
X260363D03*
X279156Y5374D03*
X278469Y24773D03*
Y44773D03*
X265945Y440098D03*
Y437598D03*
Y435098D03*
Y432598D03*
Y430098D03*
X294959Y11097D03*
X285384Y103783D03*
X298059Y3000D03*
X301943Y332017D03*
X318059Y3000D03*
X318497Y466528D03*
Y471484D03*
X328899Y473640D03*
Y487813D03*
Y478596D03*
X318497Y480701D03*
Y485657D03*
X328899Y492769D03*
Y517774D03*
X318497Y510661D03*
Y515617D03*
X328899Y522730D03*
X318497Y524835D03*
X328899Y536903D03*
Y531947D03*
X318497Y529791D03*
X328899Y572769D03*
X318497Y565657D03*
Y560701D03*
X328899Y567813D03*
X318497Y579830D03*
Y574874D03*
X328899Y581987D03*
X318497Y589047D03*
X328899Y586943D03*
X318497Y594003D03*
X328899Y596160D03*
X318497Y603221D03*
X328899Y601116D03*
Y610333D03*
X318497Y608177D03*
X328899Y615289D03*
X334043Y4469D03*
X335404Y24773D03*
Y44773D03*
X342725Y53597D03*
X348737Y375386D03*
X354486Y377173D03*
X357173Y392183D03*
X357218Y396866D03*
X361234Y402867D03*
X358042Y442518D03*
Y439718D03*
X362725Y53597D03*
X361767Y392228D03*
X376992Y395248D03*
X368587Y409016D03*
X364551Y409032D03*
X361811Y396866D03*
X375919Y449118D03*
Y446318D03*
X367919Y449118D03*
Y446318D03*
X376099Y458309D03*
Y454309D03*
Y462309D03*
X369282Y468088D03*
Y465288D03*
X367816Y1310586D03*
Y1315542D03*
X388059Y3000D03*
X381518Y5374D03*
X388487Y24069D03*
X380831Y24773D03*
X383612Y30618D03*
X380831Y44773D03*
X387746Y103783D03*
X389237Y371070D03*
X385237Y370976D03*
X396373Y407104D03*
X385584Y450041D03*
Y452841D03*
Y455641D03*
X387587Y1296675D03*
X387644Y1302089D03*
X389458Y1365466D03*
X389188Y1369033D03*
X388600Y1395500D03*
X389985Y1405762D03*
X408059Y3000D03*
X396373Y409904D03*
X395577Y455641D03*
Y450041D03*
Y452841D03*
X397315Y479560D03*
X400914Y762675D03*
X408300Y755487D03*
X407965Y770196D03*
X408400Y795200D03*
Y792200D03*
X406600Y789000D03*
X402376Y842677D03*
X399876D03*
X402376Y850677D03*
X399876D03*
X395959Y1352153D03*
X403029Y1379716D03*
X403111Y1384920D03*
X408212Y1379695D03*
X394657Y1377875D03*
X403111Y1390103D03*
X408212Y1390083D03*
X410152Y1410928D03*
X398112Y1403741D03*
X415453Y455039D03*
X419040Y533690D03*
Y528390D03*
Y530990D03*
Y536290D03*
Y538890D03*
X423266Y631438D03*
X420266D03*
X417666D03*
X420266Y637038D03*
Y634238D03*
X417666Y637038D03*
Y634238D03*
X423266Y637038D03*
Y634238D03*
Y642638D03*
X420266D03*
X417666D03*
X423266Y639838D03*
X420266D03*
X417666D03*
X415696Y762466D03*
X424649Y842644D03*
X422149D03*
Y850644D03*
X424649D03*
X422149Y858644D03*
X424649D03*
X414280Y1362561D03*
X413437Y1379736D03*
Y1384899D03*
X413395Y1390062D03*
X428059Y3000D03*
X433724Y433975D03*
X432310Y436164D03*
X428740Y533690D03*
X442704Y533790D03*
X428740Y528390D03*
Y530990D03*
X442704Y528490D03*
Y531090D03*
X428740Y536290D03*
Y538890D03*
X442704Y536390D03*
Y538990D03*
X436369Y622883D03*
X441612Y631011D03*
X435881Y1394934D03*
Y1398800D03*
X448059Y3000D03*
X452404Y533690D03*
Y528390D03*
Y530990D03*
Y536290D03*
Y538890D03*
X468059Y3000D03*
X468850Y537507D03*
X461849Y668016D03*
X459349D03*
X466849D03*
X469349D03*
X464349D03*
X469349Y678016D03*
X466849D03*
X459349D03*
X461849D03*
X464349D03*
X484043Y4469D03*
X485404Y24773D03*
Y44773D03*
X482193Y472784D03*
Y468784D03*
Y476784D03*
X484341Y700528D03*
Y705484D03*
X492725Y53597D03*
X499278Y641817D03*
X493778D03*
X512725Y53597D03*
X523457Y482134D03*
Y484634D03*
X517319Y521804D03*
X513626Y528578D03*
Y531378D03*
X517319Y524304D03*
X519875Y608311D03*
X523596Y628242D03*
X531518Y5374D03*
X530831Y24773D03*
Y44773D03*
X537747Y103783D03*
X535119Y483886D03*
Y481086D03*
Y478586D03*
X526902Y478446D03*
Y475946D03*
X535119Y476086D03*
X525288Y522129D03*
Y524629D03*
Y527129D03*
Y529929D03*
X542275Y760782D03*
X532449Y782389D03*
X534672Y785037D03*
X536641Y838649D03*
X550421Y3000D03*
X542599Y782389D03*
X542546Y784911D03*
X554357Y784889D03*
X551524D03*
X570421Y3000D03*
X562231Y784911D03*
X558294D03*
X560263Y829989D03*
X568503Y936807D03*
X565003D03*
X586405Y4469D03*
X587766Y24773D03*
Y44773D03*
X583501Y800831D03*
X577903Y940907D03*
X581703D03*
X576003Y935107D03*
X581903Y954507D03*
X577303D03*
X595087Y53597D03*
X603282Y390223D03*
Y395179D03*
Y404396D03*
Y409352D03*
X595280Y402291D03*
Y397335D03*
X592880Y416465D03*
Y411509D03*
X603282Y418569D03*
Y423525D03*
X592880Y425682D03*
X603282Y432743D03*
Y437699D03*
X592880Y439855D03*
Y430638D03*
Y444811D03*
Y468609D03*
Y473565D03*
X603282Y489895D03*
X592880Y487738D03*
X603282Y480677D03*
Y475721D03*
X592880Y482782D03*
X603282Y494851D03*
X592880Y517699D03*
X603282Y519855D03*
X592880Y526916D03*
Y531872D03*
X603282Y524811D03*
Y538984D03*
Y534028D03*
X589603Y952907D03*
X615087Y53597D03*
X633248Y44884D03*
X640109Y103783D03*
X690073Y44662D03*
X697387Y53619D03*
X717387D03*
X723031Y440098D03*
Y437598D03*
Y435098D03*
Y432598D03*
Y430098D03*
X736242Y5374D03*
X735555Y24773D03*
Y44773D03*
X742471Y103783D03*
X755145Y3000D03*
X759029Y332017D03*
X775145Y3000D03*
X775584Y466528D03*
X775583Y471484D03*
Y480701D03*
Y485657D03*
Y515617D03*
Y510661D03*
Y524835D03*
Y529791D03*
Y560701D03*
Y565657D03*
Y579830D03*
Y574874D03*
Y589047D03*
Y594003D03*
Y603221D03*
Y608177D03*
X791129Y4469D03*
X792490Y24773D03*
Y44773D03*
X799811Y53597D03*
X785985Y473640D03*
Y487813D03*
Y478596D03*
Y492769D03*
Y517774D03*
Y522730D03*
Y531947D03*
Y536903D03*
Y572769D03*
Y567813D03*
Y581987D03*
Y586943D03*
Y601116D03*
Y596160D03*
Y615289D03*
Y610333D03*
X806318Y1401661D03*
X806874Y1447457D03*
X812474D03*
X806874Y1452587D03*
Y1457717D03*
X812474D03*
X815096Y1464387D03*
X812009Y1473432D03*
Y1470432D03*
X815096Y1467387D03*
X812096Y1479587D03*
Y1476587D03*
X815096Y1473387D03*
Y1479587D03*
Y1476587D03*
Y1470387D03*
X819811Y53597D03*
X829791Y839020D03*
X825721Y836666D03*
X823234Y867680D03*
X825774Y895553D03*
X816648Y1377608D03*
X817974Y1447457D03*
Y1452587D03*
Y1457717D03*
X818096Y1464387D03*
X821096D03*
X818096Y1473387D03*
X821096D03*
X824096D03*
X818096Y1479587D03*
X821096D03*
X824096D03*
X818096Y1476587D03*
X821096D03*
X824096D03*
X818096Y1467387D03*
Y1470387D03*
X821096D03*
Y1467387D03*
X824096D03*
Y1470387D03*
X838606Y5374D03*
X837919Y24773D03*
Y44773D03*
X844833Y103783D03*
X833185Y456309D03*
Y452309D03*
Y448309D03*
X850145Y3000D03*
X857973Y404867D03*
X862522Y400229D03*
X862566Y404867D03*
X857928Y400184D03*
X862020Y410899D03*
X862882Y468791D03*
Y465991D03*
X854882D03*
Y468791D03*
X861468Y491303D03*
X859071Y1447459D03*
X864671D03*
X859071Y1452589D03*
Y1457719D03*
X864671D03*
X864644Y1464759D03*
X861644D03*
X855644D03*
X858644D03*
Y1467759D03*
X855644Y1470759D03*
X858644D03*
X864644Y1467759D03*
Y1470759D03*
X861644Y1467759D03*
Y1470759D03*
X855644Y1467759D03*
Y1473759D03*
X858644D03*
X864644D03*
X861644D03*
X855644Y1476759D03*
X858644D03*
X864644D03*
X861644D03*
X872736Y383125D03*
X872318Y408589D03*
X866128Y417532D03*
X869342Y417399D03*
X880910Y471982D03*
Y469182D03*
Y466382D03*
X870882Y465991D03*
Y468791D03*
X878610Y747171D03*
X871294Y771809D03*
X871624Y1213314D03*
X874624D03*
X871624Y1221714D03*
Y1218914D03*
Y1216114D03*
X874624Y1221714D03*
Y1218914D03*
Y1216114D03*
X871624Y1224514D03*
X874624D03*
X870171Y1447459D03*
Y1452589D03*
Y1457719D03*
X867644Y1464759D03*
X870644D03*
X867644Y1467759D03*
X870644D03*
X867644Y1470759D03*
X870644D03*
X867644Y1473759D03*
X870644D03*
X867644Y1476759D03*
X870644D03*
X884736Y383125D03*
X893736D03*
X888736D03*
X891699Y420445D03*
Y423245D03*
X890903Y469182D03*
Y471982D03*
Y466382D03*
X896431Y534093D03*
X897118Y857891D03*
Y864189D03*
Y854742D03*
X893968Y864189D03*
Y857891D03*
Y854742D03*
X897118Y873638D03*
Y870488D03*
Y867338D03*
X893968Y870488D03*
Y873638D03*
Y867338D03*
X887669Y876787D03*
X888650Y1199622D03*
X893328Y1212887D03*
X912278Y343881D03*
X910779Y471380D03*
X903431Y534093D03*
X912462Y695770D03*
X912864Y848442D03*
Y845293D03*
Y842143D03*
X909714Y845293D03*
Y842143D03*
X900267Y864189D03*
X909714Y854742D03*
X906565Y857891D03*
X909714D03*
X906565Y864189D03*
X909714D03*
X906565Y854742D03*
X900267Y857891D03*
Y854742D03*
X912864Y851592D03*
Y857891D03*
Y854742D03*
X909714Y873638D03*
Y870488D03*
X906565Y873638D03*
Y870488D03*
Y867338D03*
X900267Y873638D03*
Y870488D03*
Y867338D03*
X909714D03*
X912171Y1447459D03*
X906671D03*
X901071D03*
X912171Y1457719D03*
Y1452589D03*
X906671Y1457719D03*
X901071D03*
Y1452589D03*
X908370Y1464583D03*
X905370D03*
X899370D03*
X902370D03*
X911370D03*
X905370Y1476583D03*
X908370D03*
X902370D03*
X899370D03*
X905370Y1473583D03*
X908370D03*
X902370D03*
X899370D03*
X902370Y1467583D03*
X899370Y1470583D03*
X902370D03*
X908370Y1467583D03*
Y1470583D03*
X905370Y1467583D03*
Y1470583D03*
X899370Y1467583D03*
X911370Y1476583D03*
Y1473583D03*
Y1467583D03*
Y1470583D03*
X930145Y3000D03*
X921847Y346622D03*
X927636Y452505D03*
X929050Y450316D03*
X928612Y835844D03*
X922313Y851592D03*
X929611Y858669D03*
X914370Y1464583D03*
Y1476583D03*
Y1473583D03*
Y1467583D03*
Y1470583D03*
X941129Y4469D03*
X942490Y24773D03*
Y44773D03*
X931620Y584417D03*
X931594Y599420D03*
X931647Y593271D03*
X931578Y590669D03*
X933810Y972433D03*
X935601Y1221714D03*
Y1218914D03*
Y1216114D03*
Y1213314D03*
X938601Y1221714D03*
Y1218914D03*
Y1216114D03*
Y1213314D03*
X935601Y1224514D03*
X938601D03*
X949811Y53597D03*
X956365Y641817D03*
X950865D03*
X950567Y927654D03*
X952627Y1199622D03*
X957305Y1212887D03*
X969811Y53597D03*
X976763Y307303D03*
X969623Y405614D03*
X963577Y426391D03*
X974406Y521804D03*
Y524304D03*
X970713Y531378D03*
Y528878D03*
X976962Y608311D03*
X980683Y628242D03*
X972278Y934429D03*
X988606Y5374D03*
X987919Y24773D03*
Y44773D03*
X994833Y103783D03*
X993132Y310942D03*
X993243Y321325D03*
X987055Y320273D03*
X993920Y335454D03*
X993420Y337954D03*
X992206Y478586D03*
Y481086D03*
Y483886D03*
X980544Y482134D03*
Y484634D03*
X992206Y476086D03*
X983989Y475946D03*
Y478446D03*
X982375Y522129D03*
Y527129D03*
Y524629D03*
Y529929D03*
X1007508Y3000D03*
X1004635Y300276D03*
X1008635D03*
X998667Y322239D03*
X1000420Y348954D03*
X1010119Y933822D03*
X1006619D03*
X1013683Y-44304D03*
Y-39348D03*
Y-29348D03*
Y-34304D03*
X1027508Y3000D03*
X1021895Y771974D03*
X1019519Y937922D03*
X1023319D03*
X1017619Y932122D03*
X1023519Y951522D03*
X1018919D03*
X1043492Y4469D03*
X1041496Y300276D03*
X1031354Y322905D03*
X1031219Y949922D03*
X1044853Y24773D03*
Y44773D03*
X1052174Y53597D03*
X1046674Y340031D03*
X1045966Y346808D03*
X1052367Y402291D03*
Y397335D03*
X1049967Y416465D03*
Y411509D03*
Y425682D03*
Y439855D03*
Y430638D03*
Y444811D03*
Y468609D03*
Y473565D03*
Y487738D03*
Y482782D03*
Y512743D03*
Y517699D03*
Y526916D03*
Y531872D03*
X1072174Y53597D03*
X1060369Y390223D03*
Y395179D03*
Y404396D03*
Y409352D03*
Y418569D03*
Y423525D03*
Y432743D03*
Y437699D03*
Y489895D03*
Y480677D03*
Y475721D03*
Y494851D03*
Y519855D03*
Y524811D03*
Y538984D03*
Y534028D03*
X1083683Y-78528D03*
Y-83484D03*
Y-73484D03*
Y-68528D03*
X1090280Y44773D03*
X1083483Y1523433D03*
X1097195Y103783D03*
X1147214Y44773D03*
X1154535Y53597D03*
X1174535D03*
X1176858Y306534D03*
X1180118Y430098D03*
Y440098D03*
Y437598D03*
Y435098D03*
Y432598D03*
X1193330Y5374D03*
X1192643Y24773D03*
Y44773D03*
X1199557Y103783D03*
X1192500Y322400D03*
X1199615Y950670D03*
X1201794Y985289D03*
X1212232Y3000D03*
X1221337Y332017D03*
X1232232Y3000D03*
X1232670Y466528D03*
Y471484D03*
Y480701D03*
Y485657D03*
Y515617D03*
Y510661D03*
Y524835D03*
Y529791D03*
Y565657D03*
Y560701D03*
Y579830D03*
Y589047D03*
Y574874D03*
Y603221D03*
Y594003D03*
Y608177D03*
X1248216Y4469D03*
X1249577Y24773D03*
Y44773D03*
X1243072Y473640D03*
Y487813D03*
Y478596D03*
Y492769D03*
Y522730D03*
Y517774D03*
Y536903D03*
Y531947D03*
Y567813D03*
Y572769D03*
Y586943D03*
Y581987D03*
Y601116D03*
Y596160D03*
Y610333D03*
Y615289D03*
X1256898Y53597D03*
X1266219Y374300D03*
X1268659Y377173D03*
X1276898Y53597D03*
X1275940Y392228D03*
X1271346Y392183D03*
X1275407Y402867D03*
X1271391Y396866D03*
X1275984D03*
X1282760Y409016D03*
X1278724Y409032D03*
X1272215Y442518D03*
Y439718D03*
X1282092Y449118D03*
Y446318D03*
X1283455Y468088D03*
Y465288D03*
X1300183Y-44434D03*
Y-29478D03*
Y-34434D03*
Y-39478D03*
X1302232Y3000D03*
X1295692Y5374D03*
X1303229Y23274D03*
X1295005Y24773D03*
X1297785Y30618D03*
X1295005Y44773D03*
X1301919Y103783D03*
X1303158Y371043D03*
X1299410Y370976D03*
X1291165Y395248D03*
X1290092Y449118D03*
Y446318D03*
X1299757Y450041D03*
Y452841D03*
Y455641D03*
X1290272Y458309D03*
Y454309D03*
Y462309D03*
X1310546Y409904D03*
Y407104D03*
X1309750Y455641D03*
Y450041D03*
Y452841D03*
X1311488Y479560D03*
X1309856Y899161D03*
X1305761D03*
X1313756D03*
X1322232Y3000D03*
X1320903Y370995D03*
X1333331Y370905D03*
X1329064Y370951D03*
X1329626Y455039D03*
X1340183Y-83484D03*
Y-78528D03*
Y-68528D03*
Y-73484D03*
X1342232Y3000D03*
X1338287Y370905D03*
X1347897Y433975D03*
X1346483Y436164D03*
X1362232Y3000D03*
X1382232D03*
X1373748Y397758D03*
X1375375Y428995D03*
X1398216Y4469D03*
X1399577Y24773D03*
Y44773D03*
X1397550Y390484D03*
X1387814Y397136D03*
X1389295Y408443D03*
X1386809Y414173D03*
X1388788Y428348D03*
X1406898Y53597D03*
X1416830Y407134D03*
X1411400Y398032D03*
X1413889Y415642D03*
X1413452Y641817D03*
X1407952D03*
X1426898Y53597D03*
X1431493Y521804D03*
X1427800Y528578D03*
X1431493Y524304D03*
X1427800Y531378D03*
X1422176Y1491198D03*
X1423806Y1524252D03*
X1445692Y5374D03*
X1445005Y24773D03*
Y44773D03*
X1440568Y369566D03*
X1449619Y363290D03*
X1438588Y380589D03*
X1437631Y482134D03*
Y484634D03*
X1449293Y476086D03*
X1441076Y475946D03*
Y478446D03*
X1449293Y478586D03*
Y481086D03*
Y483886D03*
X1439462Y522129D03*
Y529929D03*
Y527129D03*
Y524629D03*
X1434049Y608311D03*
X1437770Y628242D03*
X1464594Y3000D03*
X1462675Y14334D03*
X1451920Y103783D03*
X1455979Y391756D03*
X1458212Y403374D03*
X1473364Y410724D03*
X1472403Y417338D03*
X1469293Y428815D03*
X1484594Y3000D03*
X1498446Y912370D03*
X1497208Y909740D03*
X1500578Y4469D03*
X1501939Y24773D03*
Y44773D03*
X1509260Y53597D03*
X1509454Y402291D03*
Y397335D03*
X1507054Y416465D03*
Y411509D03*
Y425682D03*
Y439855D03*
Y430638D03*
Y444811D03*
Y468609D03*
Y473565D03*
Y487738D03*
Y482782D03*
Y517699D03*
Y512743D03*
Y526916D03*
Y531872D03*
X1507034Y888133D03*
X1507358Y909740D03*
X1507305Y912262D03*
X1501400Y966000D03*
X1529260Y53597D03*
X1517456Y390223D03*
Y395179D03*
Y404396D03*
Y409352D03*
Y418569D03*
Y423525D03*
Y432743D03*
Y437699D03*
Y489895D03*
Y480677D03*
Y475721D03*
Y494851D03*
Y519855D03*
Y538984D03*
Y524811D03*
Y534028D03*
X1516283Y912240D03*
X1519116D03*
X1523053Y912262D03*
X1525022Y957340D03*
X1547367Y44773D03*
X1554282Y103783D03*
X1594683Y-83484D03*
Y-78528D03*
Y-68528D03*
Y-73484D03*
X1584683Y-44564D03*
Y-29608D03*
Y-34564D03*
Y-39608D03*
X1604301Y44773D03*
X1611622Y53597D03*
X1631622D03*
X1637205Y440098D03*
Y437598D03*
Y435098D03*
Y432598D03*
Y430098D03*
X1650417Y5374D03*
X1649730Y24773D03*
Y44773D03*
X1656644Y103783D03*
X1669319Y3001D03*
X1673203Y332017D03*
X1689319Y3001D03*
X1689757Y466528D03*
Y471484D03*
Y480701D03*
Y485657D03*
Y515617D03*
Y510661D03*
Y524835D03*
Y529791D03*
Y565657D03*
Y560701D03*
Y589047D03*
Y574874D03*
Y579830D03*
Y603221D03*
Y594003D03*
Y608177D03*
X1705303Y4470D03*
X1706664Y24774D03*
Y44774D03*
X1700159Y473640D03*
Y487813D03*
Y478596D03*
Y492769D03*
Y517774D03*
Y522730D03*
Y536903D03*
Y531947D03*
Y572769D03*
Y567813D03*
Y586943D03*
Y581987D03*
Y601116D03*
Y596160D03*
Y610333D03*
Y615289D03*
X1713985Y53598D03*
X1725746Y377173D03*
X1723964Y370935D03*
X1733985Y53598D03*
X1733027Y392228D03*
X1728433Y392183D03*
X1739847Y409016D03*
X1735811Y409032D03*
X1732494Y402867D03*
X1728478Y396866D03*
X1733071D03*
X1729302Y439718D03*
Y442518D03*
X1739179Y449118D03*
Y446318D03*
X1740542Y468088D03*
Y465288D03*
X1752778Y5374D03*
X1752091Y24773D03*
Y44773D03*
X1756497Y370976D03*
X1748252Y395248D03*
X1756844Y450041D03*
Y452841D03*
Y455641D03*
X1747179Y449118D03*
Y446318D03*
X1747359Y454309D03*
Y458309D03*
Y462309D03*
X1765559Y3001D03*
X1759006Y103783D03*
X1760497Y371070D03*
X1767633Y409904D03*
Y407104D03*
X1766837Y450041D03*
Y452841D03*
Y455641D03*
X1768575Y479560D03*
X1773600Y888100D03*
X1773614Y895275D03*
X1773600Y902800D03*
X1786713Y455039D03*
X1788400Y888100D03*
X1781000Y888087D03*
X1788396Y895066D03*
X1788300Y902800D03*
X1780665Y902796D03*
X1781263Y964660D03*
X1784763D03*
X1779581Y1222200D03*
Y1219400D03*
Y1216600D03*
Y1213800D03*
X1782581Y1222200D03*
Y1219400D03*
Y1216600D03*
Y1213800D03*
X1779581Y1225000D03*
X1782581D03*
X1804984Y433975D03*
X1803570Y436164D03*
X1794163Y968760D03*
X1797963D03*
X1792263Y962960D03*
X1798163Y982360D03*
X1793563D03*
X1805863Y980760D03*
X1796607Y1200108D03*
X1801285Y1213373D03*
X1822983Y346053D03*
Y366053D03*
Y386053D03*
Y406053D03*
Y426053D03*
Y446053D03*
Y466053D03*
Y486053D03*
Y506053D03*
Y526053D03*
Y546053D03*
Y566053D03*
Y586053D03*
Y606053D03*
Y626053D03*
Y646053D03*
Y666053D03*
Y686053D03*
Y706053D03*
Y726053D03*
Y746053D03*
Y766053D03*
Y786053D03*
Y806053D03*
Y826053D03*
Y846053D03*
Y866053D03*
Y886053D03*
Y906053D03*
Y926053D03*
Y946053D03*
X1825559Y3001D03*
X1836543Y4470D03*
X1837904Y24774D03*
Y44774D03*
Y64774D03*
Y84774D03*
Y104774D03*
Y124774D03*
Y144774D03*
Y164774D03*
Y184774D03*
Y204774D03*
Y224774D03*
Y244774D03*
Y264774D03*
Y284774D03*
Y304774D03*
X1837728Y324733D03*
X1830094Y333210D03*
X1830472Y960970D03*
X1837937Y973244D03*
Y993244D03*
Y1013244D03*
Y1033244D03*
Y1053244D03*
Y1073244D03*
X1824733Y1102830D03*
X1837937Y1093244D03*
X1825832Y1097589D03*
X1837937Y1113244D03*
Y1133244D03*
Y1153244D03*
Y1173244D03*
Y1193244D03*
Y1213244D03*
Y1253244D03*
Y1273244D03*
Y1293244D03*
Y1313244D03*
Y1333244D03*
Y1353244D03*
Y1373244D03*
Y1393244D03*
Y1433244D03*
Y1453244D03*
Y1473244D03*
Y1493244D03*
Y1513244D03*
Y1533244D03*
Y1553244D03*
Y1573244D03*
G54D14*
X20408Y51296D03*
Y55296D03*
X9057Y138939D03*
X19184Y144728D03*
X15184D03*
X15520Y195176D03*
X18320D03*
X13020D03*
X10520D03*
X12880Y203393D03*
X10380D03*
X19068Y206838D03*
X16568D03*
X13606Y1476707D03*
X19365Y1494298D03*
X24316Y67527D03*
Y63527D03*
Y59527D03*
X23184Y144728D03*
X35650Y487982D03*
Y478982D03*
Y483982D03*
Y499982D03*
X25819Y531726D03*
Y536726D03*
Y552726D03*
Y540726D03*
X30410Y1218497D03*
Y1220997D03*
Y1234797D03*
Y1232297D03*
Y1227897D03*
Y1225397D03*
Y1241697D03*
Y1239197D03*
X25674Y1486291D03*
X32195Y1511279D03*
X32079Y1521641D03*
X31237Y1532096D03*
X46240Y109410D03*
X45988Y102323D03*
X46240Y116496D03*
X46931Y130670D03*
X49236Y121658D03*
X46932Y137756D03*
X49839Y546830D03*
X44195Y1511279D03*
X39237Y1532096D03*
X64098Y102323D03*
Y109410D03*
Y116496D03*
Y123583D03*
Y130670D03*
Y137756D03*
X69139Y236611D03*
X68841Y248891D03*
X66224Y473045D03*
X58224D03*
X53643Y472905D03*
X59670Y500086D03*
X64495Y527449D03*
X61695D03*
X60554Y1612002D03*
X66291Y1633801D03*
X74139Y236611D03*
X71639D03*
X71341Y248891D03*
X73841D03*
X74326Y480705D03*
X71995Y532749D03*
X74795D03*
X74291Y1633801D03*
X86291D03*
X119582Y102249D03*
X111582D03*
X115582D03*
X115382Y195176D03*
X112882D03*
X117882D03*
X115242Y203393D03*
X112742D03*
X120682Y195176D03*
X118930Y206838D03*
X121430D03*
X148602Y109410D03*
Y116496D03*
X148350Y102323D03*
X148774Y124576D03*
X149827Y130670D03*
X149822Y137756D03*
X166460Y116496D03*
Y109410D03*
Y102323D03*
Y123583D03*
Y130670D03*
Y137756D03*
X174001Y236611D03*
X176501D03*
X171501D03*
X176203Y248891D03*
X173703D03*
X171203D03*
X185169Y389154D03*
Y396240D03*
X186448Y404911D03*
X186589Y426299D03*
X185402Y412571D03*
X186900Y445847D03*
X185169Y467539D03*
Y474626D03*
X185430Y480828D03*
X187380Y498834D03*
X185169Y518760D03*
Y511673D03*
Y525847D03*
X191125Y602400D03*
Y598400D03*
Y594400D03*
Y606400D03*
Y614400D03*
X203591Y91951D03*
X213944Y102249D03*
X215244Y195176D03*
X215104Y203393D03*
X203280Y389154D03*
Y396240D03*
Y403327D03*
Y410413D03*
Y417500D03*
Y424586D03*
Y431673D03*
Y438760D03*
Y445847D03*
Y467539D03*
Y474626D03*
Y488799D03*
Y481713D03*
Y495886D03*
Y511673D03*
Y518760D03*
Y525847D03*
Y532933D03*
Y540020D03*
Y547106D03*
Y554193D03*
Y602205D03*
Y595118D03*
X221944Y102249D03*
X217944D03*
X220244Y195176D03*
X217744D03*
X223044D03*
X223792Y206838D03*
X221292D03*
X217604Y203393D03*
X228267Y392718D03*
Y408718D03*
Y400718D03*
Y404718D03*
Y412718D03*
X250964Y109410D03*
X250712Y102323D03*
X250964Y116496D03*
X251136Y124576D03*
X252189Y130670D03*
X252184Y137756D03*
X268822Y116496D03*
Y109410D03*
Y102323D03*
Y130670D03*
Y123583D03*
Y137756D03*
X276363Y236611D03*
X278863D03*
X273863D03*
X276065Y248891D03*
X273565D03*
X278565D03*
X274205Y466027D03*
X274347Y475262D03*
Y489435D03*
Y482666D03*
X274163Y495088D03*
X274205Y509626D03*
X274820Y522134D03*
X274898Y514608D03*
X275463Y529136D03*
X275302Y535677D03*
X274586Y565574D03*
X274205Y559665D03*
X274233Y574338D03*
X274332Y616358D03*
X292500Y410394D03*
Y403307D03*
X284295Y430760D03*
X284316Y433570D03*
X284132Y437072D03*
X284173Y439963D03*
X284417Y443180D03*
X284437Y454744D03*
X284379Y452018D03*
X292316Y458406D03*
Y465492D03*
Y472579D03*
Y479665D03*
Y486752D03*
Y493839D03*
Y523799D03*
Y516713D03*
Y509626D03*
Y537973D03*
Y530886D03*
Y559665D03*
Y566752D03*
Y573839D03*
Y588012D03*
Y580925D03*
Y595099D03*
Y602185D03*
Y616358D03*
Y609272D03*
X324306Y102249D03*
X320306D03*
X316306D03*
X322606Y195176D03*
X325406D03*
X320106D03*
X317606D03*
X323654Y206838D03*
X319966Y203393D03*
X317466D03*
X326154Y206838D03*
X319857Y321649D03*
X324291Y556775D03*
X353074Y102323D03*
X353326Y109410D03*
Y116496D03*
X353498Y124576D03*
X354551Y130670D03*
X354546Y137756D03*
X371184Y116496D03*
Y109410D03*
Y102323D03*
Y130670D03*
Y123583D03*
Y137756D03*
X376225Y236611D03*
X375927Y248891D03*
X373101Y779608D03*
X376300Y779800D03*
X370214Y959812D03*
Y967812D03*
X381225Y236611D03*
X378725D03*
X378427Y248891D03*
X380927D03*
X379800Y778000D03*
X387692Y790056D03*
X393547D03*
X386614Y868286D03*
X385512Y955356D03*
X390150Y955312D03*
Y959905D03*
X385467Y959950D03*
X409268Y408240D03*
X409386Y420393D03*
X400900Y755400D03*
Y770100D03*
X407193Y883566D03*
X396182Y955858D03*
X402682Y948536D03*
X402815Y951750D03*
X404004Y1198321D03*
Y1200821D03*
X407469Y1495035D03*
X407854Y1492118D03*
X406377Y1499142D03*
X411768Y408240D03*
X414268D03*
X411847Y424240D03*
X414386Y420393D03*
X411886D03*
X411847Y426740D03*
X415700Y755400D03*
Y770200D03*
X422430Y834800D03*
X422379Y867229D03*
X420661Y1119422D03*
X423141Y1113822D03*
Y1119422D03*
X418181Y1113822D03*
Y1119422D03*
X420661Y1113822D03*
X417469Y1200821D03*
Y1198321D03*
X439804Y536682D03*
Y539182D03*
X430934Y1200821D03*
Y1198321D03*
X430657Y1563562D03*
X446179Y447101D03*
X448726Y653288D03*
Y646480D03*
Y648980D03*
Y655788D03*
X450244Y1090268D03*
Y1093068D03*
X455269Y1119422D03*
X450309Y1113822D03*
Y1119422D03*
X452789Y1113822D03*
Y1119422D03*
X455269Y1113822D03*
X474307Y102249D03*
X470307D03*
X466307D03*
X470107Y195176D03*
X467607D03*
X472607D03*
X475407D03*
X473655Y206838D03*
X467467Y203393D03*
X469967D03*
X463104Y536582D03*
Y539082D03*
X476155Y206838D03*
X492736Y478982D03*
X482905Y531726D03*
X482737Y537215D03*
X482905Y552726D03*
Y540726D03*
X488728Y1119422D03*
X483768Y1113822D03*
X486248D03*
Y1119422D03*
X483768D03*
X488728Y1113822D03*
X477206Y1198321D03*
X490671D03*
Y1200821D03*
X477206D03*
X503075Y102323D03*
X503327Y109410D03*
Y116496D03*
X506653Y121652D03*
X504552Y130670D03*
X504547Y137756D03*
X493485Y439903D03*
X492736Y487982D03*
Y483982D03*
Y499982D03*
X506925Y546830D03*
X504136Y1198321D03*
Y1200821D03*
X521185Y116496D03*
Y109410D03*
Y102323D03*
Y130670D03*
Y123583D03*
Y137756D03*
X508729Y469905D03*
X521310Y470045D03*
X513310D03*
X516756Y500086D03*
X518781Y527449D03*
X521581D03*
X518812Y665867D03*
X515831Y1090568D03*
Y1093068D03*
X518376Y1113822D03*
Y1119422D03*
X520856Y1113822D03*
Y1119422D03*
X515896Y1113822D03*
Y1119422D03*
X526226Y236611D03*
X531226D03*
X528726D03*
X528428Y248891D03*
X530928D03*
X525928D03*
X531412Y480705D03*
X528612D03*
X529481Y532849D03*
X532281D03*
X533486Y664052D03*
X538442D03*
X524941Y661387D03*
X530796D03*
X572669Y102249D03*
X568669D03*
X572469Y195176D03*
X572329Y203393D03*
X567559Y812850D03*
X576669Y102249D03*
X574969Y195176D03*
X577769D03*
X578517Y206838D03*
X576017D03*
X605437Y102323D03*
X605689Y109410D03*
Y116496D03*
X605861Y124576D03*
X606914Y130670D03*
X606909Y137756D03*
X623547Y109410D03*
Y116496D03*
Y102323D03*
Y123583D03*
Y130670D03*
Y137756D03*
X633588Y236611D03*
X631088D03*
X628588D03*
X630790Y248891D03*
X633290D03*
X628290D03*
X642255Y389154D03*
Y396240D03*
X643534Y404911D03*
X642488Y412571D03*
X643675Y426299D03*
X643986Y445847D03*
X642255Y467539D03*
Y474626D03*
X642516Y480828D03*
X644466Y498834D03*
X642255Y518760D03*
Y511673D03*
Y525847D03*
X648211Y602400D03*
Y598400D03*
Y594400D03*
Y606400D03*
Y614400D03*
X660366Y389154D03*
Y403327D03*
Y410413D03*
Y396240D03*
Y417500D03*
Y424586D03*
Y431673D03*
Y438760D03*
Y445847D03*
Y467539D03*
Y474626D03*
Y488799D03*
Y481713D03*
Y495886D03*
Y511673D03*
Y518760D03*
Y525847D03*
Y532933D03*
Y540020D03*
Y554193D03*
Y547106D03*
Y602205D03*
Y595118D03*
X679031Y102249D03*
X672331Y195176D03*
X674831D03*
X680131D03*
X672191Y203393D03*
X674691D03*
X678379Y206838D03*
X680879D03*
X685353Y392718D03*
Y408718D03*
Y400718D03*
Y404718D03*
Y412718D03*
X707799Y102323D03*
X708051Y109410D03*
Y116496D03*
X708223Y124576D03*
X709276Y130670D03*
X709271Y137756D03*
X725909Y102323D03*
Y116496D03*
Y109410D03*
Y130670D03*
Y123583D03*
Y137756D03*
X733450Y236611D03*
X730950D03*
X733152Y248891D03*
X730652D03*
X731291Y466027D03*
X731433Y475262D03*
Y489435D03*
Y482666D03*
X731249Y495088D03*
X731984Y514608D03*
X731906Y522134D03*
X731291Y509626D03*
X732549Y529136D03*
X732388Y535677D03*
X731291Y559665D03*
X731672Y565574D03*
X731319Y574338D03*
X731418Y616358D03*
X735950Y236611D03*
X735652Y248891D03*
X749586Y410394D03*
Y403307D03*
X741259Y439963D03*
X741381Y430760D03*
X741402Y433570D03*
X741218Y437072D03*
X741503Y443180D03*
X741523Y454744D03*
X741465Y452018D03*
X749402Y458406D03*
Y465492D03*
Y472579D03*
Y479665D03*
Y486752D03*
Y493839D03*
Y523799D03*
Y516713D03*
Y509626D03*
Y537973D03*
Y530886D03*
Y559665D03*
Y566752D03*
Y573839D03*
Y588012D03*
Y580925D03*
Y602185D03*
Y595099D03*
Y609272D03*
Y616358D03*
X751140Y1581335D03*
X740640Y1586885D03*
X748924Y1617709D03*
X735878Y1617010D03*
X763040Y91951D03*
X781393Y102249D03*
X777393D03*
X773393D03*
X779693Y195176D03*
X777193D03*
X782493D03*
X774693D03*
X780741Y206838D03*
X783241D03*
X777053Y203393D03*
X774553D03*
X776943Y321649D03*
X778985Y442498D03*
X778881Y446510D03*
X779029Y450510D03*
X777033Y1595215D03*
X781545Y1602835D03*
X774658Y1601012D03*
X792564Y406410D03*
X784586Y421000D03*
Y418500D03*
Y413500D03*
Y416000D03*
X784665Y564843D03*
X787447Y1593586D03*
X791610Y1593708D03*
X810161Y102323D03*
X810413Y109410D03*
Y116496D03*
X810585Y124576D03*
X811638Y130670D03*
X811633Y137756D03*
X828271Y116496D03*
Y109410D03*
Y102323D03*
Y130670D03*
Y123583D03*
Y137756D03*
X835812Y236611D03*
X838312D03*
X833312D03*
X833014Y248891D03*
X838014D03*
X835514D03*
X867093Y570703D03*
Y582828D03*
Y558703D03*
Y562703D03*
Y566703D03*
Y578703D03*
X872440Y1230083D03*
Y1227583D03*
Y1234483D03*
Y1236983D03*
Y1243883D03*
Y1241383D03*
Y1248283D03*
Y1250783D03*
X889436Y715970D03*
X905094Y424581D03*
X902594D03*
X907594D03*
X905212Y436734D03*
X902712D03*
X907712D03*
X907173Y440581D03*
Y443081D03*
X909024Y578394D03*
Y574394D03*
X909714Y838994D03*
X931393Y102249D03*
X923393D03*
X927393D03*
X925359Y180347D03*
X927859D03*
X925219Y188564D03*
X927719D03*
X919606Y231000D03*
X919577Y245669D03*
Y233858D03*
X919682Y236921D03*
X919577Y259843D03*
Y255118D03*
X919729Y274580D03*
X930359Y180347D03*
X933159D03*
X931407Y192009D03*
X933907D03*
X941505Y463442D03*
X939827Y531104D03*
X939992Y536726D03*
Y540726D03*
Y552726D03*
X936417Y1234483D03*
Y1236983D03*
Y1230083D03*
Y1227583D03*
Y1243883D03*
Y1241383D03*
Y1248283D03*
Y1250783D03*
X956460Y-35982D03*
X953207Y-35996D03*
X956445Y-38497D03*
X953192Y-38511D03*
X950167Y-37191D03*
X960161Y102323D03*
X960413Y109410D03*
Y116496D03*
X961638Y130670D03*
X961633Y137756D03*
X950315Y464851D03*
X949823Y487982D03*
X949876Y478486D03*
X949823Y483982D03*
Y499982D03*
X978036Y-77691D03*
X978051Y-75176D03*
X975011Y-76371D03*
X978271Y109410D03*
Y102323D03*
Y116496D03*
Y130670D03*
Y123583D03*
X963360Y121459D03*
X978271Y137756D03*
X977150Y328472D03*
Y335472D03*
X967816Y472905D03*
X972397Y472954D03*
X973843Y500086D03*
X978668Y527449D03*
X975868D03*
X964012Y546830D03*
X978857Y1360945D03*
X981289Y-77677D03*
X981304Y-75162D03*
X985812Y236611D03*
X988312D03*
X983312D03*
X983014Y248891D03*
X988014D03*
X985514D03*
X980397Y473045D03*
X985699Y480705D03*
X988499D03*
X989068Y532949D03*
X986268D03*
X981857Y1360945D03*
X978944Y1413859D03*
X981944D03*
X1007611Y1561247D03*
Y1558247D03*
Y1555247D03*
Y1552247D03*
X1004611Y1561247D03*
Y1558247D03*
Y1555247D03*
Y1552247D03*
X1015402Y91951D03*
X1025755Y102249D03*
X1027055Y195176D03*
X1033755Y102249D03*
X1029755D03*
X1032055Y195176D03*
X1029555D03*
X1034855D03*
X1033103Y206838D03*
X1035603D03*
X1029415Y203393D03*
X1062523Y102323D03*
X1062775Y109410D03*
Y116496D03*
X1062947Y124576D03*
X1064000Y130670D03*
X1063995Y137756D03*
X1080633Y102323D03*
Y116496D03*
Y109410D03*
Y130670D03*
Y123583D03*
Y137756D03*
X1085674Y236611D03*
X1088174D03*
X1090674D03*
X1090376Y248891D03*
X1087876D03*
X1085376D03*
X1077855Y327478D03*
X1077252Y323521D03*
Y318565D03*
X1077855Y332434D03*
X1099342Y389154D03*
Y396240D03*
X1100621Y404911D03*
X1099575Y412571D03*
X1100762Y426299D03*
X1101073Y445847D03*
X1099342Y467539D03*
Y474626D03*
X1099603Y480828D03*
X1101553Y498834D03*
X1099342Y518760D03*
Y511673D03*
Y525847D03*
X1105298Y598400D03*
Y602400D03*
Y594400D03*
Y614400D03*
Y606400D03*
X1117764Y91951D03*
X1117453Y389154D03*
Y396240D03*
Y403327D03*
Y410413D03*
Y417500D03*
Y424586D03*
Y431673D03*
Y438760D03*
Y445847D03*
Y467539D03*
Y474626D03*
Y488799D03*
Y481713D03*
Y495886D03*
Y511673D03*
Y518760D03*
Y525847D03*
Y532933D03*
Y540020D03*
Y554193D03*
Y547106D03*
Y602205D03*
Y595118D03*
X1136117Y102249D03*
X1132117D03*
X1128117D03*
X1134417Y195176D03*
X1131917D03*
X1137217D03*
X1129417D03*
X1137965Y206838D03*
X1131777Y203393D03*
X1135465Y206838D03*
X1142440Y404718D03*
Y412718D03*
X1125287Y592897D03*
X1142440Y392718D03*
Y400718D03*
Y408718D03*
X1164885Y102323D03*
X1165137Y109410D03*
Y116496D03*
X1165309Y124576D03*
X1166362Y130670D03*
X1166357Y137756D03*
X1182995Y116496D03*
Y109410D03*
Y102323D03*
Y130670D03*
Y123583D03*
Y137756D03*
X1188036Y236611D03*
X1187738Y248891D03*
X1188378Y466027D03*
X1188520Y475262D03*
Y489435D03*
Y482666D03*
X1188336Y495088D03*
X1189071Y514608D03*
X1188993Y522134D03*
X1188378Y509626D03*
X1189475Y535677D03*
X1189636Y529136D03*
X1188378Y559665D03*
X1188759Y565574D03*
X1188406Y574338D03*
X1188505Y616358D03*
X1190536Y236611D03*
X1193036D03*
X1192738Y248891D03*
X1190238D03*
X1198468Y430760D03*
X1198489Y433570D03*
X1198305Y437072D03*
X1198346Y439963D03*
X1198552Y452018D03*
X1198590Y443180D03*
X1198610Y454744D03*
X1220126Y91951D03*
X1206673Y410394D03*
Y403307D03*
X1206489Y458406D03*
Y465492D03*
Y472579D03*
Y479665D03*
Y486752D03*
Y493839D03*
Y523799D03*
Y516713D03*
Y509626D03*
Y537973D03*
Y530886D03*
Y566752D03*
Y559665D03*
Y580925D03*
Y588012D03*
Y573839D03*
Y602185D03*
Y595099D03*
Y616358D03*
Y609272D03*
X1231336Y-87691D03*
X1234589Y-87777D03*
X1231351Y-85176D03*
X1234604Y-85262D03*
X1228311Y-86371D03*
X1236692Y-48727D03*
X1236707Y-46212D03*
X1233667Y-47421D03*
X1238479Y102249D03*
X1230479D03*
X1234479D03*
X1236779Y195176D03*
X1234279D03*
X1239579D03*
X1231779D03*
X1234139Y203393D03*
X1231639D03*
X1237827Y206838D03*
X1234100Y322924D03*
X1239945Y-48727D03*
X1239960Y-46212D03*
X1240327Y206838D03*
X1241752Y564843D03*
X1267499Y116496D03*
X1267247Y102323D03*
X1267499Y109410D03*
X1267671Y124576D03*
X1268724Y130670D03*
X1268719Y137756D03*
X1259500Y330000D03*
X1285357Y116496D03*
Y109410D03*
Y102323D03*
Y123583D03*
Y130670D03*
Y137756D03*
X1281834Y374839D03*
X1290398Y236611D03*
X1295398D03*
X1292898D03*
X1290100Y248891D03*
X1292600D03*
X1295100D03*
X1301500Y329000D03*
X1292731Y331820D03*
X1300400Y339619D03*
Y344575D03*
X1290066Y804246D03*
X1319000Y566500D03*
Y582500D03*
Y613000D03*
Y629000D03*
Y657500D03*
Y673500D03*
Y704500D03*
Y720500D03*
X1305412Y799061D03*
X1318178Y1198321D03*
Y1200821D03*
X1325941Y408240D03*
X1328441D03*
X1323441D03*
X1326059Y420393D03*
X1326020Y424240D03*
X1323559Y420393D03*
X1328559D03*
X1326020Y426740D03*
X1335802Y896011D03*
X1332355Y1113822D03*
Y1119422D03*
X1334835Y1113822D03*
Y1119422D03*
X1331643Y1200821D03*
Y1198321D03*
X1344768Y769675D03*
X1337315Y1113822D03*
Y1119422D03*
X1345108Y1200821D03*
Y1198321D03*
X1361039Y327099D03*
Y332055D03*
X1364039Y334973D03*
Y339929D03*
X1361039Y342847D03*
X1364039Y350721D03*
X1361039Y347803D03*
X1364039Y355677D03*
X1360352Y447101D03*
X1364148Y896011D03*
X1364418Y1090568D03*
Y1093068D03*
X1366963Y1119422D03*
Y1113822D03*
X1364483Y1119422D03*
Y1113822D03*
X1380480Y102249D03*
X1384480D03*
X1384280Y195176D03*
X1381780D03*
X1384140Y203393D03*
X1381640D03*
X1384253Y346826D03*
X1384447Y356871D03*
X1384174Y362641D03*
X1379896Y870814D03*
Y883413D03*
X1383046Y899161D03*
X1369443Y1119422D03*
Y1113822D03*
X1388480Y102249D03*
X1389580Y195176D03*
X1386780D03*
X1390328Y206838D03*
X1387828D03*
X1385943Y323222D03*
X1385971Y327688D03*
X1386143Y331982D03*
X1386057Y341200D03*
X1385971Y336791D03*
X1386286Y350218D03*
X1397079Y531726D03*
Y536726D03*
Y552726D03*
Y540726D03*
X1397942Y1119422D03*
X1400422D03*
Y1113822D03*
X1397942D03*
X1391380Y1200821D03*
Y1198321D03*
X1417248Y102323D03*
X1416347Y384373D03*
X1406910Y487982D03*
Y478982D03*
Y483982D03*
Y499982D03*
X1410000Y689000D03*
Y705000D03*
Y733000D03*
Y749000D03*
X1402902Y1119422D03*
Y1113822D03*
X1404845Y1198321D03*
Y1200821D03*
X1404239Y1547755D03*
X1403747Y1570433D03*
X1417500Y109410D03*
Y116496D03*
X1421700Y122900D03*
X1418725Y130670D03*
X1418720Y137756D03*
X1427484Y470045D03*
X1422903Y469905D03*
X1430930Y500086D03*
X1432955Y527449D03*
X1421099Y546830D03*
X1427000Y774500D03*
Y790500D03*
Y818500D03*
Y834500D03*
X1430005Y1090568D03*
Y1093068D03*
X1432550Y1119422D03*
Y1113822D03*
X1430070Y1119422D03*
Y1113822D03*
X1418310Y1198321D03*
Y1200821D03*
X1435358Y116496D03*
Y109410D03*
Y102323D03*
Y130670D03*
Y123583D03*
Y137756D03*
X1440399Y236611D03*
X1442899D03*
X1445399D03*
X1440101Y248891D03*
X1442601D03*
X1445101D03*
X1435484Y470045D03*
X1442786Y480705D03*
X1445586D03*
X1435755Y527449D03*
X1443555Y532949D03*
X1446355D03*
X1435030Y1119422D03*
Y1113822D03*
X1437293Y1546125D03*
X1436801Y1568803D03*
X1451215Y323193D03*
X1451330Y327588D03*
X1451272Y340971D03*
X1451344Y336620D03*
X1451300Y332225D03*
X1451387Y345609D03*
X1451186Y350447D03*
X1472489Y91951D03*
X1479500Y706500D03*
Y750500D03*
X1487836Y-87777D03*
X1491089D03*
X1487851Y-85262D03*
X1491104D03*
X1484811Y-86371D03*
X1490842Y102249D03*
X1486842D03*
X1482842D03*
X1486642Y195176D03*
X1489142D03*
X1484142D03*
X1491942D03*
X1492690Y206838D03*
X1490190D03*
X1484002Y203393D03*
X1486502D03*
X1484796Y320359D03*
X1484968Y325025D03*
X1484876Y329377D03*
X1488255Y342921D03*
X1484682Y338394D03*
X1497760Y336543D03*
X1487926Y347387D03*
X1496500Y792000D03*
Y836000D03*
X1500480Y295727D03*
X1523192Y-48857D03*
X1526445D03*
X1523207Y-46342D03*
X1526460D03*
X1520167Y-47451D03*
X1519610Y102323D03*
X1519862Y109410D03*
Y116496D03*
X1520034Y124576D03*
X1521087Y130670D03*
X1521082Y137756D03*
X1527876Y939439D03*
X1537720Y116496D03*
Y109410D03*
Y102323D03*
Y130670D03*
Y123583D03*
Y137756D03*
X1542761Y236611D03*
X1545261D03*
X1542463Y248891D03*
X1544963D03*
X1541534Y322850D03*
X1547761Y236611D03*
X1547463Y248891D03*
X1547972Y304906D03*
X1556151Y318596D03*
X1556294Y327814D03*
X1556437Y332022D03*
X1556380Y336917D03*
X1556498Y340958D03*
X1556353Y345636D03*
X1556429Y389154D03*
Y396240D03*
X1557708Y404911D03*
X1556662Y412571D03*
X1557849Y426299D03*
X1558160Y445847D03*
X1556429Y467539D03*
Y474626D03*
X1556690Y480828D03*
X1558640Y498834D03*
X1556429Y518760D03*
Y511673D03*
Y525847D03*
X1562385Y598400D03*
Y602400D03*
Y594400D03*
Y614400D03*
Y606400D03*
X1574851Y91951D03*
X1574845Y338843D03*
X1574540Y389154D03*
Y396240D03*
Y403327D03*
Y410413D03*
Y417500D03*
Y424586D03*
Y438760D03*
Y431673D03*
Y445847D03*
Y467539D03*
Y474626D03*
Y488799D03*
Y481713D03*
Y495886D03*
Y511673D03*
Y518760D03*
Y540020D03*
Y525847D03*
Y532933D03*
Y547106D03*
Y554193D03*
Y602205D03*
Y595118D03*
X1593204Y102249D03*
X1585204D03*
X1589204D03*
X1586504Y195176D03*
X1594304D03*
X1589004D03*
X1591504D03*
X1586364Y203393D03*
X1588864D03*
X1595052Y206838D03*
X1592552D03*
X1593290Y339876D03*
X1597006Y290417D03*
X1599527Y392718D03*
Y408718D03*
Y400718D03*
Y404718D03*
Y412718D03*
X1621972Y102323D03*
X1622224Y109410D03*
Y116496D03*
X1622396Y124576D03*
X1623449Y130670D03*
X1623444Y137756D03*
X1640082Y116496D03*
Y109410D03*
Y102323D03*
Y130670D03*
Y123583D03*
Y137756D03*
X1644825Y248891D03*
X1632230Y330400D03*
X1645123Y236611D03*
X1650123D03*
X1647623D03*
X1647325Y248891D03*
X1649825D03*
X1655555Y430760D03*
X1655576Y433570D03*
X1655392Y437072D03*
X1655433Y439963D03*
X1655677Y443180D03*
X1655697Y454744D03*
X1655639Y452018D03*
X1645465Y466027D03*
X1645607Y475262D03*
Y489435D03*
Y482666D03*
X1645423Y495088D03*
X1646158Y514608D03*
X1646080Y522134D03*
X1645465Y509626D03*
X1646562Y535677D03*
X1646723Y529136D03*
X1645465Y559665D03*
X1645846Y565574D03*
X1645493Y574338D03*
X1645592Y616358D03*
X1677213Y91951D03*
X1663760Y410394D03*
Y403307D03*
X1663576Y458406D03*
Y465492D03*
Y472579D03*
Y479665D03*
Y486752D03*
Y493839D03*
Y523799D03*
Y516713D03*
Y509626D03*
Y537973D03*
Y530886D03*
Y559665D03*
Y566752D03*
Y580925D03*
Y588012D03*
Y573839D03*
Y602185D03*
Y595099D03*
Y616358D03*
Y609272D03*
X1695566Y102249D03*
X1687566D03*
X1691566D03*
X1691366Y195176D03*
X1688866D03*
X1691226Y203393D03*
X1688726D03*
X1691117Y321649D03*
X1696666Y195176D03*
X1693866D03*
X1697414Y206838D03*
X1694914D03*
X1698839Y564843D03*
X1724334Y102323D03*
X1724586Y109410D03*
Y116496D03*
X1724758Y124576D03*
X1725811Y130670D03*
X1725806Y137756D03*
X1715705Y328692D03*
X1712734Y340534D03*
X1742336Y-87777D03*
X1739311Y-86371D03*
X1734826Y376499D03*
X1745589Y-87777D03*
X1742351Y-85262D03*
X1745604D03*
X1742444Y102323D03*
Y116496D03*
Y109410D03*
Y130670D03*
Y123583D03*
Y137756D03*
X1752485Y236611D03*
X1749985D03*
X1747485D03*
X1747187Y248891D03*
X1749687D03*
X1752187D03*
X1747561Y385161D03*
X1758583Y1581027D03*
X1750685Y1618504D03*
X1756422Y1640303D03*
X1770680Y926322D03*
X1763818Y926241D03*
X1765294Y1575434D03*
X1759092Y1588137D03*
X1767142Y1588219D03*
X1764422Y1640303D03*
X1779575Y91951D03*
X1790533Y303750D03*
X1783028Y408240D03*
X1785528D03*
X1780528D03*
X1783107Y424240D03*
X1780646Y420393D03*
X1785646D03*
X1783146D03*
X1783107Y426740D03*
X1780397Y1237469D03*
Y1230569D03*
Y1228069D03*
Y1234969D03*
Y1241869D03*
Y1244369D03*
Y1248769D03*
Y1251269D03*
X1776422Y1640303D03*
X1804667Y-47581D03*
X1804993Y297591D03*
X1807692Y-49001D03*
X1810945Y-48987D03*
X1807707Y-46486D03*
X1810960Y-46472D03*
X1817439Y447101D03*
G54D30*
X106586Y1204932D03*
X563673D03*
X1020434Y1205579D03*
X1477846Y1204932D03*
G54D38*
X190325Y368760D03*
Y455492D03*
Y503760D03*
Y583957D03*
Y636752D03*
X647411Y368760D03*
Y455492D03*
Y503760D03*
Y583957D03*
Y636752D03*
X1104498Y368760D03*
Y455492D03*
Y503760D03*
Y583957D03*
Y636752D03*
X1561585Y368760D03*
Y455492D03*
Y503760D03*
Y583957D03*
Y636752D03*
G54D43*
X515573Y692515D03*
X518299Y692384D03*
X520799D03*
X529493Y692443D03*
Y697443D03*
Y699943D03*
X529501Y702622D03*
X526993Y692443D03*
X529493Y694943D03*
X524493Y692443D03*
X1809078Y2165771D03*
X1806706Y2180760D03*
X1812366Y2063809D03*
X1822066Y2054109D03*
X1812366D03*
X1813087Y2087512D03*
X1825427Y2104853D03*
X1817378Y2165771D03*
X1815006Y2180760D03*
X1841295Y2065122D03*
X1832995D03*
X1833649Y2057507D03*
X1830872Y2083503D03*
X1840875Y2083215D03*
X1837649Y2072324D03*
X1829349D03*
X1833727Y2104853D03*
X1835862Y2121040D03*
X1833506Y2185252D03*
X1852032Y2052576D03*
X1854559Y2077931D03*
X1851762Y2121040D03*
X1854796Y2170548D03*
X1846496D03*
X1855978Y2185118D03*
X1847678D03*
X1859032Y2052576D03*
X1870505Y2064156D03*
X1860338Y2071384D03*
X1874505Y2078973D03*
X1860234Y2157701D03*
X1867072Y2174962D03*
X1864547Y2185020D03*
X1890039Y2066092D03*
X1878805Y2064156D03*
X1886128Y2075919D03*
X1882805Y2078973D03*
X1876497Y2070684D03*
X1884535Y2155415D03*
X1882972Y2174962D03*
X1882111Y2179074D03*
X1874932Y2180585D03*
X1881852Y2196600D03*
X1886699Y2183170D03*
X1876697D03*
X1905939Y2066092D03*
X1893118Y2054585D03*
X1905944Y2055424D03*
X1898342Y2062143D03*
X1901295Y2072745D03*
X1892835Y2155415D03*
X1902872Y2178531D03*
X1894572D03*
X1893087Y2168011D03*
X1896403Y2185019D03*
X1917195Y2072745D03*
X1917550Y2158451D03*
X1909250D03*
X1922010Y2151829D03*
X1913710D03*
X1921855Y2172152D03*
X1936295Y2074343D03*
X1935195Y2155918D03*
X1936377Y2163810D03*
X1924735Y2178131D03*
X1936212Y2173508D03*
X1930155Y2172152D03*
X1931738Y2182647D03*
X1923438D03*
X1941040Y2070124D03*
X1951095Y2155918D03*
X1946077Y2163810D03*
X1969128Y2161283D03*
X1959428D03*
X1969128Y2151583D03*
X1959428D03*
G54D51*
X909360Y230906D03*
Y274606D03*
G54D22*
X51043Y144095D03*
X57933Y66811D03*
X160295D03*
X153405Y144095D03*
X183435Y630650D03*
X190325Y374862D03*
X262657Y66811D03*
X255767Y144095D03*
X279360Y630650D03*
X286250Y374862D03*
X358129Y144095D03*
X365019Y66811D03*
X508130Y144095D03*
X515020Y66811D03*
X617382D03*
X610492Y144095D03*
X647411Y374862D03*
X640521Y630650D03*
X719744Y66811D03*
X712854Y144095D03*
X736446Y630650D03*
X743336Y374862D03*
X815216Y144095D03*
X822106Y66811D03*
X972106D03*
X965216Y144095D03*
X1074468Y66811D03*
X1067578Y144095D03*
X1104498Y374862D03*
X1097608Y630650D03*
X1169940Y144095D03*
X1176830Y66811D03*
X1200423Y374862D03*
X1193533Y630650D03*
X1272302Y144095D03*
X1279192Y66811D03*
X1429193D03*
X1422303Y144095D03*
X1531555Y66811D03*
X1524665Y144095D03*
X1561585Y374862D03*
X1554695Y630650D03*
X1627027Y144095D03*
X1633917Y66811D03*
X1657510Y374862D03*
X1650620Y630650D03*
X1736279Y66811D03*
X1729389Y144095D03*
G54D25*
X46248Y1760941D03*
Y1750941D03*
Y1806941D03*
Y1796941D03*
X143208Y1084547D03*
Y1092027D03*
X146948Y1077066D03*
Y1084547D03*
Y1092027D03*
X143208Y1095767D03*
X146948D03*
X143208Y1110728D03*
Y1118208D03*
X146948Y1110728D03*
Y1118208D03*
X146949Y1166830D03*
X154429Y1073326D03*
X161909D03*
X154429Y1092027D03*
X161909Y1077066D03*
X165649Y1080807D03*
Y1088287D03*
X161909D03*
Y1092027D03*
X154429Y1077066D03*
X158169Y1080807D03*
X150689D03*
X158169Y1084547D03*
X150689D03*
X158169Y1088287D03*
X154429D03*
X150689D03*
X165649Y1084547D03*
X158169Y1099507D03*
X150689D03*
X158169Y1103247D03*
X150689D03*
X161909Y1095767D03*
X165649Y1099507D03*
Y1103247D03*
X154429Y1106988D03*
X150689D03*
X154429Y1095767D03*
X158169Y1110728D03*
Y1114468D03*
X154429D03*
X150689D03*
X158169Y1129429D03*
X165649Y1166830D03*
Y1170570D03*
Y1178050D03*
Y1174310D03*
X163779Y1213582D03*
X160039D03*
X214271Y1114468D03*
X238582Y1078936D03*
X242322Y1082677D03*
X238582Y1097637D03*
X246062Y1254724D03*
X238582D03*
Y1250984D03*
X234842Y1247243D03*
X242322Y1243503D03*
Y1247243D03*
X246062Y1250984D03*
X249803Y1082677D03*
X257283D03*
X249803Y1101377D03*
X253543Y1250984D03*
Y1254724D03*
X249803Y1247243D03*
X253543Y1239763D03*
X249803D03*
X257283Y1247243D03*
X261023Y1250984D03*
Y1239763D03*
Y1254724D03*
X279724Y1082677D03*
Y1086417D03*
X275984Y1078936D03*
X264763Y1082677D03*
X275984Y1097637D03*
X274114Y1121948D03*
X277854Y1133169D03*
Y1125688D03*
X274114Y1204232D03*
X279724Y1247243D03*
X272244Y1243503D03*
Y1247243D03*
X264763D03*
X268503Y1250984D03*
X264763Y1243503D03*
X272244Y1239763D03*
X275984Y1250984D03*
X279724Y1243503D03*
X268503Y1254724D03*
X275984D03*
X294684Y1082677D03*
Y1090157D03*
X294685Y1086417D03*
X290944Y1078936D03*
X287204Y1082677D03*
X283464Y1093897D03*
X290944Y1097637D03*
X294685Y1247243D03*
Y1243503D03*
X283464Y1250984D03*
X287204Y1247243D03*
Y1243503D03*
Y1239763D03*
X290944Y1250984D03*
X283464Y1254724D03*
X290944D03*
X302164Y1082677D03*
X302165Y1086417D03*
X309644Y1082677D03*
X309645Y1086417D03*
X298425Y1097637D03*
X305905D03*
X300295Y1155610D03*
X309645Y1247243D03*
Y1243503D03*
X298425Y1250984D03*
X302165Y1247243D03*
Y1243503D03*
Y1239763D03*
X305905Y1250984D03*
X298425Y1254724D03*
X305905D03*
X320866Y1086417D03*
X317126D03*
X317125Y1082677D03*
X324606Y1086417D03*
X320866Y1093897D03*
X324606D03*
Y1105117D03*
Y1097637D03*
X320866Y1105117D03*
Y1097637D03*
X313385D03*
X324606Y1112598D03*
Y1120078D03*
X320866Y1112598D03*
Y1120078D03*
X317125Y1108858D03*
X320866Y1127558D03*
Y1135039D03*
X322736Y1140649D03*
X324606Y1127558D03*
Y1135039D03*
X326476Y1140649D03*
X322736Y1155610D03*
X326476Y1148129D03*
Y1155610D03*
X322736Y1148129D03*
X326476Y1170570D03*
Y1178051D03*
Y1185531D03*
X320866Y1250984D03*
X313385D03*
X317125Y1247243D03*
Y1243503D03*
X313385Y1254724D03*
X317125Y1239763D03*
X320866Y1254724D03*
X333286Y1728583D03*
Y1738583D03*
X333212Y1774624D03*
Y1784624D03*
X438162Y1348187D03*
Y1360099D03*
Y1384297D03*
Y1372385D03*
X450402Y1348187D03*
Y1360099D03*
Y1384297D03*
Y1372385D03*
Y1396583D03*
Y1408495D03*
X462642Y1348187D03*
X474882D03*
X462642Y1360099D03*
X474882D03*
X462642Y1384297D03*
X474882D03*
X462642Y1372385D03*
X474882D03*
Y1396583D03*
X462642D03*
X474882Y1408495D03*
X462642D03*
X487122Y1348187D03*
Y1360099D03*
Y1372385D03*
Y1384297D03*
Y1396583D03*
Y1408495D03*
X499362Y1348187D03*
Y1360099D03*
Y1372385D03*
Y1384297D03*
Y1396583D03*
Y1408495D03*
X511602Y1348187D03*
Y1360099D03*
Y1372385D03*
Y1384297D03*
Y1396583D03*
Y1408495D03*
X536082Y1348187D03*
X523842D03*
X536082Y1360099D03*
X523842D03*
Y1384297D03*
Y1372385D03*
X536082Y1384297D03*
Y1372385D03*
Y1396583D03*
X523842D03*
X536082Y1408495D03*
X523842D03*
X548322Y1348187D03*
Y1360099D03*
Y1384297D03*
Y1372385D03*
Y1396583D03*
Y1408495D03*
X560562Y1348187D03*
Y1360099D03*
Y1384297D03*
Y1372385D03*
Y1396583D03*
Y1408495D03*
X600295Y1084547D03*
Y1092027D03*
X604035Y1077066D03*
Y1084547D03*
Y1092027D03*
X600295Y1095767D03*
X604035D03*
X600295Y1110728D03*
Y1118208D03*
X604035Y1110728D03*
Y1118208D03*
X604036Y1166830D03*
X611516Y1073326D03*
X618996D03*
Y1088287D03*
Y1092027D03*
X611516Y1077066D03*
X615256Y1080807D03*
X607776D03*
X615256Y1084547D03*
X607776D03*
X615256Y1088287D03*
X611516D03*
X607776D03*
X611516Y1092027D03*
X618996Y1077066D03*
X611516Y1106988D03*
X607776D03*
X611516Y1095767D03*
X615256Y1099507D03*
X607776D03*
X615256Y1103247D03*
X607776D03*
X618996Y1095767D03*
X615256Y1110728D03*
Y1114468D03*
X611516D03*
X607776D03*
X615256Y1129429D03*
X617126Y1213582D03*
X620866D03*
X620083Y1728286D03*
Y1738286D03*
X619711Y1775438D03*
Y1785438D03*
X626476Y1088287D03*
X622736Y1080807D03*
Y1084547D03*
Y1088287D03*
Y1099507D03*
Y1103247D03*
Y1166830D03*
Y1170570D03*
Y1174310D03*
Y1178050D03*
X636288Y1372385D03*
Y1384297D03*
Y1396583D03*
X624048D03*
X636288Y1408495D03*
X624048D03*
X648528Y1348187D03*
Y1360099D03*
Y1372385D03*
Y1384297D03*
Y1396583D03*
Y1408495D03*
X660768Y1348187D03*
Y1360099D03*
Y1372385D03*
Y1384297D03*
Y1396583D03*
Y1408495D03*
X671358Y1114468D03*
X673008Y1348187D03*
X685248D03*
X673008Y1360099D03*
X685248D03*
Y1372385D03*
Y1384297D03*
X673008Y1372385D03*
Y1384297D03*
X685248Y1396583D03*
X673008D03*
X685248Y1408495D03*
X673008D03*
X695669Y1078936D03*
X699409Y1082677D03*
X695669Y1097637D03*
X699409Y1247243D03*
Y1243503D03*
X691929Y1247243D03*
X695669Y1250984D03*
Y1254724D03*
X697488Y1348187D03*
Y1360099D03*
Y1384297D03*
Y1372385D03*
Y1396583D03*
Y1408495D03*
X706890Y1082677D03*
X714370D03*
X706890Y1101377D03*
X703149Y1254724D03*
Y1250984D03*
X718110D03*
Y1239763D03*
X714370Y1247243D03*
X710630Y1254724D03*
Y1250984D03*
Y1239763D03*
X706890Y1247243D03*
Y1239763D03*
X718110Y1254724D03*
X709728Y1348187D03*
Y1360099D03*
Y1384297D03*
Y1372385D03*
Y1396583D03*
Y1408495D03*
X721850Y1082677D03*
X733071Y1078936D03*
Y1097637D03*
X731201Y1121948D03*
X734941Y1125688D03*
Y1133169D03*
X731201Y1204232D03*
X729331Y1243503D03*
X721850D03*
X729331Y1239763D03*
Y1247243D03*
X733071Y1250984D03*
Y1254724D03*
X725590D03*
Y1250984D03*
X721850Y1247243D03*
X734208Y1348187D03*
X721968D03*
X734208Y1360099D03*
X721968D03*
Y1384297D03*
Y1372385D03*
X734208D03*
Y1384297D03*
X721968Y1396489D03*
X734208D03*
X721968Y1408401D03*
X734208D03*
X744291Y1082677D03*
X748031Y1078936D03*
X736811Y1086417D03*
Y1082677D03*
X748031Y1097637D03*
X740551Y1093897D03*
X736811Y1243503D03*
Y1247243D03*
X744291Y1243503D03*
Y1239763D03*
X748031Y1254724D03*
Y1250984D03*
X744291Y1247243D03*
X740551Y1254724D03*
Y1250984D03*
X746448Y1348187D03*
Y1360099D03*
Y1372385D03*
Y1384297D03*
X759251Y1082677D03*
X751772Y1086417D03*
X751771Y1090157D03*
Y1082677D03*
X759252Y1086417D03*
X766732D03*
X766731Y1082677D03*
X762992Y1097637D03*
X755512D03*
X757382Y1155610D03*
X755512Y1250984D03*
Y1254724D03*
X759252Y1247243D03*
Y1243503D03*
X762992Y1250984D03*
Y1254724D03*
X766732Y1247243D03*
Y1243503D03*
X759252Y1239763D03*
X751772Y1247243D03*
Y1243503D03*
X758688Y1348187D03*
Y1360099D03*
Y1372385D03*
Y1384297D03*
X774213Y1086417D03*
X774212Y1082677D03*
X781693Y1086417D03*
X777953D03*
X770472Y1097637D03*
X777953Y1093897D03*
Y1105117D03*
X781693Y1093897D03*
Y1097637D03*
X777953D03*
X781693Y1105117D03*
Y1112598D03*
X777953Y1120078D03*
X781693D03*
X774212Y1108858D03*
X777953Y1112598D03*
X783563Y1140649D03*
X779823D03*
X781693Y1127558D03*
X777953D03*
Y1135039D03*
X781693D03*
X783563Y1155610D03*
Y1148129D03*
X779823Y1155610D03*
Y1148129D03*
X783563Y1170570D03*
Y1185531D03*
Y1178051D03*
X770472Y1250984D03*
Y1254724D03*
X777953Y1250984D03*
X774212Y1247243D03*
Y1243503D03*
Y1239763D03*
X777953Y1254724D03*
X770928Y1348187D03*
Y1360099D03*
X907279Y1738990D03*
Y1728990D03*
X907073Y1776014D03*
Y1786014D03*
X1057381Y1092027D03*
Y1084547D03*
Y1095767D03*
Y1118208D03*
Y1110728D03*
X1068602Y1073326D03*
X1072342Y1088287D03*
Y1084547D03*
Y1080807D03*
X1061121Y1092027D03*
X1068602D03*
X1064862Y1088287D03*
X1068602D03*
X1061121Y1084547D03*
X1064862D03*
Y1080807D03*
X1061121Y1077066D03*
X1068602D03*
X1072342Y1099507D03*
Y1103247D03*
X1061121Y1095767D03*
X1068602D03*
X1064862Y1106988D03*
X1068602D03*
X1064862Y1103247D03*
Y1099507D03*
X1072342Y1114468D03*
Y1110728D03*
X1061121Y1118208D03*
X1064862Y1114468D03*
X1068602D03*
X1061121Y1110728D03*
X1072342Y1129429D03*
X1061122Y1166830D03*
X1074212Y1213582D03*
X1076082Y1073326D03*
X1083562Y1088287D03*
X1079822D03*
Y1084547D03*
Y1080807D03*
X1076082Y1092027D03*
Y1088287D03*
Y1077066D03*
X1079822Y1103247D03*
Y1099507D03*
X1076082Y1095767D03*
X1079822Y1170570D03*
Y1166830D03*
Y1174310D03*
Y1178050D03*
X1077952Y1213582D03*
X1128444Y1114468D03*
X1152755Y1078936D03*
X1156495Y1082677D03*
X1152755Y1097637D03*
Y1254724D03*
Y1250984D03*
X1149015Y1247243D03*
X1156495Y1243503D03*
Y1247243D03*
X1163976Y1082677D03*
X1171456D03*
X1163976Y1101377D03*
Y1239763D03*
Y1247243D03*
X1167716Y1239763D03*
Y1250984D03*
Y1254724D03*
X1171456Y1247243D03*
X1160235Y1250984D03*
Y1254724D03*
X1178936Y1082677D03*
X1188287Y1121948D03*
Y1204232D03*
X1175196Y1254724D03*
Y1239763D03*
Y1250984D03*
X1178936Y1247243D03*
X1182676Y1250984D03*
Y1254724D03*
X1186417Y1247243D03*
Y1239763D03*
X1178936Y1243503D03*
X1186417D03*
X1190157Y1078936D03*
X1201377Y1082677D03*
X1205117Y1078936D03*
X1193897Y1082677D03*
Y1086417D03*
X1190157Y1097637D03*
X1197637Y1093897D03*
X1205117Y1097637D03*
X1192027Y1133169D03*
Y1125688D03*
X1190157Y1254724D03*
Y1250984D03*
X1197637D03*
Y1254724D03*
X1201377Y1247243D03*
X1205117Y1250984D03*
Y1254724D03*
X1201377Y1239763D03*
Y1243503D03*
X1193897Y1247243D03*
Y1243503D03*
X1216337Y1082677D03*
X1216338Y1086417D03*
X1208857Y1082677D03*
X1208858Y1086417D03*
X1208857Y1090157D03*
X1212598Y1097637D03*
X1220078D03*
X1214468Y1155610D03*
X1212598Y1250984D03*
Y1254724D03*
X1216338Y1247243D03*
Y1243503D03*
X1220078Y1250984D03*
Y1254724D03*
X1216338Y1239763D03*
X1208858Y1247243D03*
Y1243503D03*
X1223817Y1082677D03*
X1223818Y1086417D03*
X1231298Y1082677D03*
X1235039Y1086417D03*
X1231299D03*
X1227558Y1097637D03*
X1235039Y1093897D03*
Y1097637D03*
Y1105117D03*
X1231298Y1108858D03*
X1235039Y1112598D03*
Y1120078D03*
X1236909Y1140649D03*
X1235039Y1127558D03*
Y1135039D03*
X1236909Y1148129D03*
Y1155610D03*
X1223818Y1247243D03*
Y1243503D03*
X1227558Y1250984D03*
Y1254724D03*
X1235039Y1250984D03*
X1231298Y1247243D03*
Y1243503D03*
Y1239763D03*
X1235039Y1254724D03*
X1238779Y1086417D03*
Y1093897D03*
Y1097637D03*
Y1105117D03*
Y1112598D03*
Y1120078D03*
X1240649Y1140649D03*
X1238779Y1127558D03*
Y1135039D03*
X1240649Y1148129D03*
Y1155610D03*
Y1170570D03*
Y1178051D03*
Y1185531D03*
X1514468Y1084547D03*
Y1092027D03*
Y1095767D03*
Y1110728D03*
Y1118208D03*
X1525689Y1073326D03*
Y1077066D03*
X1518208D03*
X1529429Y1080807D03*
X1521949D03*
X1529429Y1084547D03*
X1521949D03*
X1518208D03*
X1529429Y1088287D03*
X1525689D03*
X1521949D03*
X1525689Y1092027D03*
X1518208D03*
X1521949Y1103247D03*
X1525689Y1106988D03*
X1521949D03*
X1525689Y1095767D03*
X1518208D03*
X1529429Y1099507D03*
X1521949D03*
X1529429Y1103247D03*
Y1110728D03*
X1518208D03*
X1529429Y1114468D03*
X1525689D03*
X1521949D03*
X1518208Y1118208D03*
X1529429Y1129429D03*
X1518209Y1166830D03*
X1533169Y1073326D03*
X1540649Y1088287D03*
X1533169Y1077066D03*
X1536909Y1080807D03*
Y1084547D03*
Y1088287D03*
X1533169D03*
Y1092027D03*
Y1095767D03*
X1536909Y1099507D03*
Y1103247D03*
Y1166830D03*
Y1170570D03*
Y1174310D03*
X1535039Y1176180D03*
Y1213582D03*
X1531299D03*
X1585531Y1114468D03*
X1609842Y1078936D03*
Y1097637D03*
Y1254724D03*
Y1250984D03*
X1606102Y1247243D03*
X1613582Y1082677D03*
X1621063D03*
Y1101377D03*
X1613582Y1243503D03*
Y1247243D03*
X1621063Y1239763D03*
Y1247243D03*
X1624803Y1239763D03*
Y1250984D03*
Y1254724D03*
X1617322Y1250984D03*
Y1254724D03*
X1636023Y1082677D03*
X1628543D03*
X1632283Y1254724D03*
X1628543Y1247243D03*
X1632283Y1239763D03*
Y1250984D03*
X1636023Y1247243D03*
X1639763Y1250984D03*
Y1254724D03*
X1643504Y1247243D03*
Y1239763D03*
X1636023Y1243503D03*
X1643504D03*
X1658464Y1082677D03*
X1650984D03*
Y1086417D03*
X1647244Y1078936D03*
Y1097637D03*
X1654724Y1093897D03*
X1645374Y1121948D03*
X1649114Y1133169D03*
Y1125688D03*
X1645374Y1204232D03*
X1647244Y1254724D03*
Y1250984D03*
X1654724D03*
Y1254724D03*
X1658464Y1247243D03*
Y1239763D03*
Y1243503D03*
X1650984Y1247243D03*
Y1243503D03*
X1662204Y1078936D03*
X1673424Y1082677D03*
X1673425Y1086417D03*
X1665944Y1082677D03*
X1665945Y1086417D03*
X1665944Y1090157D03*
X1662204Y1097637D03*
X1669685D03*
X1671555Y1155610D03*
X1665945Y1247243D03*
Y1243503D03*
X1662204Y1250984D03*
Y1254724D03*
X1669685Y1250984D03*
Y1254724D03*
X1673425Y1247243D03*
Y1243503D03*
Y1239763D03*
X1680904Y1082677D03*
X1680905Y1086417D03*
X1688385Y1082677D03*
X1692126Y1086417D03*
X1688386D03*
X1677165Y1097637D03*
X1684645D03*
X1692126Y1093897D03*
Y1097637D03*
Y1105117D03*
X1688385Y1108858D03*
X1692126Y1112598D03*
Y1120078D03*
Y1127558D03*
Y1135039D03*
X1684645Y1250984D03*
Y1254724D03*
X1692126Y1250984D03*
X1688385Y1247243D03*
Y1243503D03*
Y1239763D03*
X1692126Y1254724D03*
X1677165Y1250984D03*
Y1254724D03*
X1680905Y1247243D03*
Y1243503D03*
X1695866Y1086417D03*
Y1093897D03*
Y1097637D03*
Y1105117D03*
Y1112598D03*
Y1120078D03*
X1697736Y1140649D03*
X1693996D03*
X1695866Y1127558D03*
Y1135039D03*
X1697736Y1148129D03*
X1693996D03*
X1697736Y1155610D03*
X1693996D03*
X1697736Y1170570D03*
Y1178051D03*
Y1185531D03*
G54D36*
X145078Y1250984D03*
X148818Y1243503D03*
Y1250984D03*
X145078Y1243503D03*
X161909Y1125688D03*
X158169Y1151869D03*
X154429D03*
Y1166830D03*
X160039Y1194881D03*
Y1202362D03*
Y1209842D03*
Y1217322D03*
X156299Y1250984D03*
X160039Y1247243D03*
X152559D03*
X156299Y1239763D03*
X163779Y1250984D03*
X156299Y1254724D03*
X163779D03*
X178740Y1075196D03*
X171259D03*
X178740Y1078936D03*
X174999Y1086417D03*
Y1082677D03*
X171259Y1078936D03*
X182480Y1086417D03*
Y1082677D03*
X171259Y1097637D03*
X173129Y1129428D03*
X169389D03*
X180610Y1170570D03*
X174999Y1209842D03*
X167519Y1221062D03*
X182480Y1239763D03*
Y1247243D03*
X178740Y1250984D03*
Y1239763D03*
X174999Y1243503D03*
X178740Y1254724D03*
X171259D03*
X167519Y1247243D03*
X186220Y1075196D03*
X193700D03*
X189960Y1086417D03*
Y1082677D03*
X193700Y1078936D03*
X186220D03*
X197440Y1086417D03*
Y1082677D03*
X188090Y1178051D03*
Y1193011D03*
X197440Y1247243D03*
X193700Y1254724D03*
X186220D03*
X189960Y1239763D03*
X186220Y1250984D03*
X189960Y1247243D03*
X193700Y1250984D03*
X201181Y1075196D03*
X208661D03*
Y1078936D03*
X212401Y1086417D03*
Y1082677D03*
X204921Y1086417D03*
Y1082677D03*
X201181Y1078936D03*
X208661Y1250984D03*
X201181Y1239763D03*
X212401D03*
Y1247243D03*
X201181Y1254724D03*
X204921Y1239763D03*
X201181Y1250984D03*
X204921Y1247243D03*
X208661Y1254724D03*
X213969Y1445013D03*
Y1456013D03*
X223622Y1075196D03*
X231102D03*
X216141D03*
X227362Y1086417D03*
Y1082677D03*
X219881Y1086417D03*
Y1082677D03*
X223622Y1078936D03*
X231102D03*
X216141D03*
X223622Y1254724D03*
X231102D03*
X227362Y1247243D03*
X219881Y1239763D03*
X223622Y1250984D03*
X219881Y1247243D03*
X231102Y1250984D03*
X227362Y1239763D03*
X216141Y1250984D03*
Y1254724D03*
X227249Y1445013D03*
Y1456013D03*
X246062Y1221062D03*
X234842Y1239763D03*
Y1243503D03*
X242322Y1239763D03*
X257283Y1101377D03*
X249803Y1221062D03*
X253543D03*
X261023D03*
X257283D03*
X249803Y1243503D03*
X257283D03*
X272244Y1101377D03*
X279724D03*
X264763D03*
X277854Y1121948D03*
Y1129429D03*
X264763Y1221062D03*
X279724Y1239763D03*
X275984D03*
X264763D03*
X287204Y1086417D03*
X283464Y1097637D03*
X294684Y1101377D03*
X289074Y1144389D03*
X294685Y1239763D03*
X302164Y1090157D03*
X305904D03*
X309644D03*
X302165Y1101377D03*
X309645D03*
Y1123818D03*
X309644Y1108858D03*
X309645Y1116338D03*
Y1131299D03*
X307775Y1140649D03*
X298425Y1135039D03*
Y1127558D03*
X300295Y1151869D03*
Y1144389D03*
X307775Y1148129D03*
Y1155610D03*
Y1159350D03*
X305905Y1239763D03*
X317125Y1090157D03*
X317126Y1105117D03*
X317125Y1101377D03*
X318996Y1136909D03*
X317125Y1131299D03*
X318996Y1144389D03*
Y1151869D03*
X322736Y1166830D03*
X318996Y1159350D03*
Y1166830D03*
X326476D03*
X318996Y1189271D03*
Y1181791D03*
Y1174310D03*
X317125Y1198621D03*
Y1206102D03*
Y1213582D03*
X320866Y1243503D03*
X313385Y1239763D03*
X602165Y1243503D03*
Y1250984D03*
X618996Y1125688D03*
Y1133169D03*
X615256Y1151869D03*
X611516D03*
Y1166830D03*
X617126Y1202362D03*
Y1194881D03*
Y1209842D03*
Y1217322D03*
X613386Y1239763D03*
X620866Y1254724D03*
Y1250984D03*
X617126Y1247243D03*
X609646D03*
X613386Y1254724D03*
Y1250984D03*
X605905Y1243503D03*
Y1254724D03*
Y1250984D03*
X626476Y1073326D03*
X635827Y1075196D03*
X628346D03*
X626476Y1077066D03*
X628346Y1078936D03*
X635827D03*
X632086Y1082677D03*
Y1086417D03*
X626476Y1099507D03*
X628346Y1097637D03*
X630216Y1129428D03*
X626476D03*
X630216Y1136909D03*
X626476D03*
X632086Y1209842D03*
X624606Y1221062D03*
X632086Y1243503D03*
X635827Y1239763D03*
Y1254724D03*
Y1250984D03*
X628346Y1254724D03*
X624606Y1247243D03*
X643307Y1075196D03*
X650787D03*
Y1078936D03*
X647047Y1082677D03*
Y1086417D03*
X643307Y1078936D03*
X639567Y1086417D03*
Y1082677D03*
X637697Y1170570D03*
X645177Y1178051D03*
Y1193011D03*
X639567Y1239763D03*
Y1247243D03*
X647047Y1239763D03*
X650787Y1254724D03*
Y1250984D03*
X647047Y1247243D03*
X643307Y1254724D03*
Y1250984D03*
X658268Y1075196D03*
X665748D03*
X669488Y1086417D03*
X665748Y1078936D03*
X669488Y1082677D03*
X654527D03*
Y1086417D03*
X662008Y1082677D03*
Y1086417D03*
X658268Y1078936D03*
X654527Y1247243D03*
X662008Y1239763D03*
X658268D03*
X669488D03*
X665748Y1250984D03*
Y1254724D03*
X669488Y1247243D03*
X662008D03*
X658268Y1254724D03*
Y1250984D03*
X680709Y1075196D03*
X673228D03*
X684449Y1082677D03*
Y1086417D03*
X673228Y1078936D03*
X680709D03*
X676968Y1082677D03*
Y1086417D03*
Y1239763D03*
X680709Y1254724D03*
Y1250984D03*
X676968Y1247243D03*
X673228Y1254724D03*
Y1250984D03*
X684449Y1247243D03*
Y1239763D03*
X688189Y1075196D03*
Y1078936D03*
Y1254724D03*
Y1250984D03*
X699409Y1239763D03*
X691929D03*
Y1243503D03*
X714370Y1101377D03*
Y1243503D03*
X706890D03*
X729331Y1101377D03*
X721850D03*
X734941Y1121948D03*
Y1129429D03*
X733071Y1239763D03*
X721850D03*
X744291Y1086417D03*
X740551Y1097637D03*
X736811Y1101377D03*
X746161Y1144389D03*
X736811Y1239763D03*
X766731Y1090157D03*
X759251D03*
X762991D03*
X751771Y1101377D03*
X759252D03*
X766732D03*
X766731Y1108858D03*
X766732Y1116338D03*
Y1123818D03*
X764862Y1140649D03*
X766732Y1131299D03*
X755512Y1127558D03*
Y1135039D03*
X764862Y1155610D03*
Y1148129D03*
X757382Y1144389D03*
Y1151869D03*
X764862Y1159350D03*
X762992Y1239763D03*
X751772D03*
X774212Y1090157D03*
Y1101377D03*
X774213Y1105117D03*
X774212Y1131299D03*
X776083Y1151869D03*
Y1144389D03*
X783563Y1166830D03*
X776083D03*
Y1159350D03*
X779823Y1166830D03*
X776083Y1174310D03*
Y1181791D03*
Y1196751D03*
X774212Y1198621D03*
Y1213582D03*
Y1206102D03*
X777953Y1243503D03*
X770472Y1239763D03*
X1059251Y1243503D03*
Y1250984D03*
X1072342Y1151869D03*
X1068602D03*
Y1166830D03*
X1074212Y1194881D03*
Y1202362D03*
Y1217322D03*
Y1209842D03*
X1070472Y1250984D03*
Y1254724D03*
X1066732Y1247243D03*
X1074212D03*
X1070472Y1239763D03*
X1062991Y1250984D03*
Y1254724D03*
Y1243503D03*
X1083562Y1073326D03*
Y1077066D03*
X1089172Y1082677D03*
Y1086417D03*
X1083562Y1099507D03*
Y1136909D03*
X1087302D03*
X1083562Y1129428D03*
X1087302D03*
X1076082Y1133169D03*
Y1125688D03*
X1089172Y1209842D03*
X1081692Y1221062D03*
X1077952Y1250984D03*
Y1254724D03*
X1081692Y1247243D03*
X1085432Y1254724D03*
X1089172Y1243503D03*
X1092913Y1075196D03*
X1107873D03*
X1100393D03*
X1092913Y1078936D03*
X1104133Y1086417D03*
Y1082677D03*
X1107873Y1078936D03*
X1100393D03*
X1096653Y1082677D03*
Y1086417D03*
X1094783Y1170570D03*
X1102263Y1178051D03*
Y1193011D03*
X1092913Y1250984D03*
Y1254724D03*
Y1239763D03*
X1100393Y1250984D03*
Y1254724D03*
X1104133Y1247243D03*
X1107873Y1250984D03*
Y1254724D03*
X1104133Y1239763D03*
X1096653Y1247243D03*
Y1239763D03*
X1115354Y1075196D03*
X1122834D03*
X1115354Y1078936D03*
X1119094Y1082677D03*
Y1086417D03*
X1122834Y1078936D03*
X1111613Y1082677D03*
Y1086417D03*
X1115354Y1250984D03*
Y1254724D03*
X1119094Y1247243D03*
X1122834Y1254724D03*
Y1250984D03*
X1115354Y1239763D03*
X1119094D03*
X1111613Y1247243D03*
X1130314Y1075196D03*
X1137795D03*
X1126574Y1086417D03*
Y1082677D03*
X1130314Y1078936D03*
X1134054Y1082677D03*
Y1086417D03*
X1137795Y1078936D03*
X1126574Y1247243D03*
Y1239763D03*
X1130314Y1250984D03*
Y1254724D03*
X1134054Y1247243D03*
X1137795Y1250984D03*
Y1254724D03*
X1134054Y1239763D03*
X1145275Y1075196D03*
X1141535Y1082677D03*
Y1086417D03*
X1145275Y1078936D03*
X1141535Y1239763D03*
Y1247243D03*
X1149015Y1243503D03*
Y1239763D03*
X1156495D03*
X1145275Y1250984D03*
Y1254724D03*
X1171456Y1101377D03*
X1163976Y1243503D03*
X1171456D03*
X1178936Y1101377D03*
X1186417D03*
X1178936Y1239763D03*
X1201377Y1086417D03*
X1197637Y1097637D03*
X1193897Y1101377D03*
X1192027Y1121948D03*
Y1129429D03*
X1203247Y1144389D03*
X1190157Y1239763D03*
X1193897D03*
X1216337Y1090157D03*
X1220077D03*
X1216338Y1101377D03*
X1208857D03*
X1221948Y1140649D03*
X1212598Y1127558D03*
Y1135039D03*
X1221948Y1155610D03*
X1214468Y1151869D03*
Y1144389D03*
X1221948Y1148129D03*
Y1159350D03*
X1220078Y1239763D03*
X1208858D03*
X1223817Y1090157D03*
X1231298D03*
X1223818Y1101377D03*
X1231298D03*
X1231299Y1105117D03*
X1223817Y1108858D03*
X1223818Y1116338D03*
Y1123818D03*
X1233169Y1136909D03*
X1223818Y1131299D03*
X1231298D03*
X1233169Y1144389D03*
Y1151869D03*
X1236909Y1166830D03*
X1233169Y1159350D03*
Y1166830D03*
Y1189271D03*
Y1181791D03*
Y1174310D03*
Y1196751D03*
X1231298Y1198621D03*
Y1206102D03*
Y1213582D03*
X1235039Y1243503D03*
X1227558Y1239763D03*
X1243149Y1136909D03*
X1240649Y1166830D03*
X1511968Y1170570D03*
Y1178050D03*
X1529429Y1151869D03*
X1525689D03*
Y1166830D03*
X1516338Y1243503D03*
Y1250984D03*
X1527559D03*
Y1254724D03*
X1523819Y1247243D03*
X1527559Y1239763D03*
X1520078Y1250984D03*
Y1254724D03*
Y1243503D03*
X1540649Y1073326D03*
Y1077066D03*
X1546259Y1082677D03*
Y1086417D03*
X1540649Y1099507D03*
X1533169Y1125688D03*
X1544389Y1129428D03*
X1540649D03*
X1544389Y1136909D03*
X1533169Y1133169D03*
X1540649Y1136909D03*
X1531299Y1194881D03*
Y1202362D03*
Y1217322D03*
Y1209842D03*
X1546259D03*
X1538779Y1221062D03*
X1531299Y1247243D03*
X1535039Y1250984D03*
Y1254724D03*
X1538779Y1247243D03*
X1542519Y1254724D03*
X1546259Y1243503D03*
X1557480Y1075196D03*
X1550000D03*
X1561220Y1086417D03*
Y1082677D03*
X1557480Y1078936D03*
X1553740Y1082677D03*
Y1086417D03*
X1550000Y1078936D03*
X1551870Y1170570D03*
X1559350Y1178051D03*
Y1193011D03*
X1550000Y1250984D03*
Y1254724D03*
Y1239763D03*
X1557480Y1250984D03*
Y1254724D03*
X1561220Y1247243D03*
Y1239763D03*
X1553740Y1247243D03*
Y1239763D03*
X1572441Y1075196D03*
X1564960D03*
Y1078936D03*
X1572441D03*
X1576181Y1082677D03*
Y1086417D03*
X1568700Y1082677D03*
Y1086417D03*
X1564960Y1250984D03*
Y1254724D03*
X1572441Y1250984D03*
Y1254724D03*
X1576181Y1247243D03*
X1572441Y1239763D03*
X1576181D03*
X1568700Y1247243D03*
X1579921Y1075196D03*
X1587401D03*
X1594882D03*
X1583661Y1086417D03*
Y1082677D03*
X1579921Y1078936D03*
X1587401D03*
X1591141Y1082677D03*
Y1086417D03*
X1594882Y1078936D03*
X1583661Y1247243D03*
X1579921Y1254724D03*
Y1250984D03*
X1583661Y1239763D03*
X1587401Y1250984D03*
Y1254724D03*
X1591141Y1247243D03*
X1594882Y1250984D03*
Y1254724D03*
X1591141Y1239763D03*
X1602362Y1075196D03*
X1598622Y1082677D03*
Y1086417D03*
X1602362Y1078936D03*
X1598622Y1239763D03*
Y1247243D03*
X1606102Y1243503D03*
Y1239763D03*
X1602362Y1250984D03*
Y1254724D03*
X1613582Y1239763D03*
X1621063Y1243503D03*
X1636023Y1101377D03*
X1643504D03*
X1628543D03*
Y1243503D03*
X1636023Y1239763D03*
X1658464Y1086417D03*
X1654724Y1097637D03*
X1650984Y1101377D03*
X1649114Y1121948D03*
Y1129429D03*
X1660334Y1144389D03*
X1647244Y1239763D03*
X1650984D03*
X1673424Y1090157D03*
X1673425Y1101377D03*
X1665944D03*
X1671555Y1136909D03*
X1669685Y1127558D03*
Y1135039D03*
X1671555Y1151869D03*
Y1144389D03*
X1665945Y1239763D03*
X1677164Y1090157D03*
X1680904D03*
X1688385D03*
X1680905Y1101377D03*
X1688385D03*
X1688386Y1105117D03*
X1680904Y1108858D03*
X1680905Y1116338D03*
Y1123818D03*
X1690256Y1136909D03*
X1679035Y1140649D03*
X1680905Y1131299D03*
X1688385D03*
X1690256Y1144389D03*
X1679035Y1148129D03*
Y1155610D03*
X1690256Y1151869D03*
Y1159350D03*
X1679035D03*
X1690256Y1166830D03*
Y1174310D03*
Y1189271D03*
Y1181791D03*
X1688385Y1198621D03*
Y1213582D03*
Y1206102D03*
X1692126Y1243503D03*
X1684645Y1239763D03*
X1677165D03*
X1700236Y1136909D03*
X1693996Y1166830D03*
X1697736D03*
G54D46*
X718503Y-38525D03*
X718500Y-33320D03*
Y-30420D03*
X718488Y-36010D03*
X721756Y-38539D03*
X724781Y-37219D03*
X721741Y-36024D03*
X838503Y-77705D03*
X841756Y-77719D03*
X838500Y-72500D03*
X838488Y-75190D03*
X841741Y-75204D03*
X844781Y-76399D03*
X838500Y-69600D03*
X1005256Y-48539D03*
X1002003D03*
X1005241Y-46024D03*
X1001988D03*
X1008281Y-47219D03*
X1002000Y-40834D03*
X1005256Y-38239D03*
X1002003Y-38225D03*
X1002000Y-43334D03*
X1005241Y-35724D03*
X1002000Y-32720D03*
X1001988Y-35710D03*
X1002000Y-30120D03*
X1008281Y-36919D03*
X1075256Y-77419D03*
X1072003Y-77405D03*
X1071988Y-85290D03*
X1075241D03*
X1072000Y-82600D03*
X1072003Y-87805D03*
X1075256D03*
X1072000Y-80100D03*
Y-72000D03*
Y-69400D03*
X1075241Y-74904D03*
X1071988Y-74890D03*
X1078281Y-86399D03*
Y-76099D03*
X1291756Y-48669D03*
X1288503D03*
X1291741Y-46154D03*
X1288488D03*
X1294781Y-47349D03*
X1288500Y-40964D03*
X1291756Y-38369D03*
X1288503Y-38355D03*
X1288500Y-43464D03*
X1291741Y-35854D03*
X1288500Y-32950D03*
X1288488Y-35840D03*
X1288500Y-30350D03*
X1294781Y-37049D03*
X1328500Y-80100D03*
X1331756Y-77419D03*
X1328503Y-77405D03*
X1331756Y-87805D03*
X1328503D03*
X1328500Y-82600D03*
X1331741Y-85290D03*
X1328488D03*
X1334781Y-86499D03*
X1331741Y-74904D03*
X1328500Y-72000D03*
X1328488Y-74890D03*
X1328500Y-69400D03*
X1334781Y-76099D03*
X1576256Y-48799D03*
X1573003D03*
X1576241Y-46284D03*
X1572988D03*
X1579281Y-47479D03*
X1573000Y-41094D03*
X1576256Y-38499D03*
X1573003Y-38485D03*
X1573000Y-43594D03*
X1576241Y-35984D03*
X1573000Y-33080D03*
X1572988Y-35970D03*
X1573000Y-30480D03*
X1579281Y-37179D03*
X1583000Y-80014D03*
X1586256Y-77419D03*
X1583003Y-77405D03*
X1586256Y-87719D03*
X1583003D03*
X1583000Y-82514D03*
X1586241Y-85204D03*
X1582988D03*
X1589281Y-86399D03*
X1586241Y-74904D03*
X1583000Y-72000D03*
X1582988Y-74890D03*
X1583000Y-69400D03*
X1589281Y-76099D03*
G54D26*
X56348Y1727941D03*
Y1737941D03*
X56248Y1750941D03*
X56348Y1773941D03*
X56248Y1760941D03*
X56348Y1783941D03*
X56248Y1806941D03*
Y1796941D03*
X308448Y1737941D03*
Y1727941D03*
Y1750941D03*
Y1760941D03*
Y1773941D03*
Y1783941D03*
X308348Y1796941D03*
Y1806941D03*
X343286Y1738583D03*
Y1728583D03*
X343112Y1751624D03*
X343212Y1774624D03*
X343112Y1761624D03*
X343212Y1784624D03*
Y1797624D03*
Y1807624D03*
X595386Y1728583D03*
Y1738583D03*
X595312Y1751624D03*
Y1774624D03*
Y1761624D03*
Y1784624D03*
Y1807624D03*
Y1797624D03*
X630083Y1738286D03*
Y1728286D03*
X629861Y1751765D03*
X629711Y1775438D03*
X629861Y1761765D03*
X629711Y1785438D03*
X629475Y1798845D03*
Y1808845D03*
X882183Y1728286D03*
Y1738286D03*
X881911Y1751765D03*
X881761Y1775438D03*
X881911Y1761765D03*
X881761Y1785438D03*
X881525Y1798845D03*
Y1808845D03*
X917279Y1738990D03*
Y1728990D03*
X917163Y1752566D03*
Y1762566D03*
X917073Y1786014D03*
Y1776014D03*
X917166Y1800435D03*
Y1810435D03*
X1169329Y1728990D03*
Y1738990D03*
X1169263Y1752566D03*
Y1762566D03*
X1169123Y1776014D03*
Y1786014D03*
X1169216Y1800435D03*
Y1810435D03*
G54D42*
X318448Y1727941D03*
Y1737941D03*
Y1773941D03*
Y1783941D03*
X605312Y1751624D03*
Y1761624D03*
Y1807624D03*
Y1797624D03*
X891911Y1751765D03*
Y1761765D03*
X891525Y1808845D03*
Y1798845D03*
X1179263Y1752566D03*
Y1762566D03*
X1179216Y1800435D03*
Y1810435D03*
G54D34*
X146948Y1136909D03*
X143208D03*
X145078Y1198621D03*
Y1191141D03*
X148818D03*
Y1198621D03*
X145078Y1221062D03*
X148818D03*
Y1213582D03*
X145078D03*
Y1206102D03*
X148818D03*
X145078Y1228543D03*
X148818D03*
Y1247243D03*
X145078D03*
X148818Y1239763D03*
X145078D03*
X150689Y1133169D03*
X165649D03*
X161909D03*
X154429D03*
X156299Y1187401D03*
X163779D03*
X152559D03*
X156299Y1202362D03*
Y1194881D03*
X152559Y1202362D03*
Y1194881D03*
X163779D03*
Y1202362D03*
X156299Y1217322D03*
Y1209842D03*
X152559D03*
X163779D03*
Y1217322D03*
X152559D03*
X160039Y1236023D03*
X163779Y1224803D03*
X156299D03*
Y1228543D03*
X163779D03*
X160039Y1232283D03*
X152559Y1236023D03*
Y1232283D03*
Y1250984D03*
Y1254724D03*
X160039D03*
X156299Y1243503D03*
Y1247243D03*
X163779Y1243503D03*
X160039Y1250984D03*
X163779Y1247243D03*
X174999Y1075196D03*
X182480D03*
X174999Y1078936D03*
X182480D03*
X178740Y1082677D03*
Y1086417D03*
X174999Y1093897D03*
X182480D03*
Y1097637D03*
X174999D03*
X178740Y1101376D03*
Y1105117D03*
X173129Y1136909D03*
X169389D03*
X167519Y1187401D03*
X174999Y1198621D03*
Y1191141D03*
X167519Y1194881D03*
X171259Y1198621D03*
Y1191141D03*
X167519Y1202362D03*
Y1209842D03*
X171259Y1213582D03*
Y1206102D03*
X174999D03*
X167519Y1217322D03*
X174999Y1213582D03*
X178740Y1228543D03*
X171259Y1224803D03*
X182480Y1236023D03*
Y1232283D03*
X174999D03*
X171259Y1228543D03*
X178740Y1224803D03*
X174999Y1236023D03*
X167519Y1232283D03*
Y1236023D03*
Y1254724D03*
Y1250984D03*
X178740Y1247243D03*
X182480Y1254724D03*
Y1250984D03*
X171259Y1247243D03*
X174999Y1250984D03*
X171259Y1243503D03*
X174999Y1254724D03*
X178740Y1243503D03*
X189960Y1075196D03*
X197440D03*
X186220Y1082677D03*
Y1086417D03*
X189960Y1078936D03*
X193700Y1086417D03*
Y1082677D03*
X197440Y1078936D03*
X193700Y1105117D03*
X197440Y1093897D03*
X189960Y1097637D03*
X186220Y1105117D03*
X197440Y1097637D03*
X193700Y1101376D03*
X186220D03*
X189960Y1093897D03*
X197440Y1236023D03*
X186220Y1224803D03*
X193700Y1228543D03*
X197440Y1232283D03*
X189960Y1236023D03*
X186220Y1228543D03*
X193700Y1224803D03*
X189960Y1232283D03*
X197440Y1254724D03*
Y1250984D03*
X193700Y1247243D03*
Y1243503D03*
X189960Y1254724D03*
Y1250984D03*
X186220Y1247243D03*
Y1243503D03*
X204921Y1075196D03*
X212401D03*
Y1078936D03*
X208661Y1082677D03*
X201181D03*
Y1086417D03*
X208661D03*
X204921Y1078936D03*
Y1097637D03*
X208661Y1101376D03*
X212401Y1097637D03*
X208661Y1105117D03*
X212401Y1093897D03*
X201181Y1101376D03*
X204921Y1093897D03*
X201181Y1105117D03*
X204921Y1232283D03*
X201181Y1224803D03*
X212401Y1232283D03*
X208661Y1228543D03*
X212401Y1236023D03*
X208661Y1224803D03*
X201181Y1228543D03*
X204921Y1236023D03*
X208661Y1243503D03*
X204921Y1250984D03*
X208661Y1247243D03*
X212401Y1254724D03*
X201181Y1243503D03*
X212401Y1250984D03*
X201181Y1247243D03*
X204921Y1254724D03*
X227362Y1075196D03*
X219881D03*
Y1078936D03*
X216141Y1086417D03*
X231102Y1082677D03*
Y1086417D03*
X223622Y1082677D03*
X227362Y1078936D03*
X216141Y1082677D03*
X223622Y1086417D03*
X216141Y1101376D03*
X231102D03*
X227362Y1093897D03*
X219881Y1097637D03*
X223621Y1101376D03*
Y1105117D03*
X216141D03*
X219881Y1093897D03*
X227362Y1097637D03*
X231102Y1105117D03*
Y1228543D03*
Y1224803D03*
X219881Y1232283D03*
Y1236023D03*
X216141Y1224803D03*
X223622D03*
X227362Y1232283D03*
X223622Y1228543D03*
X216141D03*
X227362Y1236023D03*
X231102Y1243503D03*
Y1247243D03*
X223622Y1243503D03*
X216141Y1247243D03*
X223622D03*
X216141Y1243503D03*
X219881Y1250984D03*
Y1254724D03*
X227362D03*
Y1250984D03*
X234841Y1075195D03*
X242321Y1075196D03*
Y1078936D03*
X246061Y1082677D03*
X238581Y1082676D03*
X234841Y1078935D03*
X246061Y1086417D03*
X238581Y1086416D03*
X234841Y1093897D03*
X246062Y1105117D03*
X242321Y1097637D03*
X234841D03*
X238582Y1101376D03*
X246062D03*
X238582Y1105117D03*
X242321Y1093897D03*
X238582Y1224803D03*
Y1228543D03*
X242322Y1236023D03*
Y1232283D03*
X246062Y1228543D03*
X234842Y1232283D03*
X246062Y1224803D03*
X234842Y1236023D03*
X238582Y1247243D03*
X246062Y1243503D03*
X242322Y1250984D03*
X234842D03*
X246062Y1247243D03*
X234842Y1254724D03*
X238582Y1243503D03*
X242322Y1254724D03*
X249802Y1075196D03*
X257282D03*
X249802Y1078936D03*
X261022Y1086417D03*
X253542Y1082676D03*
X257282Y1078936D03*
X253542Y1086416D03*
X261022Y1082677D03*
X249802Y1097637D03*
X257282D03*
X249802Y1093897D03*
X253543Y1105117D03*
Y1101376D03*
X257282Y1093897D03*
X261023Y1105117D03*
Y1101376D03*
Y1224803D03*
X253543Y1228543D03*
X249803Y1232283D03*
X257283D03*
Y1236023D03*
X261023Y1228543D03*
X253543Y1224803D03*
X249803Y1236023D03*
X261023Y1243503D03*
X249803Y1250984D03*
X261023Y1247243D03*
X257283Y1250984D03*
X253543Y1247243D03*
X257283Y1254724D03*
X249803D03*
X253543Y1243503D03*
X279723Y1075196D03*
X264762D03*
X272243D03*
X275982Y1082677D03*
Y1086417D03*
X268502Y1082676D03*
X272243Y1078936D03*
X268502Y1086416D03*
X279723Y1078936D03*
X264762D03*
Y1097637D03*
X268503Y1105117D03*
X272243Y1097637D03*
X275984Y1105117D03*
X279723Y1093897D03*
X272243D03*
X279723Y1097637D03*
X268503Y1101376D03*
X275984D03*
X264762Y1093897D03*
X264763Y1232283D03*
X268503Y1224803D03*
X275984D03*
X272244Y1236023D03*
X279724Y1232283D03*
Y1236023D03*
X275984Y1228543D03*
X272244Y1232283D03*
X268503Y1228543D03*
X264763Y1236023D03*
Y1254724D03*
Y1250984D03*
X268503Y1243503D03*
Y1247243D03*
X272244Y1254724D03*
Y1250984D03*
X275984Y1243503D03*
Y1247243D03*
X279724Y1250984D03*
Y1254724D03*
X287203Y1075196D03*
X294684D03*
X290943Y1086417D03*
X287203Y1078936D03*
X290943Y1082677D03*
X283463Y1082676D03*
Y1086416D03*
X294684Y1078936D03*
X283464Y1101376D03*
X294684Y1093897D03*
X287203D03*
X294684Y1097637D03*
X283464Y1105117D03*
X290944Y1101376D03*
Y1105117D03*
X287203Y1097637D03*
X294684Y1123818D03*
Y1116338D03*
Y1131299D03*
X294685Y1198621D03*
Y1213582D03*
Y1206102D03*
X287204Y1232283D03*
X283464Y1224803D03*
Y1228543D03*
X287204Y1236023D03*
X294685D03*
X290944Y1224803D03*
X294685Y1232283D03*
X290944Y1228543D03*
X287204Y1254724D03*
X283464Y1243503D03*
Y1247243D03*
X287204Y1250984D03*
X302164Y1075196D03*
X309644D03*
X305904Y1082677D03*
X302164Y1078936D03*
X305904Y1086417D03*
X309644Y1078936D03*
X298424Y1086416D03*
Y1082676D03*
X298425Y1105117D03*
Y1101376D03*
X309644Y1097637D03*
X302164D03*
X305905Y1105117D03*
X309644Y1093897D03*
X305905Y1101376D03*
X302164Y1093897D03*
X302165Y1120078D03*
X305905Y1112598D03*
X298425Y1116338D03*
X305905Y1120078D03*
X302165Y1112598D03*
X298425Y1123818D03*
X305905Y1127559D03*
Y1135039D03*
X302165D03*
Y1127559D03*
X298425Y1131299D03*
Y1198621D03*
X305905Y1202362D03*
X302165D03*
X298425Y1213582D03*
X305905Y1209842D03*
Y1217322D03*
X302165Y1209842D03*
X298425Y1206102D03*
X302165Y1217322D03*
Y1232283D03*
X309645D03*
X298425Y1224803D03*
Y1228543D03*
X309645Y1236023D03*
X305905Y1228543D03*
Y1224803D03*
X302165Y1236023D03*
X317124Y1075196D03*
X320866Y1090157D03*
X324606D03*
Y1082676D03*
X317124Y1078936D03*
X313384Y1082677D03*
Y1086417D03*
X320866Y1082676D03*
X313385Y1101377D03*
X317125Y1093897D03*
X320866Y1101377D03*
X313385Y1105117D03*
X324606Y1101377D03*
X317125Y1097637D03*
X313385Y1120078D03*
X324606Y1123818D03*
Y1108858D03*
X320866D03*
X317125Y1112598D03*
X324606Y1116338D03*
X313385Y1112598D03*
X317125Y1120078D03*
X320866Y1116338D03*
Y1123818D03*
X313385Y1127558D03*
X317125Y1135039D03*
X313385D03*
X324606Y1131299D03*
X317125Y1127558D03*
X320866Y1131299D03*
X317125Y1236023D03*
X313385Y1224803D03*
X324606Y1228543D03*
X317125Y1232283D03*
X313385Y1228543D03*
X320866D03*
X324606Y1239763D03*
X320866D03*
X602165Y1191141D03*
Y1198621D03*
Y1221062D03*
Y1206102D03*
Y1213582D03*
Y1228543D03*
Y1247243D03*
Y1239763D03*
X613386Y1187401D03*
X609646D03*
X620866D03*
X605905Y1191141D03*
X613386Y1194881D03*
X605905Y1198621D03*
X609646Y1194881D03*
Y1202362D03*
X613386D03*
X620866D03*
Y1194881D03*
X613386Y1217322D03*
X605905Y1221062D03*
X609646Y1217322D03*
Y1209842D03*
X605905Y1206102D03*
Y1213582D03*
X620866Y1209842D03*
X613386D03*
X620866Y1217322D03*
X605905Y1228543D03*
X620866D03*
Y1224803D03*
X609646Y1232283D03*
X617126Y1236023D03*
X613386Y1228543D03*
X617126Y1232283D03*
X609646Y1236023D03*
X613386Y1224803D03*
X605905Y1247243D03*
X617126Y1250984D03*
X620866Y1243503D03*
Y1247243D03*
X609646Y1254724D03*
X613386Y1247243D03*
X617126Y1254724D03*
X613386Y1243503D03*
X609646Y1250984D03*
X605905Y1239763D03*
X632086Y1075196D03*
Y1078936D03*
X635827Y1086417D03*
Y1082677D03*
X632086Y1097637D03*
X635827Y1105117D03*
X632086Y1093897D03*
X635827Y1101376D03*
X624606Y1187401D03*
X628346Y1191141D03*
X624606Y1194881D03*
X632086Y1191141D03*
X628346Y1198621D03*
X624606Y1202362D03*
X632086Y1198621D03*
X628346Y1206102D03*
X632086D03*
X624606Y1217322D03*
X628346Y1213582D03*
X632086D03*
X624606Y1209842D03*
X628346Y1224803D03*
Y1228543D03*
X635827D03*
X632086Y1232283D03*
Y1236023D03*
X624606Y1232283D03*
Y1236023D03*
X635827Y1224803D03*
X624606Y1254724D03*
Y1250984D03*
X639567Y1075196D03*
X647047D03*
X643307Y1086417D03*
Y1082677D03*
X647047Y1078936D03*
X639567D03*
X650787Y1082677D03*
Y1086417D03*
Y1105117D03*
X647047Y1093897D03*
X639567Y1097637D03*
X643307Y1105117D03*
X647047Y1097637D03*
X639567Y1093897D03*
X643307Y1101376D03*
X650787D03*
X639567Y1236023D03*
X647047D03*
X639567Y1232283D03*
X643307Y1224803D03*
X647047Y1232283D03*
X643307Y1228543D03*
X650787D03*
Y1224803D03*
X662008Y1075196D03*
X654527D03*
X669488D03*
X662008Y1078936D03*
X665748Y1082677D03*
X658268D03*
X654527Y1078936D03*
X665748Y1086417D03*
X658268D03*
X669488Y1078936D03*
X662008Y1097637D03*
X654527Y1093897D03*
X669488D03*
X665748Y1105117D03*
X654527Y1097637D03*
X662008Y1093897D03*
X669488Y1097637D03*
X665748Y1101376D03*
X658268Y1105117D03*
Y1101376D03*
X669488Y1232283D03*
X654527Y1236023D03*
X662008Y1232283D03*
X665748Y1224803D03*
X662008Y1236023D03*
X658268Y1224803D03*
X665748Y1228543D03*
X658268D03*
X669488Y1236023D03*
X654527Y1232283D03*
X662008Y1254724D03*
X665748Y1247243D03*
X669488Y1250984D03*
X658268Y1247243D03*
X662008Y1250984D03*
X665748Y1243503D03*
X669488Y1254724D03*
X658268Y1243503D03*
X676968Y1075196D03*
X684449D03*
X676968Y1078936D03*
X680709Y1086417D03*
X684449Y1078936D03*
X673228Y1086417D03*
Y1082677D03*
X680709D03*
X673228Y1105117D03*
X684449Y1093897D03*
X676968D03*
X684449Y1097637D03*
X676968D03*
X680708Y1105117D03*
X673228Y1101376D03*
X680708D03*
X676968Y1236023D03*
X684449Y1232283D03*
X673228Y1228543D03*
X680709Y1224803D03*
X684449Y1236023D03*
X676968Y1232283D03*
X673228Y1224803D03*
X680709Y1228543D03*
X673228Y1243503D03*
X680709Y1247243D03*
X673228D03*
X684449Y1254724D03*
Y1250984D03*
X676968Y1254724D03*
Y1250984D03*
X680709Y1243503D03*
X699408Y1075196D03*
X691928Y1075195D03*
X688189Y1086417D03*
Y1082677D03*
X691928Y1078935D03*
X699408Y1078936D03*
X695668Y1086416D03*
Y1082676D03*
X688189Y1105117D03*
X695669Y1101376D03*
X699408Y1097637D03*
X695669Y1105117D03*
X691928Y1093897D03*
Y1097637D03*
X699408Y1093897D03*
X688189Y1101376D03*
Y1228543D03*
X691929Y1236023D03*
X699409Y1232283D03*
X688189Y1224803D03*
X699409Y1236023D03*
X691929Y1232283D03*
X695669Y1228543D03*
Y1224803D03*
X699409Y1254724D03*
X691929Y1250984D03*
X688189Y1247243D03*
Y1243503D03*
X691929Y1254724D03*
X695669Y1247243D03*
X699409Y1250984D03*
X695669Y1243503D03*
X706889Y1075196D03*
X714369D03*
X706889Y1078936D03*
X718109Y1086417D03*
X714369Y1078936D03*
X703148Y1082677D03*
X710629Y1086416D03*
X703148Y1086417D03*
X718109Y1082677D03*
X710629Y1082676D03*
X714369Y1097637D03*
X706889Y1093897D03*
X703149Y1105117D03*
X718110D03*
Y1101376D03*
X710630Y1105117D03*
X714369Y1093897D03*
X706889Y1097637D03*
X703149Y1101376D03*
X710630D03*
X706890Y1236023D03*
X718110Y1228543D03*
X714370Y1236023D03*
X710630Y1228543D03*
X703149D03*
X714370Y1232283D03*
X703149Y1224803D03*
X718110D03*
X710630D03*
X706890Y1232283D03*
Y1250984D03*
X703149Y1243503D03*
X714370Y1254724D03*
Y1250984D03*
X710630Y1247243D03*
X706890Y1254724D03*
X710630Y1243503D03*
X703149Y1247243D03*
X721849Y1075196D03*
X729330D03*
X725589Y1086416D03*
X733069Y1086417D03*
X721849Y1078936D03*
X729330D03*
X733069Y1082677D03*
X725589Y1082676D03*
X725590Y1101376D03*
X733071Y1105117D03*
X725590D03*
X721849Y1097637D03*
Y1093897D03*
X729330Y1097637D03*
X733071Y1101376D03*
X729330Y1093897D03*
X725590Y1228543D03*
X733071D03*
X721850Y1236023D03*
X733071Y1224803D03*
X721850Y1232283D03*
X725590Y1224803D03*
X729331Y1236023D03*
Y1232283D03*
X736810Y1075196D03*
X744290D03*
Y1078936D03*
X748030Y1086417D03*
X740550Y1086416D03*
Y1082676D03*
X736810Y1078936D03*
X748030Y1082677D03*
X736810Y1097637D03*
X748031Y1105117D03*
X744290Y1093897D03*
X740551Y1105117D03*
X744290Y1097637D03*
X736810Y1093897D03*
X740551Y1101376D03*
X748031D03*
X744291Y1236023D03*
X736811Y1232283D03*
X744291D03*
X736811Y1236023D03*
X740551Y1224803D03*
Y1228543D03*
X748031Y1224803D03*
Y1228543D03*
Y1247243D03*
Y1243503D03*
X751771Y1075196D03*
X766731D03*
X759251D03*
X762991Y1086417D03*
X766731Y1078936D03*
X755511Y1086416D03*
X759251Y1078936D03*
X755511Y1082676D03*
X762991Y1082677D03*
X751771Y1078936D03*
Y1097637D03*
X762992Y1101376D03*
Y1105117D03*
X755512D03*
X759251Y1097637D03*
Y1093897D03*
X766731Y1097637D03*
X755512Y1101376D03*
X766731Y1093897D03*
X751771D03*
X755512Y1123818D03*
X759252Y1112598D03*
X751771Y1123818D03*
X762992Y1112598D03*
X755512Y1116338D03*
X751771D03*
X759252Y1120078D03*
X762992D03*
X751771Y1131299D03*
X762992Y1135039D03*
X755512Y1131299D03*
X762992Y1127559D03*
X759252Y1135039D03*
Y1127559D03*
X762992Y1202362D03*
X755512Y1198621D03*
X759252Y1202362D03*
X751772Y1198621D03*
X762992Y1217322D03*
X751772Y1213582D03*
X762992Y1209842D03*
X755512Y1213582D03*
X751772Y1206102D03*
X759252Y1217322D03*
Y1209842D03*
X755512Y1206102D03*
Y1228543D03*
X751772Y1236023D03*
X762992Y1228543D03*
X751772Y1232283D03*
X766732D03*
Y1236023D03*
X759252Y1232283D03*
X762992Y1224803D03*
X759252Y1236023D03*
X755512Y1224803D03*
X766732Y1250984D03*
X755512Y1243503D03*
X762992D03*
Y1247243D03*
X751772Y1250984D03*
Y1254724D03*
X759252D03*
X766732D03*
X759252Y1250984D03*
X755512Y1247243D03*
X774211Y1075196D03*
X781693Y1090157D03*
X777953D03*
X781693Y1082676D03*
X774211Y1078936D03*
X770471Y1086417D03*
Y1082677D03*
X777953Y1082676D03*
X770472Y1101377D03*
X781693D03*
X777953D03*
X774212Y1097637D03*
X770472Y1105117D03*
X774212Y1093897D03*
Y1112598D03*
X770472D03*
X781693Y1123818D03*
X777953D03*
X781693Y1116338D03*
X777953Y1108858D03*
X770472Y1120078D03*
X781693Y1108858D03*
X777953Y1116338D03*
X774212Y1120078D03*
X770472Y1127558D03*
Y1135039D03*
X781693Y1131299D03*
X774212Y1127558D03*
Y1135039D03*
X777953Y1131299D03*
X781693Y1198621D03*
X774212Y1202362D03*
X770472D03*
X777953Y1198621D03*
Y1206102D03*
X770472Y1209842D03*
X781693Y1213582D03*
X774212Y1209842D03*
X777953Y1221062D03*
X781693D03*
Y1206102D03*
X770472Y1217322D03*
X774212D03*
X777953Y1213582D03*
X770472Y1228543D03*
X781693D03*
X770472Y1224803D03*
X777953Y1228543D03*
X774212Y1232283D03*
Y1236023D03*
X777953Y1239763D03*
X781693D03*
X777953Y1247243D03*
X770472Y1243503D03*
X781693Y1247243D03*
X770472D03*
X774212Y1250984D03*
Y1254724D03*
X1059251Y1198621D03*
Y1191141D03*
Y1221062D03*
Y1206102D03*
Y1213582D03*
Y1228543D03*
Y1247243D03*
Y1239763D03*
X1070472Y1187401D03*
X1066732D03*
X1062991Y1198621D03*
X1066732Y1194881D03*
X1062991Y1191141D03*
X1070472Y1194881D03*
Y1202362D03*
X1066732D03*
X1070472Y1217322D03*
X1066732D03*
X1062991Y1221062D03*
Y1206102D03*
X1070472Y1209842D03*
X1062991Y1213582D03*
X1066732Y1209842D03*
X1070472Y1228543D03*
X1066732Y1236023D03*
Y1232283D03*
X1074212Y1236023D03*
Y1232283D03*
X1070472Y1224803D03*
X1062991Y1228543D03*
X1074212Y1250984D03*
X1066732Y1254724D03*
X1070472Y1247243D03*
X1074212Y1254724D03*
X1062991Y1247243D03*
X1070472Y1243503D03*
X1062991Y1239763D03*
X1066732Y1250984D03*
X1089172Y1075196D03*
Y1078936D03*
Y1097637D03*
Y1093897D03*
X1077952Y1187401D03*
X1081692D03*
X1077952Y1194881D03*
Y1202362D03*
X1089172Y1191141D03*
Y1198621D03*
X1081692Y1202362D03*
X1085432Y1198621D03*
X1081692Y1194881D03*
X1085432Y1191141D03*
X1089172Y1206102D03*
X1077952Y1209842D03*
X1081692D03*
Y1217322D03*
X1089172Y1213582D03*
X1077952Y1217322D03*
X1085432Y1206102D03*
Y1213582D03*
X1089172Y1232283D03*
X1081692D03*
Y1236023D03*
X1089172D03*
X1077952Y1224803D03*
Y1228543D03*
X1085432Y1224803D03*
Y1228543D03*
X1077952Y1243503D03*
X1081692Y1250984D03*
X1077952Y1247243D03*
X1081692Y1254724D03*
X1085432Y1243503D03*
X1089172Y1254724D03*
Y1250984D03*
X1085432Y1247243D03*
X1096653Y1075196D03*
X1104133D03*
X1100393Y1082677D03*
X1104133Y1078936D03*
X1107873Y1082677D03*
Y1086417D03*
X1092913Y1082677D03*
X1100393Y1086417D03*
X1092913D03*
X1096653Y1078936D03*
X1092913Y1105117D03*
X1104133Y1097637D03*
X1096653D03*
X1100393Y1105117D03*
X1104133Y1093897D03*
X1100393Y1101376D03*
X1096653Y1093897D03*
X1092913Y1101376D03*
X1107873Y1105117D03*
Y1101376D03*
X1100393Y1228543D03*
X1104133Y1236023D03*
X1092913Y1224803D03*
X1104133Y1232283D03*
X1107873Y1224803D03*
X1096653Y1236023D03*
X1100393Y1224803D03*
X1107873Y1228543D03*
X1096653Y1232283D03*
X1092913Y1228543D03*
X1096653Y1254724D03*
X1104133D03*
X1092913Y1247243D03*
X1096653Y1250984D03*
X1092913Y1243503D03*
X1107873D03*
X1100393D03*
X1107873Y1247243D03*
X1100393D03*
X1104133Y1250984D03*
X1111613Y1075196D03*
X1119094D03*
X1122834Y1086417D03*
X1119094Y1078936D03*
X1115354Y1082677D03*
X1111613Y1078936D03*
X1115354Y1086417D03*
X1122834Y1082677D03*
X1119094Y1097637D03*
X1115354Y1101376D03*
X1111613Y1093897D03*
Y1097637D03*
X1122834Y1105117D03*
X1119094Y1093897D03*
X1122834Y1101376D03*
X1115354Y1105117D03*
X1122834Y1224803D03*
X1119094Y1232283D03*
X1115354Y1228543D03*
X1111613Y1232283D03*
X1119094Y1236023D03*
X1115354Y1224803D03*
X1111613Y1236023D03*
X1122834Y1228543D03*
Y1243503D03*
X1119094Y1250984D03*
X1111613Y1254724D03*
X1119094D03*
X1122834Y1247243D03*
X1115354Y1243503D03*
Y1247243D03*
X1111613Y1250984D03*
X1126574Y1075196D03*
X1134054D03*
Y1078936D03*
X1126574D03*
X1130314Y1086417D03*
Y1082677D03*
X1137795Y1086417D03*
Y1082677D03*
X1126574Y1093897D03*
X1130314Y1105117D03*
X1134054Y1093897D03*
X1130314Y1101376D03*
X1134054Y1097637D03*
X1137794Y1105117D03*
X1126574Y1097637D03*
X1137794Y1101376D03*
X1134054Y1236023D03*
X1137795Y1228543D03*
X1134054Y1232283D03*
X1126574D03*
Y1236023D03*
X1137795Y1224803D03*
X1130314Y1228543D03*
Y1224803D03*
X1126574Y1254724D03*
X1137795Y1243503D03*
X1130314Y1247243D03*
X1126574Y1250984D03*
X1137795Y1247243D03*
X1130314Y1243503D03*
X1134054Y1250984D03*
Y1254724D03*
X1141535Y1075196D03*
X1156494D03*
X1149014Y1075195D03*
X1145275Y1086417D03*
Y1082677D03*
X1141535Y1078936D03*
X1149014Y1078935D03*
X1156494Y1078936D03*
X1152754Y1086416D03*
Y1082676D03*
X1145275Y1105117D03*
X1141535Y1093897D03*
X1145275Y1101376D03*
X1141535Y1097637D03*
X1149014D03*
X1156494Y1093897D03*
X1152755Y1101376D03*
X1156494Y1097637D03*
X1149014Y1093897D03*
X1152755Y1105117D03*
X1149015Y1236023D03*
Y1232283D03*
X1152755Y1228543D03*
X1145275Y1224803D03*
X1156495Y1232283D03*
Y1236023D03*
X1141535D03*
X1145275Y1228543D03*
X1152755Y1224803D03*
X1141535Y1232283D03*
Y1254724D03*
Y1250984D03*
X1149015Y1254724D03*
X1145275Y1247243D03*
X1152755Y1243503D03*
X1156495Y1254724D03*
X1145275Y1243503D03*
X1152755Y1247243D03*
X1149015Y1250984D03*
X1156495D03*
X1163975Y1075196D03*
X1171455D03*
X1160234Y1086417D03*
X1167715Y1086416D03*
X1163975Y1078936D03*
X1160234Y1082677D03*
X1171455Y1078936D03*
X1167715Y1082676D03*
X1160235Y1105117D03*
Y1101376D03*
X1171455Y1093897D03*
X1167716Y1105117D03*
X1171455Y1097637D03*
X1163975Y1093897D03*
Y1097637D03*
X1167716Y1101376D03*
X1160235Y1224803D03*
X1163976Y1232283D03*
X1167716Y1224803D03*
X1160235Y1228543D03*
X1171456Y1232283D03*
X1163976Y1236023D03*
X1171456D03*
X1167716Y1228543D03*
X1171456Y1250984D03*
X1167716Y1247243D03*
X1163976Y1250984D03*
X1160235Y1247243D03*
Y1243503D03*
X1167716D03*
X1171456Y1254724D03*
X1163976D03*
X1178935Y1075196D03*
X1186416D03*
X1175195Y1086417D03*
X1182675Y1086416D03*
X1175195Y1082677D03*
X1178935Y1078936D03*
X1182675Y1082676D03*
X1186416Y1078936D03*
X1178935Y1097637D03*
X1186416Y1093897D03*
X1182676Y1105117D03*
X1175196D03*
X1178935Y1093897D03*
X1182676Y1101376D03*
X1175196D03*
X1186416Y1097637D03*
X1182676Y1228543D03*
X1186417Y1236023D03*
X1178936D03*
X1186417Y1232283D03*
X1175196Y1228543D03*
X1178936Y1232283D03*
X1182676Y1224803D03*
X1175196D03*
X1178936Y1254724D03*
X1175196Y1243503D03*
X1182676Y1247243D03*
X1178936Y1250984D03*
X1186417D03*
X1182676Y1243503D03*
X1186417Y1254724D03*
X1175196Y1247243D03*
X1193896Y1075196D03*
X1201376D03*
X1190155Y1086417D03*
X1205116Y1082677D03*
X1190155D03*
X1197636Y1082676D03*
X1193896Y1078936D03*
X1205116Y1086417D03*
X1201376Y1078936D03*
X1197636Y1086416D03*
X1201376Y1093897D03*
X1193896Y1097637D03*
X1197637Y1105117D03*
X1205117D03*
X1197637Y1101376D03*
X1205117D03*
X1190157D03*
X1193896Y1093897D03*
X1201376Y1097637D03*
X1190157Y1105117D03*
X1197637Y1224803D03*
X1193897Y1236023D03*
X1190157Y1228543D03*
X1201377Y1236023D03*
X1190157Y1224803D03*
X1193897Y1232283D03*
X1197637Y1228543D03*
X1201377Y1232283D03*
X1205117Y1228543D03*
Y1224803D03*
X1190157Y1243503D03*
X1201377Y1250984D03*
X1197637Y1247243D03*
X1193897Y1250984D03*
X1201377Y1254724D03*
X1197637Y1243503D03*
X1193897Y1254724D03*
X1190157Y1247243D03*
X1216337Y1075196D03*
X1208857D03*
X1212597Y1082676D03*
Y1086416D03*
X1220077Y1086417D03*
X1208857Y1078936D03*
X1216337D03*
X1220077Y1082677D03*
X1220078Y1105117D03*
X1216337Y1093897D03*
X1212598Y1101376D03*
Y1105117D03*
X1208857Y1093897D03*
X1216337Y1097637D03*
X1220078Y1101376D03*
X1208857Y1097637D03*
X1212598Y1123818D03*
X1208857Y1116338D03*
X1212598D03*
X1216338Y1120078D03*
Y1112598D03*
X1208857Y1123818D03*
X1220078Y1112598D03*
Y1120078D03*
X1216338Y1127559D03*
Y1135039D03*
X1212598Y1131299D03*
X1208857D03*
X1220078Y1135039D03*
Y1127559D03*
X1212598Y1198621D03*
X1208858D03*
X1216338Y1202362D03*
X1220078D03*
Y1217322D03*
Y1209842D03*
X1212598Y1206102D03*
X1216338Y1217322D03*
X1212598Y1213582D03*
X1208858Y1206102D03*
Y1213582D03*
X1216338Y1209842D03*
X1220078Y1224803D03*
X1212598Y1228543D03*
X1208858Y1232283D03*
X1216338Y1236023D03*
Y1232283D03*
X1212598Y1224803D03*
X1220078Y1228543D03*
X1208858Y1236023D03*
X1231297Y1075196D03*
X1223817D03*
X1235039Y1090157D03*
X1231297Y1078936D03*
X1235039Y1082676D03*
X1227557Y1086417D03*
X1223817Y1078936D03*
X1227557Y1082677D03*
X1227558Y1101377D03*
X1231298Y1093897D03*
X1235039Y1101377D03*
X1227558Y1105117D03*
X1223817Y1093897D03*
Y1097637D03*
X1231298D03*
X1227558Y1112598D03*
X1235039Y1123818D03*
X1231298Y1120078D03*
Y1112598D03*
X1235039Y1108858D03*
Y1116338D03*
X1227558Y1120078D03*
X1231298Y1135039D03*
X1227558Y1127558D03*
X1235039Y1131299D03*
X1231298Y1127558D03*
X1227558Y1135039D03*
X1231298Y1232283D03*
X1227558Y1228543D03*
Y1224803D03*
X1223818Y1236023D03*
X1231298D03*
X1235039Y1228543D03*
X1223818Y1232283D03*
X1235039Y1239763D03*
X1238779Y1090157D03*
Y1082676D03*
Y1101377D03*
Y1108858D03*
Y1116338D03*
Y1123818D03*
Y1131299D03*
Y1228543D03*
Y1239763D03*
X1523819Y1187401D03*
X1527559D03*
X1516338Y1198621D03*
X1523819Y1194881D03*
X1520078Y1198621D03*
X1523819Y1202362D03*
X1516338Y1191141D03*
X1527559Y1202362D03*
Y1194881D03*
X1520078Y1191141D03*
Y1221062D03*
X1516338Y1213582D03*
Y1206102D03*
X1520078D03*
X1527559Y1217322D03*
X1523819Y1209842D03*
X1516338Y1221062D03*
X1527559Y1209842D03*
X1523819Y1217322D03*
X1520078Y1213582D03*
X1527559Y1228543D03*
X1516338D03*
X1523819Y1232283D03*
X1520078Y1228543D03*
X1523819Y1236023D03*
X1527559Y1224803D03*
X1516338Y1239763D03*
X1520078D03*
Y1247243D03*
X1516338D03*
X1527559Y1243503D03*
Y1247243D03*
X1523819Y1250984D03*
Y1254724D03*
X1546259Y1075196D03*
Y1078936D03*
Y1097637D03*
Y1093897D03*
X1535039Y1187401D03*
X1538779D03*
X1542519Y1191141D03*
X1538779Y1202362D03*
X1535039Y1194881D03*
X1542519Y1198621D03*
X1546259D03*
Y1191141D03*
X1535039Y1202362D03*
X1538779Y1194881D03*
X1542519Y1213582D03*
Y1206102D03*
X1546259Y1213582D03*
X1535039Y1209842D03*
Y1217322D03*
X1546259Y1206102D03*
X1538779Y1209842D03*
Y1217322D03*
X1546259Y1232283D03*
X1535039Y1224803D03*
X1538779Y1236023D03*
X1531299Y1232283D03*
X1542519Y1228543D03*
X1535039D03*
X1546259Y1236023D03*
X1542519Y1224803D03*
X1531299Y1236023D03*
X1538779Y1232283D03*
Y1250984D03*
Y1254724D03*
X1535039Y1243503D03*
X1531299Y1250984D03*
X1535039Y1247243D03*
X1531299Y1254724D03*
X1553740Y1075196D03*
X1561220D03*
X1557480Y1082677D03*
X1553740Y1078936D03*
X1561220D03*
X1550000Y1086417D03*
Y1082677D03*
X1557480Y1086417D03*
Y1101376D03*
X1561220Y1093897D03*
X1557480Y1105117D03*
X1561220Y1097637D03*
X1550000Y1101376D03*
Y1105117D03*
X1553740Y1093897D03*
Y1097637D03*
Y1232283D03*
X1550000Y1228543D03*
X1553740Y1236023D03*
X1550000Y1224803D03*
X1557480Y1228543D03*
X1561220Y1236023D03*
Y1232283D03*
X1557480Y1224803D03*
X1576181Y1075196D03*
X1568700D03*
Y1078936D03*
X1572441Y1086417D03*
X1564960Y1082677D03*
Y1086417D03*
X1572441Y1082677D03*
X1576181Y1078936D03*
X1564960Y1105117D03*
X1576181Y1097637D03*
X1568700D03*
X1576181Y1093897D03*
X1568700D03*
X1572441Y1101376D03*
Y1105117D03*
X1564960Y1101376D03*
X1572441Y1228543D03*
X1568700Y1236023D03*
X1564960Y1224803D03*
X1576181Y1236023D03*
X1572441Y1224803D03*
X1564960Y1228543D03*
X1576181Y1232283D03*
X1568700D03*
X1572441Y1247243D03*
X1576181Y1254724D03*
Y1250984D03*
X1572441Y1243503D03*
X1583661Y1075196D03*
X1591141D03*
X1594882Y1082677D03*
X1579921D03*
X1583661Y1078936D03*
X1594882Y1086417D03*
X1587401Y1082677D03*
X1579921Y1086417D03*
X1587401D03*
X1591141Y1078936D03*
X1594881Y1105117D03*
X1591141Y1097637D03*
X1583661Y1093897D03*
X1594881Y1101376D03*
X1583661Y1097637D03*
X1587401Y1105117D03*
X1579921Y1101376D03*
X1591141Y1093897D03*
X1587401Y1101376D03*
X1579921Y1105117D03*
X1594882Y1224803D03*
X1591141Y1232283D03*
X1583661Y1236023D03*
X1579921Y1228543D03*
X1583661Y1232283D03*
X1594882Y1228543D03*
X1579921Y1224803D03*
X1587401Y1228543D03*
Y1224803D03*
X1591141Y1236023D03*
X1583661Y1254724D03*
X1579921Y1247243D03*
X1591141Y1254724D03*
X1587401Y1247243D03*
Y1243503D03*
X1594882D03*
X1579921D03*
X1594882Y1247243D03*
X1583661Y1250984D03*
X1591141D03*
X1606101Y1075195D03*
X1598622Y1075196D03*
X1609841Y1086416D03*
X1606101Y1078935D03*
X1609841Y1082676D03*
X1602362Y1082677D03*
Y1086417D03*
X1598622Y1078936D03*
X1606101Y1093897D03*
X1602362Y1101376D03*
X1598622Y1097637D03*
Y1093897D03*
X1602362Y1105117D03*
X1609842Y1101376D03*
Y1105117D03*
X1606101Y1097637D03*
X1598622Y1236023D03*
X1606102D03*
X1609842Y1228543D03*
X1606102Y1232283D03*
X1602362Y1224803D03*
X1609842D03*
X1602362Y1228543D03*
X1598622Y1232283D03*
Y1254724D03*
Y1250984D03*
X1609842Y1247243D03*
X1606102Y1250984D03*
Y1254724D03*
X1609842Y1243503D03*
X1602362Y1247243D03*
Y1243503D03*
X1613581Y1075196D03*
X1621062D03*
X1613581Y1078936D03*
X1624802Y1082676D03*
X1617321Y1082677D03*
X1621062Y1078936D03*
X1617321Y1086417D03*
X1624802Y1086416D03*
X1621062Y1093897D03*
X1617322Y1105117D03*
Y1101376D03*
X1613581Y1093897D03*
Y1097637D03*
X1624803Y1101376D03*
Y1105117D03*
X1621062Y1097637D03*
X1617322Y1228543D03*
X1624803Y1224803D03*
X1617322D03*
X1621063Y1236023D03*
X1613582D03*
X1621063Y1232283D03*
X1624803Y1228543D03*
X1613582Y1232283D03*
X1624803Y1247243D03*
Y1243503D03*
X1621063Y1254724D03*
X1613582Y1250984D03*
X1617322Y1243503D03*
Y1247243D03*
X1613582Y1254724D03*
X1621063Y1250984D03*
X1636022Y1075196D03*
X1643503D03*
X1628542D03*
X1632282Y1082677D03*
X1643503Y1078936D03*
X1628542D03*
X1639762Y1086416D03*
X1632282Y1086417D03*
X1636022Y1078936D03*
X1639762Y1082676D03*
X1639763Y1101376D03*
X1628542Y1093897D03*
X1636022D03*
X1639763Y1105117D03*
X1632283D03*
Y1101376D03*
X1636022Y1097637D03*
X1643503D03*
Y1093897D03*
X1628542Y1097637D03*
X1632283Y1228543D03*
X1628543Y1236023D03*
Y1232283D03*
X1639763Y1224803D03*
X1636023Y1236023D03*
X1643504Y1232283D03*
X1632283Y1224803D03*
X1643504Y1236023D03*
X1636023Y1232283D03*
X1639763Y1228543D03*
X1628543Y1250984D03*
Y1254724D03*
X1650983Y1075196D03*
X1658463D03*
X1654723Y1086416D03*
Y1082676D03*
X1650983Y1078936D03*
X1647242Y1082677D03*
Y1086417D03*
X1658463Y1078936D03*
Y1097637D03*
X1647244Y1101376D03*
X1658463Y1093897D03*
X1654724Y1105117D03*
X1650983Y1093897D03*
X1647244Y1105117D03*
X1654724Y1101376D03*
X1650983Y1097637D03*
X1654724Y1228543D03*
X1647244D03*
X1658464Y1232283D03*
X1654724Y1224803D03*
X1658464Y1236023D03*
X1650984D03*
X1647244Y1224803D03*
X1650984Y1232283D03*
X1673424Y1075196D03*
X1665944D03*
X1662203Y1086417D03*
Y1082677D03*
X1669684Y1086416D03*
X1665944Y1078936D03*
X1673424D03*
X1669684Y1082676D03*
X1665944Y1093897D03*
X1662204Y1105117D03*
X1669685D03*
X1673424Y1097637D03*
X1669685Y1101376D03*
X1673424Y1093897D03*
X1665944Y1097637D03*
X1662204Y1101376D03*
X1673425Y1112598D03*
X1665944Y1123818D03*
X1673425Y1120078D03*
X1669685Y1123818D03*
X1665944Y1116338D03*
X1669685D03*
X1665944Y1131299D03*
X1669685D03*
X1673425Y1127559D03*
Y1135039D03*
Y1202362D03*
X1665945Y1198621D03*
X1669685D03*
X1665945Y1206102D03*
X1669685Y1213582D03*
X1673425Y1209842D03*
X1669685Y1206102D03*
X1665945Y1213582D03*
X1673425Y1217322D03*
Y1236023D03*
X1662204Y1228543D03*
X1669685D03*
X1673425Y1232283D03*
X1665945D03*
Y1236023D03*
X1662204Y1224803D03*
X1669685D03*
X1673425Y1250984D03*
X1662204Y1247243D03*
X1665945Y1254724D03*
X1673425D03*
X1662204Y1243503D03*
X1665945Y1250984D03*
X1669685Y1247243D03*
Y1243503D03*
X1680904Y1075196D03*
X1688384D03*
X1692126Y1090157D03*
Y1082676D03*
X1684644Y1082677D03*
Y1086417D03*
X1680904Y1078936D03*
X1688384D03*
X1677164Y1086417D03*
Y1082677D03*
X1692126Y1101377D03*
X1684645D03*
X1677165Y1105117D03*
X1680904Y1097637D03*
X1677165Y1101376D03*
X1688385Y1097637D03*
X1684645Y1105117D03*
X1680904Y1093897D03*
X1688385D03*
X1677165Y1120078D03*
Y1112598D03*
X1692126Y1116338D03*
Y1108858D03*
X1684645Y1120078D03*
X1688385D03*
X1684645Y1112598D03*
X1692126Y1123818D03*
X1688385Y1112598D03*
X1677165Y1135039D03*
Y1127559D03*
X1684645Y1135039D03*
Y1127558D03*
X1692126Y1131299D03*
X1688385Y1127558D03*
Y1135039D03*
X1684645Y1202362D03*
X1692126Y1198621D03*
X1688385Y1202362D03*
X1677165D03*
X1692126Y1213582D03*
X1684645Y1217322D03*
Y1209842D03*
X1692126Y1206102D03*
X1677165Y1209842D03*
X1692126Y1221062D03*
X1688385Y1209842D03*
X1677165Y1217322D03*
X1688385D03*
X1677165Y1228543D03*
X1680905Y1236023D03*
Y1232283D03*
X1692126Y1228543D03*
X1684645Y1224803D03*
Y1228543D03*
X1677165Y1224803D03*
X1688385Y1232283D03*
Y1236023D03*
X1684645Y1243503D03*
X1677165D03*
X1692126Y1247243D03*
X1684645D03*
X1677165D03*
X1688385Y1254724D03*
Y1250984D03*
X1692126Y1239763D03*
X1680905Y1254724D03*
Y1250984D03*
X1695866Y1090157D03*
Y1082676D03*
Y1101377D03*
Y1123818D03*
Y1116338D03*
Y1108858D03*
Y1131299D03*
Y1198621D03*
Y1221062D03*
Y1213582D03*
Y1206102D03*
Y1228543D03*
Y1239763D03*
Y1247243D03*
G54D58*
X1250055Y1710189D03*
Y1720189D03*
Y1739208D03*
Y1749208D03*
X1250048Y1768377D03*
Y1778377D03*
X1248555Y1797909D03*
Y1807909D03*
X1734069Y1710189D03*
Y1720189D03*
Y1739208D03*
Y1749208D03*
X1734062Y1768377D03*
Y1778377D03*
X1734069Y1797909D03*
Y1807909D03*
G54D18*
X7983Y1529035D03*
Y1525635D03*
X35688Y111255D03*
Y114655D03*
X28388Y121742D03*
X35688Y125428D03*
X28388Y132515D03*
Y118342D03*
X35688Y128828D03*
X28388Y135915D03*
X35825Y1464845D03*
X39225D03*
X76005Y114623D03*
Y111223D03*
Y125396D03*
Y128796D03*
X76112Y1348187D03*
X79512D03*
X76112Y1360099D03*
X79512D03*
Y1372385D03*
X76112D03*
Y1384297D03*
X79512D03*
X86407Y132509D03*
Y118335D03*
Y121735D03*
Y135909D03*
X88352Y1348187D03*
X91752D03*
X100592D03*
X91752Y1360099D03*
X88352D03*
X100592D03*
Y1384297D03*
Y1372385D03*
X91752D03*
X88352D03*
Y1384297D03*
X91752D03*
Y1396583D03*
X88352D03*
X100592D03*
X91752Y1408495D03*
X88352D03*
X100592D03*
X116232Y1348187D03*
X112832D03*
X103992D03*
X112832Y1360099D03*
X116232D03*
X103992D03*
Y1372385D03*
Y1384297D03*
X112832D03*
X116232Y1372385D03*
Y1384297D03*
X112832Y1372385D03*
X116232Y1396583D03*
X112832D03*
X103992D03*
X112832Y1408495D03*
X116232D03*
X103992D03*
X130750Y132515D03*
Y121742D03*
Y118342D03*
Y135915D03*
X125072Y1348187D03*
X128472D03*
Y1360099D03*
X125072D03*
Y1384297D03*
X128472D03*
X125072Y1372385D03*
X128472D03*
X125072Y1396583D03*
X128472D03*
X125072Y1408495D03*
X128472D03*
X138050Y111255D03*
Y114655D03*
Y128828D03*
Y125428D03*
X148692Y391001D03*
Y394401D03*
Y405174D03*
X140690Y401513D03*
Y398113D03*
X148692Y408574D03*
X138290Y412287D03*
X148692Y419347D03*
Y422747D03*
X138290Y415687D03*
Y426460D03*
X148692Y433521D03*
X138290Y429860D03*
X148692Y436921D03*
X138290Y440633D03*
Y444033D03*
Y469387D03*
Y472787D03*
X148692Y476499D03*
X138290Y483560D03*
X148692Y490673D03*
X138290Y486960D03*
X148692Y479899D03*
Y494073D03*
Y524033D03*
Y520633D03*
X138290Y516921D03*
Y513521D03*
Y531094D03*
X148692Y538206D03*
Y534806D03*
X138290Y527694D03*
X140712Y1348187D03*
X137312D03*
X149552D03*
X137312Y1360099D03*
X140712D03*
X149552D03*
Y1384297D03*
Y1372385D03*
X140712D03*
Y1384297D03*
X137312D03*
Y1372385D03*
X140712Y1396583D03*
X137312D03*
X149552D03*
X140712Y1408495D03*
X137312D03*
X149552D03*
X165192Y1348187D03*
X161792D03*
X152952D03*
X165192Y1360099D03*
X161792D03*
X152952D03*
Y1384297D03*
Y1372385D03*
X161792Y1384297D03*
X165192Y1372385D03*
Y1384297D03*
X161792Y1372385D03*
X165192Y1396583D03*
X161792D03*
X152952D03*
X165192Y1408495D03*
X161792D03*
X152952D03*
X178367Y111223D03*
Y114623D03*
Y128796D03*
Y125396D03*
X177432Y1348187D03*
X174032D03*
Y1360099D03*
X177432D03*
Y1384297D03*
X174032D03*
Y1372385D03*
X177432D03*
Y1396583D03*
X174032D03*
X177432Y1408495D03*
X174032D03*
X188769Y118335D03*
Y121735D03*
Y132509D03*
Y135909D03*
X189672Y1348187D03*
X186272D03*
X198512D03*
X189672Y1360099D03*
X186272D03*
X198512D03*
Y1384297D03*
Y1372385D03*
X186272Y1384297D03*
X189672D03*
Y1372385D03*
X186272D03*
Y1396583D03*
X189672D03*
X198512D03*
X189672Y1408495D03*
X186272D03*
X198512D03*
X212980Y390995D03*
Y405168D03*
Y394395D03*
X205680Y401482D03*
Y398082D03*
X212980Y408568D03*
Y419341D03*
Y422741D03*
X205680Y415655D03*
Y412255D03*
Y426428D03*
Y440602D03*
Y429828D03*
X212980Y433515D03*
Y436915D03*
X205680Y444002D03*
X212980Y469381D03*
Y472781D03*
X205680Y490641D03*
Y479868D03*
X212980Y483554D03*
X205680Y476468D03*
X212980Y486954D03*
X205680Y494041D03*
Y524002D03*
X212980Y516915D03*
Y513515D03*
X205680Y520602D03*
Y534775D03*
X212980Y527688D03*
X205680Y538175D03*
X212980Y531088D03*
X201912Y1348187D03*
Y1360099D03*
Y1384297D03*
Y1372385D03*
Y1396583D03*
Y1408495D03*
X227249Y1447453D03*
Y1450853D03*
Y1458453D03*
Y1461853D03*
X240412Y114655D03*
Y111255D03*
X233112Y132515D03*
Y121742D03*
X240412Y125428D03*
X233112Y118342D03*
X240412Y128828D03*
X233112Y135915D03*
X241623Y1348187D03*
X245023D03*
Y1360099D03*
X241623D03*
X245023Y1372385D03*
X241623D03*
Y1384297D03*
X245023D03*
X264005Y467337D03*
Y470737D03*
X256705Y474424D03*
X264005Y484910D03*
X256705Y488597D03*
X264005Y481510D03*
X256705Y477824D03*
Y491997D03*
X264005Y514871D03*
X256705Y518558D03*
X264005Y511471D03*
X256705Y521958D03*
Y532731D03*
Y536131D03*
X264005Y525644D03*
Y529044D03*
Y561510D03*
X256705Y571997D03*
Y568597D03*
X264005Y564910D03*
X256705Y586171D03*
X264005Y575684D03*
Y579084D03*
X256705Y582771D03*
X264005Y589857D03*
X256705Y600344D03*
X264005Y593257D03*
Y604030D03*
X256705Y596944D03*
Y611117D03*
Y614517D03*
X264005Y607430D03*
X253863Y1348187D03*
X257263D03*
X253863Y1360099D03*
X257263D03*
X253863Y1372385D03*
X257263D03*
X253863Y1384297D03*
X257263D03*
X253863Y1396583D03*
X257263D03*
Y1408495D03*
X253863D03*
X269503Y1348187D03*
X278343D03*
X266103D03*
X278343Y1360099D03*
X266103D03*
X269503D03*
Y1372385D03*
X266103D03*
X278343D03*
X266103Y1384297D03*
X269503D03*
X278343D03*
Y1396583D03*
X269503D03*
X266103D03*
X278343Y1408495D03*
X269503D03*
X266103D03*
X280729Y111223D03*
Y114623D03*
Y125396D03*
X291131Y121735D03*
X280729Y128796D03*
X291131Y118335D03*
Y132509D03*
Y135909D03*
X281743Y1348187D03*
X293983D03*
X290583D03*
X281743Y1360099D03*
X293983D03*
X290583D03*
X293983Y1372385D03*
X281743D03*
X290583Y1384297D03*
X293983D03*
X290583Y1372385D03*
X281743Y1384297D03*
X293983Y1396583D03*
X290583D03*
X281743D03*
Y1408495D03*
X293983D03*
X290583D03*
X302823Y1348187D03*
X306223D03*
Y1360099D03*
X302823D03*
X306223Y1372385D03*
X302823D03*
X306223Y1384297D03*
X302823D03*
Y1396583D03*
X306223D03*
X302823Y1408495D03*
X306223D03*
X320993Y467306D03*
Y470706D03*
Y481479D03*
Y484879D03*
Y514839D03*
Y511439D03*
Y525613D03*
Y529013D03*
Y564879D03*
Y561479D03*
Y575652D03*
Y579052D03*
Y603999D03*
Y593225D03*
Y589825D03*
Y607399D03*
X327303Y1348187D03*
X315063D03*
X318463D03*
X327303Y1360099D03*
X315063D03*
X318463D03*
X315063Y1372385D03*
X318463Y1384297D03*
X315063D03*
X327303Y1372385D03*
X318463D03*
X327303Y1384297D03*
Y1396583D03*
X315063D03*
X318463D03*
X327303Y1408495D03*
X318463D03*
X315063D03*
X342774Y111255D03*
Y114655D03*
X335474Y118342D03*
Y132515D03*
X342774Y125428D03*
X335474Y121742D03*
X342774Y128828D03*
X335474Y135915D03*
X331395Y474418D03*
Y488591D03*
Y477818D03*
Y491991D03*
Y518552D03*
Y521952D03*
Y536125D03*
Y532725D03*
Y568591D03*
Y571991D03*
Y586165D03*
Y582765D03*
Y600338D03*
Y596938D03*
Y611111D03*
Y614511D03*
X339543Y1348187D03*
X342943D03*
X330703D03*
Y1360099D03*
X342943D03*
X339543D03*
Y1372385D03*
X342943D03*
X330703D03*
X342943Y1384297D03*
X339543D03*
X330703D03*
Y1396583D03*
X339543D03*
X342943D03*
X330703Y1408495D03*
X342943D03*
X339543D03*
X351783Y1348187D03*
X355183D03*
Y1360099D03*
X351783D03*
Y1372385D03*
X355183D03*
Y1384297D03*
X351783D03*
Y1396583D03*
X355183D03*
X351783Y1408495D03*
X355183D03*
X364023Y1348187D03*
X367423D03*
Y1360099D03*
X364023D03*
Y1372385D03*
X367423Y1384297D03*
X364023D03*
X367423Y1372385D03*
X364023Y1396583D03*
X367423D03*
X364023Y1408495D03*
X367423D03*
X383091Y111223D03*
Y114623D03*
X393493Y118335D03*
X383091Y125396D03*
Y128796D03*
X393493Y132509D03*
Y121735D03*
Y135909D03*
X392415Y792725D03*
X389015D03*
X440402Y1348187D03*
Y1360099D03*
Y1372385D03*
Y1384297D03*
X452642Y1348187D03*
X456042D03*
X443802D03*
X456042Y1360099D03*
X452642D03*
X443802D03*
Y1372385D03*
X452642D03*
X456042D03*
X452642Y1384297D03*
X456042D03*
X443802D03*
X452642Y1396583D03*
X456042D03*
X452642Y1408495D03*
X456042D03*
X468282Y1348187D03*
X464882D03*
X468282Y1360099D03*
X464882D03*
Y1372385D03*
X468282D03*
X464882Y1384297D03*
X468282D03*
Y1396583D03*
X464882D03*
Y1408495D03*
X468282D03*
X485475Y118342D03*
Y121742D03*
Y132515D03*
Y135915D03*
X489362Y1348187D03*
X480522D03*
X477122D03*
X480522Y1360099D03*
X477122D03*
X489362D03*
X477122Y1372385D03*
X480522D03*
X489362D03*
Y1384297D03*
X480522D03*
X477122D03*
X480522Y1396583D03*
X477122D03*
X489362D03*
X477122Y1408495D03*
X480522D03*
X489362D03*
X492775Y114655D03*
Y111255D03*
Y128828D03*
Y125428D03*
X492762Y1348187D03*
X501602D03*
X505002D03*
X501602Y1360099D03*
X505002D03*
X492762D03*
X505002Y1372385D03*
X492762D03*
X501602D03*
X492762Y1384297D03*
X505002D03*
X501602D03*
X505002Y1396583D03*
X492762D03*
X501602D03*
X505002Y1408495D03*
X501602D03*
X492762D03*
X517242Y1348187D03*
X513842D03*
Y1360099D03*
X517242D03*
Y1372385D03*
X513842D03*
X517242Y1384297D03*
X513842D03*
X517242Y1396583D03*
X513842D03*
X517242Y1408495D03*
X513842D03*
X533092Y114623D03*
Y111223D03*
Y128796D03*
Y125396D03*
X529482Y1348187D03*
X526082D03*
X538322D03*
Y1360099D03*
X529482D03*
X526082D03*
X529482Y1372385D03*
X538322Y1384297D03*
X529482D03*
X538322Y1372385D03*
X526082D03*
Y1384297D03*
Y1396583D03*
X538322D03*
X529482D03*
Y1408495D03*
X526082D03*
X538322D03*
X543494Y121735D03*
Y132509D03*
Y118335D03*
Y135909D03*
X549168Y781600D03*
X545768D03*
X553962Y1348187D03*
X541722D03*
X550562D03*
X553962Y1360099D03*
X550562D03*
X541722D03*
Y1372385D03*
X550562D03*
X541722Y1384297D03*
X553962D03*
X550562D03*
X553962Y1372385D03*
Y1396583D03*
X541722D03*
X550562D03*
X553962Y1408495D03*
X550562D03*
X541722D03*
X562802Y1348187D03*
X566202D03*
Y1360099D03*
X562802D03*
X566202Y1372385D03*
Y1384297D03*
X562802D03*
Y1372385D03*
X566202Y1396583D03*
X562802D03*
X566202Y1408495D03*
X562802D03*
X587837Y118342D03*
Y121742D03*
Y132515D03*
Y135915D03*
X595137Y111255D03*
Y114655D03*
Y125428D03*
Y128828D03*
X597776Y401513D03*
Y398113D03*
X595376Y412287D03*
Y426460D03*
Y415687D03*
Y440633D03*
Y429860D03*
Y444033D03*
Y469387D03*
Y472787D03*
Y483560D03*
Y486960D03*
Y513521D03*
Y516921D03*
Y531094D03*
Y527694D03*
X605778Y391001D03*
Y405174D03*
Y394401D03*
Y408574D03*
Y422747D03*
Y419347D03*
Y433521D03*
Y436921D03*
Y479899D03*
Y490673D03*
Y476499D03*
Y494073D03*
Y520633D03*
Y524033D03*
Y534806D03*
Y538206D03*
X635454Y114623D03*
Y111223D03*
Y128796D03*
Y125396D03*
X629688Y1396583D03*
X626288D03*
Y1408495D03*
X629688D03*
X645856Y118335D03*
Y132509D03*
Y121735D03*
Y135909D03*
X650768Y1348187D03*
Y1360099D03*
Y1384297D03*
Y1372385D03*
X638528D03*
X641928D03*
X638528Y1384297D03*
X641928D03*
Y1396583D03*
X638528D03*
X650768D03*
X638528Y1408495D03*
X641928D03*
X650768D03*
X670066Y390995D03*
Y405168D03*
X662766Y398082D03*
X670066Y408568D03*
Y394395D03*
X662766Y401482D03*
X670066Y422741D03*
Y419341D03*
X662766Y415655D03*
Y426428D03*
Y412255D03*
Y440602D03*
X670066Y433515D03*
X662766Y429828D03*
X670066Y436915D03*
X662766Y444002D03*
X670066Y469381D03*
Y472781D03*
X662766Y476468D03*
Y490641D03*
X670066Y483554D03*
Y486954D03*
X662766Y479868D03*
Y494041D03*
X670066Y516915D03*
X662766Y520602D03*
Y524002D03*
X670066Y513515D03*
Y527688D03*
X662766Y534775D03*
X670066Y531088D03*
X662766Y538175D03*
X666408Y1348187D03*
X663008D03*
X654168D03*
X666408Y1360099D03*
X663008D03*
X654168D03*
Y1384297D03*
Y1372385D03*
X663008D03*
X666408D03*
X663008Y1384297D03*
X666408D03*
Y1396583D03*
X663008D03*
X654168D03*
X666408Y1408495D03*
X663008D03*
X654168D03*
X678648Y1348187D03*
X675248D03*
X678648Y1360099D03*
X675248D03*
Y1384297D03*
X678648D03*
Y1372385D03*
X675248D03*
Y1396583D03*
X678648D03*
Y1408495D03*
X675248D03*
X697499Y114655D03*
Y111255D03*
X690199Y132515D03*
X697499Y125428D03*
Y128828D03*
X690199Y121742D03*
Y118342D03*
Y135915D03*
X690888Y1348187D03*
X687488D03*
X699728D03*
X687488Y1360099D03*
X690888D03*
X699728D03*
Y1372385D03*
Y1384297D03*
X690888Y1372385D03*
X687488D03*
Y1384297D03*
X690888D03*
Y1396583D03*
X687488D03*
X699728D03*
X687488Y1408495D03*
X690888D03*
X699728D03*
X713791Y474424D03*
Y488597D03*
Y477824D03*
Y491997D03*
Y518558D03*
Y521958D03*
Y536131D03*
Y532731D03*
Y571997D03*
Y568597D03*
Y582771D03*
Y586171D03*
Y596944D03*
Y600344D03*
Y611117D03*
Y614517D03*
X715368Y1348187D03*
X711968D03*
X703128D03*
X715368Y1360099D03*
X711968D03*
X703128D03*
Y1372385D03*
Y1384297D03*
X715368Y1372385D03*
X711968D03*
X715368Y1384297D03*
X711968D03*
X715368Y1396583D03*
X711968D03*
X703128D03*
X715368Y1408495D03*
X711968D03*
X703128D03*
X721091Y470737D03*
Y467337D03*
Y484910D03*
Y481510D03*
Y514871D03*
Y511471D03*
Y525644D03*
Y529044D03*
Y561510D03*
Y564910D03*
Y579084D03*
Y575684D03*
Y593257D03*
Y604030D03*
Y589857D03*
Y607430D03*
X727608Y1348187D03*
X724208D03*
Y1360099D03*
X727608D03*
X724208Y1372385D03*
Y1384297D03*
X727608D03*
Y1372385D03*
X724208Y1396489D03*
X727608D03*
X724208Y1408401D03*
X727608D03*
X737816Y114623D03*
Y111223D03*
X748218Y118335D03*
X737816Y128796D03*
X748218Y132509D03*
Y121735D03*
X737816Y125396D03*
X748218Y135909D03*
X739848Y1348187D03*
X736448D03*
X748688D03*
X736448Y1360099D03*
X739848D03*
X748688D03*
Y1372385D03*
Y1384297D03*
X739848Y1372385D03*
X736448D03*
X739848Y1384297D03*
X736448D03*
X739848Y1396489D03*
X736448D03*
X739848Y1408401D03*
X736448D03*
X760928Y1348187D03*
X764328D03*
X752088D03*
X764328Y1360099D03*
X760928D03*
X752088D03*
Y1372385D03*
Y1384297D03*
X764328Y1372385D03*
X760928D03*
X764328Y1384297D03*
X760928D03*
X778079Y467306D03*
Y470706D03*
Y481479D03*
Y484879D03*
Y514839D03*
Y511439D03*
Y529013D03*
Y525613D03*
Y561479D03*
Y564879D03*
Y575652D03*
Y579052D03*
Y589825D03*
Y593225D03*
Y603999D03*
Y607399D03*
X776568Y1348187D03*
X773168D03*
Y1360099D03*
X776568D03*
X799861Y114655D03*
Y111255D03*
X792561Y132515D03*
Y118342D03*
X799861Y128828D03*
X792561Y121742D03*
X799861Y125428D03*
X792561Y135915D03*
X788481Y474418D03*
Y477818D03*
Y488591D03*
Y491991D03*
Y518552D03*
Y521952D03*
Y532725D03*
Y536125D03*
Y571991D03*
Y568591D03*
Y586165D03*
Y582765D03*
Y600338D03*
Y596938D03*
Y614511D03*
Y611111D03*
X840178Y114623D03*
Y111223D03*
Y128796D03*
Y125396D03*
X850580Y118335D03*
Y132509D03*
Y121735D03*
Y135909D03*
X919163Y848442D03*
Y851592D03*
X942561Y118342D03*
Y132515D03*
Y121742D03*
Y135915D03*
X942731Y324044D03*
X939331D03*
X942700Y346363D03*
X939300D03*
X945982Y886737D03*
X949861Y111255D03*
Y114655D03*
Y125428D03*
Y128828D03*
X949382Y886737D03*
X990178Y114623D03*
Y111223D03*
Y128796D03*
Y125396D03*
X1011187Y-33526D03*
Y-30126D03*
Y-43526D03*
Y-40126D03*
X1000580Y121735D03*
Y118335D03*
Y132509D03*
Y135909D03*
X1052223Y111255D03*
Y114655D03*
X1044923Y118342D03*
X1052223Y125428D03*
Y128828D03*
X1044923Y132515D03*
Y121742D03*
Y135915D03*
X1054863Y401513D03*
Y398113D03*
X1052463Y412287D03*
Y415687D03*
Y426460D03*
Y440633D03*
Y429860D03*
Y444033D03*
Y469387D03*
Y472787D03*
Y486960D03*
Y483560D03*
Y513521D03*
Y516921D03*
Y531094D03*
Y527694D03*
X1058113Y1348187D03*
X1054713D03*
X1058113Y1360099D03*
X1054713D03*
X1058113Y1372385D03*
X1054713D03*
Y1384297D03*
X1058113D03*
X1062865Y391001D03*
Y408574D03*
Y405174D03*
Y394401D03*
Y422747D03*
Y419347D03*
Y436921D03*
Y433521D03*
Y476499D03*
Y479899D03*
Y490673D03*
Y494073D03*
Y520633D03*
Y524033D03*
Y534806D03*
Y538206D03*
X1066953Y1348187D03*
X1070353D03*
X1066953Y1360099D03*
X1070353D03*
X1066953Y1384297D03*
Y1372385D03*
X1070353D03*
Y1384297D03*
Y1396583D03*
X1066953D03*
Y1408495D03*
X1070353D03*
X1081187Y-79306D03*
Y-82706D03*
Y-72706D03*
Y-69306D03*
X1092540Y111223D03*
Y114623D03*
Y128796D03*
Y125396D03*
X1091433Y1348187D03*
X1082593D03*
X1079193D03*
X1091433Y1360099D03*
X1082593D03*
X1079193D03*
Y1372385D03*
X1082593D03*
Y1384297D03*
X1079193D03*
X1091433D03*
Y1372385D03*
Y1396583D03*
X1082593D03*
X1079193D03*
X1091433Y1408495D03*
X1082593D03*
X1079193D03*
X1102942Y118335D03*
Y132509D03*
Y121735D03*
Y135909D03*
X1094833Y1348187D03*
X1107073D03*
X1103673D03*
X1094833Y1360099D03*
X1103673D03*
X1107073D03*
Y1372385D03*
X1103673D03*
X1107073Y1384297D03*
X1103673D03*
X1094833D03*
Y1372385D03*
Y1396583D03*
X1107073D03*
X1103673D03*
X1094833Y1408495D03*
X1107073D03*
X1103673D03*
X1119853Y398082D03*
Y401482D03*
Y412255D03*
Y426428D03*
Y415655D03*
Y440602D03*
Y429828D03*
Y444002D03*
Y490641D03*
Y476468D03*
Y479868D03*
Y494041D03*
Y524002D03*
Y520602D03*
Y538175D03*
Y534775D03*
X1115913Y1348187D03*
X1119313D03*
X1115913Y1360099D03*
X1119313D03*
Y1384297D03*
X1115913Y1372385D03*
X1119313D03*
X1115913Y1384297D03*
Y1396583D03*
X1119313D03*
X1115913Y1408495D03*
X1119313D03*
X1127153Y390995D03*
Y408568D03*
Y405168D03*
Y394395D03*
Y422741D03*
Y419341D03*
Y436915D03*
Y433515D03*
Y472781D03*
Y469381D03*
Y486954D03*
Y483554D03*
Y516915D03*
Y513515D03*
Y527688D03*
Y531088D03*
X1140393Y1348187D03*
X1131553D03*
X1128153D03*
X1140393Y1360099D03*
X1131553D03*
X1128153D03*
Y1384297D03*
X1131553D03*
X1128153Y1372385D03*
X1131553D03*
X1140393Y1384297D03*
Y1372385D03*
Y1396583D03*
X1131553D03*
X1128153D03*
X1140393Y1408495D03*
X1128153D03*
X1131553D03*
X1154585Y114655D03*
Y111255D03*
Y128828D03*
X1147285Y118342D03*
Y121742D03*
Y132515D03*
X1154585Y125428D03*
X1147285Y135915D03*
X1143793Y1348187D03*
X1156033D03*
X1152633D03*
X1143793Y1360099D03*
X1152633D03*
X1156033D03*
Y1384297D03*
X1152633D03*
X1156033Y1372385D03*
X1152633D03*
X1143793D03*
Y1384297D03*
Y1396583D03*
X1156033D03*
X1152633D03*
X1143793Y1408495D03*
X1152633D03*
X1156033D03*
X1170878Y474424D03*
Y477824D03*
Y488597D03*
Y491997D03*
Y518558D03*
Y521958D03*
Y532731D03*
Y536131D03*
Y571997D03*
Y568597D03*
Y586171D03*
Y582771D03*
Y596944D03*
Y600344D03*
Y614517D03*
Y611117D03*
X1168273Y1348187D03*
X1164873D03*
Y1360099D03*
X1168273D03*
Y1384297D03*
X1164873D03*
X1168273Y1372385D03*
X1164873D03*
Y1396583D03*
X1168273D03*
Y1408495D03*
X1164873D03*
X1178178Y467337D03*
Y470737D03*
Y484910D03*
Y481510D03*
Y511471D03*
Y514871D03*
Y529044D03*
Y525644D03*
Y564910D03*
Y561510D03*
Y579084D03*
Y575684D03*
Y604030D03*
Y593257D03*
Y589857D03*
Y607430D03*
X1177113Y1348187D03*
X1180513D03*
X1177113Y1360099D03*
X1180513D03*
X1177113Y1384297D03*
X1180513D03*
X1177113Y1372385D03*
X1180513D03*
Y1396583D03*
X1177113D03*
Y1408495D03*
X1180513D03*
X1194902Y114623D03*
Y111223D03*
X1205304Y118335D03*
Y121735D03*
X1194902Y128796D03*
X1205304Y132509D03*
X1194902Y125396D03*
X1205304Y135909D03*
X1225405Y-79278D03*
Y-82678D03*
Y-72678D03*
Y-69278D03*
X1230761Y-33628D03*
Y-30228D03*
Y-43628D03*
Y-40228D03*
X1235166Y470706D03*
Y467306D03*
Y484879D03*
Y481479D03*
Y514839D03*
Y511439D03*
Y529013D03*
Y525613D03*
Y564879D03*
Y561479D03*
Y575652D03*
Y579052D03*
Y593225D03*
Y603999D03*
Y589825D03*
Y607399D03*
X1230326Y1348187D03*
X1233726D03*
X1230326Y1360099D03*
X1233726D03*
X1230326Y1372385D03*
X1233726D03*
X1230326Y1384297D03*
X1233726D03*
X1249647Y118342D03*
Y132515D03*
Y121742D03*
Y135915D03*
X1245568Y474418D03*
Y488591D03*
Y477818D03*
Y491991D03*
Y521952D03*
Y518552D03*
Y536125D03*
Y532725D03*
Y568591D03*
Y571991D03*
Y582765D03*
Y586165D03*
Y596938D03*
Y600338D03*
Y611111D03*
Y614511D03*
X1245966Y1348187D03*
X1242566D03*
X1254806D03*
Y1360099D03*
X1242566D03*
X1245966D03*
X1254806Y1372385D03*
X1242566D03*
X1245966D03*
X1242566Y1384297D03*
X1245966D03*
X1254806D03*
X1245966Y1396583D03*
X1254806D03*
X1242566D03*
X1254806Y1408495D03*
X1242566D03*
X1245966D03*
X1256947Y114655D03*
Y111255D03*
Y128828D03*
Y125428D03*
X1267046Y1348187D03*
X1270446D03*
X1258206D03*
Y1360099D03*
X1270446D03*
X1267046D03*
X1258206Y1372385D03*
X1270446D03*
X1267046D03*
X1270446Y1384297D03*
X1267046D03*
X1258206D03*
X1267046Y1396583D03*
X1270446D03*
X1258206D03*
Y1408495D03*
X1270446D03*
X1267046D03*
X1282686Y1348187D03*
X1279286D03*
Y1360099D03*
X1282686D03*
X1279286Y1372385D03*
X1282686D03*
Y1384297D03*
X1279286D03*
Y1396583D03*
X1282686D03*
X1279286Y1408495D03*
X1282686D03*
X1297687Y-33656D03*
Y-30256D03*
X1297264Y114623D03*
Y111223D03*
Y128796D03*
Y125396D03*
X1291526Y1348187D03*
X1294926D03*
X1291526Y1360099D03*
X1294926D03*
X1291526Y1372385D03*
X1294926D03*
X1291526Y1384297D03*
X1294926D03*
Y1396583D03*
X1291526D03*
Y1408495D03*
X1294926D03*
X1307666Y118335D03*
Y132509D03*
Y121735D03*
Y135909D03*
X1319406Y1348187D03*
X1316006D03*
X1307166D03*
X1303766D03*
X1319406Y1360099D03*
X1316006D03*
X1307166D03*
X1303766D03*
X1316006Y1372385D03*
X1307166D03*
X1303766D03*
Y1384297D03*
X1307166D03*
X1319406Y1372385D03*
X1316006Y1384297D03*
X1319406D03*
Y1396583D03*
X1316006D03*
X1303766D03*
X1307166D03*
X1316006Y1408495D03*
X1319406D03*
X1307166D03*
X1303766D03*
X1328246Y1348187D03*
X1331646D03*
X1328246Y1360099D03*
X1331646D03*
Y1384297D03*
Y1372385D03*
X1328246D03*
Y1384297D03*
X1331646Y1396583D03*
X1328246D03*
X1331646Y1408495D03*
X1328246D03*
X1337687Y-69306D03*
Y-72706D03*
X1343886Y1348187D03*
X1340486D03*
X1343886Y1360099D03*
X1340486D03*
X1343886Y1372385D03*
X1340486D03*
Y1384297D03*
X1343886D03*
X1340486Y1396583D03*
X1343886D03*
Y1408495D03*
X1340486D03*
X1356126Y1348187D03*
X1352726D03*
X1356126Y1360099D03*
X1352726D03*
Y1384297D03*
X1356126Y1372385D03*
Y1384297D03*
X1352726Y1372385D03*
X1356126Y1396583D03*
X1352726D03*
Y1408495D03*
X1356126D03*
X1399648Y132515D03*
Y121742D03*
Y118342D03*
Y135915D03*
X1406948Y111255D03*
Y114655D03*
Y128828D03*
Y125428D03*
X1447265Y111223D03*
Y114623D03*
Y125396D03*
Y128796D03*
X1457667Y118335D03*
Y121735D03*
Y132509D03*
Y135909D03*
X1464770Y1348187D03*
X1461370D03*
X1464770Y1360099D03*
X1461370D03*
X1464770Y1372385D03*
X1461370D03*
X1464770Y1384297D03*
X1461370D03*
X1481905Y-69278D03*
Y-72678D03*
X1477010Y1348187D03*
X1473610D03*
Y1360099D03*
X1477010D03*
X1473610Y1372385D03*
X1477010D03*
X1473610Y1384297D03*
X1477010D03*
Y1396583D03*
X1473610D03*
Y1408495D03*
X1477010D03*
X1489250Y1348187D03*
X1485850D03*
X1498090D03*
Y1360099D03*
X1485850D03*
X1489250D03*
Y1372385D03*
X1485850D03*
X1498090D03*
X1485850Y1384297D03*
X1498090D03*
X1489250D03*
X1498090Y1396583D03*
X1485850D03*
X1489250D03*
X1498090Y1408495D03*
X1489250D03*
X1485850D03*
X1509310Y114655D03*
Y111255D03*
X1502010Y121742D03*
X1509310Y125428D03*
Y128828D03*
X1502010Y118342D03*
Y132515D03*
Y135915D03*
X1511950Y401513D03*
Y398113D03*
X1509550Y412287D03*
Y415687D03*
Y426460D03*
Y440633D03*
Y429860D03*
Y444033D03*
Y472787D03*
Y469387D03*
Y483560D03*
Y486960D03*
Y516921D03*
Y513521D03*
Y527694D03*
Y531094D03*
X1513730Y1348187D03*
X1510330D03*
X1501490D03*
X1510330Y1360099D03*
X1501490D03*
X1513730D03*
X1510330Y1372385D03*
X1513730D03*
X1501490D03*
Y1384297D03*
X1513730D03*
X1510330D03*
Y1396583D03*
X1513730D03*
X1501490D03*
X1510330Y1408495D03*
X1513730D03*
X1501490D03*
X1517261Y-33758D03*
Y-30358D03*
X1519952Y391001D03*
Y394401D03*
Y408574D03*
Y405174D03*
Y422747D03*
Y419347D03*
Y436921D03*
Y433521D03*
Y479899D03*
Y476499D03*
Y490673D03*
Y494073D03*
Y520633D03*
Y524033D03*
Y534806D03*
Y538206D03*
X1525970Y1348187D03*
X1522570D03*
Y1360099D03*
X1525970D03*
Y1372385D03*
X1522570D03*
X1525970Y1384297D03*
X1522570D03*
Y1396583D03*
X1525970D03*
Y1408495D03*
X1522570D03*
X1538210Y1348187D03*
X1547050D03*
X1534810D03*
X1538210Y1360099D03*
X1534810D03*
X1547050D03*
X1538210Y1372385D03*
X1534810D03*
X1547050D03*
Y1384297D03*
X1534810D03*
X1538210D03*
Y1396583D03*
X1534810D03*
X1547050D03*
X1538210Y1408495D03*
X1534810D03*
X1547050D03*
X1549627Y111223D03*
Y114623D03*
Y128796D03*
X1560029Y132509D03*
Y121735D03*
Y118335D03*
X1549627Y125396D03*
X1560029Y135909D03*
X1550450Y1348187D03*
X1559290D03*
X1562690D03*
X1559290Y1360099D03*
X1562690D03*
X1550450D03*
X1562690Y1372385D03*
X1559290D03*
X1550450D03*
X1562690Y1384297D03*
X1559290D03*
X1550450D03*
Y1396583D03*
X1562690D03*
X1559290D03*
Y1408495D03*
X1562690D03*
X1550450D03*
X1576940Y398082D03*
Y401482D03*
Y415655D03*
Y412255D03*
Y426428D03*
Y440602D03*
Y429828D03*
Y444002D03*
Y476468D03*
Y490641D03*
Y479868D03*
Y494041D03*
Y520602D03*
Y524002D03*
Y534775D03*
Y538175D03*
X1574930Y1348187D03*
X1571530D03*
X1574930Y1360099D03*
X1571530D03*
X1574930Y1372385D03*
X1571530D03*
Y1384297D03*
X1574930D03*
X1571530Y1396583D03*
X1574930D03*
X1571530Y1408495D03*
X1574930D03*
X1592187Y-69306D03*
Y-72706D03*
X1582187Y-33786D03*
Y-30386D03*
X1584240Y390995D03*
Y408568D03*
Y405168D03*
Y394395D03*
Y419341D03*
Y422741D03*
Y433515D03*
Y436915D03*
Y472781D03*
Y469381D03*
Y483554D03*
Y486954D03*
Y516915D03*
Y513515D03*
Y531088D03*
Y527688D03*
X1587170Y1348187D03*
X1583770D03*
X1587170Y1360099D03*
X1583770D03*
X1587170Y1372385D03*
X1583770D03*
Y1384297D03*
X1587170D03*
X1583770Y1396583D03*
X1587170D03*
X1583770Y1408495D03*
X1587170D03*
X1611672Y111255D03*
Y114655D03*
X1604372Y118342D03*
X1611672Y125428D03*
X1604372Y121742D03*
X1611672Y128828D03*
X1604372Y132515D03*
Y135915D03*
X1611398Y1348187D03*
Y1360099D03*
Y1384297D03*
Y1372385D03*
X1627965Y474424D03*
Y488597D03*
Y477824D03*
Y491997D03*
Y521958D03*
Y518558D03*
Y536131D03*
Y532731D03*
Y571997D03*
Y568597D03*
Y582771D03*
Y586171D03*
Y596944D03*
Y600344D03*
Y614517D03*
Y611117D03*
X1614798Y1348187D03*
X1623638D03*
X1627038D03*
X1614798Y1360099D03*
X1623638D03*
X1627038D03*
Y1372385D03*
X1623638D03*
X1627038Y1384297D03*
X1623638D03*
X1614798Y1372385D03*
Y1384297D03*
X1627038Y1396583D03*
X1623638D03*
X1627038Y1408495D03*
X1623638D03*
X1635265Y470737D03*
Y467337D03*
Y484910D03*
Y481510D03*
Y514871D03*
Y511471D03*
Y529044D03*
Y525644D03*
Y564910D03*
Y561510D03*
Y575684D03*
Y579084D03*
Y593257D03*
Y604030D03*
Y589857D03*
Y607430D03*
X1639278Y1348187D03*
X1635878D03*
X1639278Y1360099D03*
X1635878D03*
Y1384297D03*
X1639278D03*
Y1372385D03*
X1635878D03*
X1639278Y1396583D03*
X1635878D03*
Y1408495D03*
X1639278D03*
X1651989Y114623D03*
Y111223D03*
Y125396D03*
Y128796D03*
X1660358Y1348187D03*
X1651518D03*
X1648118D03*
X1660358Y1360099D03*
X1651518D03*
X1648118D03*
Y1372385D03*
X1651518D03*
X1648118Y1384297D03*
X1651518D03*
X1660358D03*
Y1372385D03*
Y1396583D03*
X1651518D03*
X1648118D03*
X1660358Y1408495D03*
X1648118D03*
X1651518D03*
X1662391Y118335D03*
Y121735D03*
Y132509D03*
Y135909D03*
X1663758Y1348187D03*
X1672598D03*
X1675998D03*
X1663758Y1360099D03*
X1675998D03*
X1672598D03*
X1675998Y1372385D03*
X1672598D03*
Y1384297D03*
X1675998D03*
X1663758D03*
Y1372385D03*
Y1396583D03*
X1675998D03*
X1672598D03*
X1663758Y1408495D03*
X1675998D03*
X1672598D03*
X1692253Y467306D03*
Y470706D03*
Y484879D03*
Y481479D03*
Y511439D03*
Y514839D03*
Y529013D03*
Y525613D03*
Y561479D03*
Y564879D03*
Y575652D03*
Y579052D03*
Y593225D03*
Y603999D03*
Y589825D03*
Y607399D03*
X1688238Y1348187D03*
X1684838D03*
X1688238Y1360099D03*
X1684838D03*
Y1384297D03*
X1688238D03*
X1684838Y1372385D03*
X1688238D03*
X1684838Y1396583D03*
X1688238D03*
Y1408495D03*
X1684838D03*
X1706734Y118342D03*
Y132515D03*
Y121742D03*
Y135915D03*
X1702655Y474418D03*
Y477818D03*
Y488591D03*
Y491991D03*
Y521952D03*
Y518552D03*
Y536125D03*
Y532725D03*
Y571991D03*
Y568591D03*
Y586165D03*
Y582765D03*
Y600338D03*
Y596938D03*
Y611111D03*
Y614511D03*
X1709318Y1348187D03*
X1700478D03*
X1697078D03*
X1709318Y1360099D03*
X1697078D03*
X1700478D03*
X1697078Y1372385D03*
X1700478D03*
X1697078Y1384297D03*
X1700478D03*
X1709318D03*
Y1372385D03*
Y1396583D03*
X1700478D03*
X1697078D03*
X1709318Y1408495D03*
X1697078D03*
X1700478D03*
X1714034Y111255D03*
Y114655D03*
Y125428D03*
Y128828D03*
X1712718Y1348187D03*
X1721558D03*
X1724958D03*
X1712718Y1360099D03*
X1724958D03*
X1721558D03*
Y1372385D03*
X1724958D03*
Y1384297D03*
X1721558D03*
X1712718Y1372385D03*
Y1384297D03*
Y1396583D03*
X1721558D03*
X1724958D03*
X1712718Y1408495D03*
X1721558D03*
X1724958D03*
X1736405Y-69278D03*
Y-72678D03*
X1733798Y1348187D03*
X1737198D03*
X1733798Y1360099D03*
X1737198D03*
Y1384297D03*
X1733798D03*
Y1372385D03*
X1737198D03*
Y1396583D03*
X1733798D03*
X1737198Y1408495D03*
X1733798D03*
X1754351Y111223D03*
Y114623D03*
Y128796D03*
Y125396D03*
X1764753Y121735D03*
Y118335D03*
Y132509D03*
Y135909D03*
X1801761Y-33888D03*
Y-30488D03*
G54D11*
X13780Y1226024D03*
X79331Y1186654D03*
X390354Y1141024D03*
X536418Y1086654D03*
X854291Y1225118D03*
X993504Y1170748D03*
X1304528Y1141024D03*
X1450591Y1086654D03*
X1761614Y1215000D03*
X1827165Y1235630D03*
G54D44*
X661674Y23622D03*
G54D19*
X23622Y1604724D03*
X62205Y765197D03*
X74016Y333464D03*
X102224Y70866D03*
X409488Y1604724D03*
X433130Y70866D03*
X463387Y286221D03*
X463386Y765197D03*
X785039Y1547638D03*
X890217Y23622D03*
X920473Y765196D03*
X1055905Y1547637D03*
X1118760Y23622D03*
X1347303Y70866D03*
X1377559Y286220D03*
Y765197D03*
X1431457Y1604724D03*
X1575846Y23622D03*
X1766929Y333464D03*
X1778740Y765197D03*
X1795010Y23622D03*
X1817323Y1604724D03*
G54D20*
X28819Y81575D03*
X73307Y61614D03*
X131181Y81575D03*
X175669Y61614D03*
X233543Y81575D03*
X278032Y61614D03*
X335906Y81575D03*
X380394Y61614D03*
X485886Y81595D03*
X530394Y61614D03*
X588248Y81594D03*
X632756Y61614D03*
X690611Y81595D03*
X735118Y61614D03*
X792973Y81595D03*
X837480Y61614D03*
X942973Y81595D03*
X987480Y61614D03*
X1045335Y81595D03*
X1089843Y61614D03*
X1147697Y81595D03*
X1192205Y61614D03*
X1250060Y81595D03*
X1294567Y61614D03*
X1400060Y81595D03*
X1444567Y61614D03*
X1502441Y81575D03*
X1546929Y61614D03*
X1604784Y81595D03*
X1649291Y61614D03*
X1707146Y81595D03*
X1751654Y61614D03*
G54D32*
X109882Y1458622D03*
Y1463741D03*
Y1473977D03*
Y1479095D03*
Y1504685D03*
Y1509804D03*
Y1560985D03*
Y1566103D03*
Y1576339D03*
Y1581457D03*
Y1607048D03*
Y1612166D03*
X127205Y1458622D03*
Y1463741D03*
X118543Y1462953D03*
X127205Y1473977D03*
Y1479095D03*
X118543Y1468071D03*
Y1478308D03*
Y1483426D03*
X127205Y1504685D03*
Y1509804D03*
X118543Y1509016D03*
Y1514134D03*
X127205Y1560985D03*
Y1566103D03*
Y1576339D03*
X118543Y1565315D03*
Y1570434D03*
X127205Y1581457D03*
X118543Y1580670D03*
Y1585788D03*
X127205Y1607048D03*
Y1612166D03*
X118543Y1611378D03*
Y1616496D03*
X144528Y1458622D03*
Y1463741D03*
X135866Y1462953D03*
X144528Y1473977D03*
Y1479095D03*
X135866Y1468071D03*
Y1478308D03*
Y1483426D03*
X144528Y1504685D03*
Y1509804D03*
X135866Y1509016D03*
Y1514134D03*
X144528Y1560985D03*
Y1566103D03*
Y1576339D03*
X135866Y1565315D03*
Y1570434D03*
X144528Y1581457D03*
X135866Y1580670D03*
Y1585788D03*
X144528Y1607048D03*
Y1612166D03*
X135866Y1611378D03*
Y1616496D03*
X161850Y1458622D03*
Y1463741D03*
X153189Y1462953D03*
X161850Y1473977D03*
Y1479095D03*
X153189Y1468071D03*
Y1478308D03*
Y1483426D03*
X161850Y1504685D03*
Y1509804D03*
X153189Y1509016D03*
Y1514134D03*
X161850Y1560985D03*
Y1566103D03*
Y1576339D03*
X153189Y1565315D03*
Y1570434D03*
X161850Y1581457D03*
X153189Y1580670D03*
Y1585788D03*
X161850Y1607048D03*
Y1612166D03*
X153189Y1611378D03*
Y1616496D03*
X170512Y1462953D03*
X179173Y1473977D03*
Y1479095D03*
X170512Y1468071D03*
Y1478308D03*
Y1483426D03*
Y1509016D03*
Y1514134D03*
Y1565315D03*
Y1570434D03*
Y1580670D03*
Y1585788D03*
Y1611378D03*
Y1616496D03*
X187835Y1478308D03*
Y1483426D03*
Y1596024D03*
Y1601142D03*
Y1611378D03*
Y1616496D03*
X283110Y1458622D03*
X291771Y1462953D03*
X283110Y1463741D03*
X291771Y1468071D03*
X283110Y1473977D03*
X291771Y1478308D03*
X283110Y1479095D03*
X291771Y1483426D03*
X283110Y1489331D03*
X291771Y1493662D03*
X283110Y1494449D03*
X291771Y1498780D03*
X283110Y1504685D03*
X291771Y1509016D03*
X283110Y1509804D03*
X291771Y1514134D03*
X283110Y1560985D03*
X291771Y1565315D03*
X283110Y1566103D03*
X291771Y1570434D03*
X283110Y1576339D03*
X291771Y1580670D03*
X283110Y1581457D03*
X291771Y1585788D03*
X283110Y1591693D03*
X291771Y1596024D03*
X283110Y1596811D03*
X291771Y1601142D03*
X283110Y1607048D03*
X291771Y1611378D03*
X283110Y1612166D03*
X291771Y1616496D03*
X300433Y1458622D03*
X309094Y1462953D03*
X300433Y1463741D03*
X309094Y1468071D03*
X300433Y1473977D03*
X309094Y1478308D03*
X300433Y1479095D03*
X309094Y1483426D03*
X300433Y1489331D03*
X309094Y1493662D03*
X300433Y1494449D03*
X309094Y1498780D03*
X300433Y1504685D03*
X309094Y1509016D03*
X300433Y1509804D03*
X309094Y1514134D03*
X300433Y1560985D03*
X309094Y1565315D03*
X300433Y1566103D03*
X309094Y1570434D03*
X300433Y1576339D03*
X309094Y1580670D03*
X300433Y1581457D03*
X309094Y1585788D03*
X300433Y1591693D03*
X309094Y1596024D03*
X300433Y1596811D03*
X309094Y1601142D03*
X300433Y1607048D03*
X309094Y1611378D03*
X300433Y1612166D03*
X309094Y1616496D03*
X317756Y1458622D03*
X326417Y1462953D03*
X317756Y1463741D03*
X326417Y1468071D03*
X317756Y1473977D03*
X326417Y1478308D03*
X317756Y1479095D03*
X326417Y1483426D03*
X317756Y1489331D03*
X326417Y1493662D03*
X317756Y1494449D03*
X326417Y1498780D03*
X317756Y1504685D03*
X326417Y1509016D03*
X317756Y1509804D03*
X326417Y1514134D03*
X317756Y1560985D03*
X326417Y1565315D03*
X317756Y1566103D03*
X326417Y1570434D03*
X317756Y1576339D03*
X326417Y1580670D03*
X317756Y1581457D03*
X326417Y1585788D03*
X317756Y1591693D03*
X326417Y1596024D03*
X317756Y1596811D03*
X326417Y1601142D03*
X317756Y1607048D03*
X326417Y1611378D03*
X317756Y1612166D03*
X326417Y1616496D03*
X335078Y1458622D03*
X343740Y1462953D03*
X335078Y1463741D03*
X343740Y1468071D03*
X335078Y1473977D03*
X343740Y1478308D03*
X335078Y1479095D03*
X343740Y1483426D03*
X335078Y1489331D03*
X343740Y1493662D03*
X335078Y1494449D03*
X343740Y1498780D03*
X335078Y1504685D03*
X343740Y1509016D03*
X335078Y1509804D03*
X343740Y1514134D03*
X335078Y1560985D03*
X343740Y1565315D03*
X335078Y1566103D03*
X343740Y1570434D03*
X335078Y1576339D03*
X343740Y1580670D03*
X335078Y1581457D03*
X343740Y1585788D03*
X335078Y1591693D03*
X343740Y1596024D03*
X335078Y1596811D03*
X343740Y1601142D03*
X335078Y1607048D03*
X343740Y1611378D03*
X335078Y1612166D03*
X343740Y1616496D03*
X361063Y1596024D03*
Y1601142D03*
Y1611378D03*
Y1616496D03*
X456339Y1473977D03*
Y1479095D03*
Y1489331D03*
Y1494449D03*
Y1504685D03*
Y1509804D03*
Y1560985D03*
Y1566103D03*
Y1591693D03*
Y1596811D03*
Y1607048D03*
Y1612166D03*
X473662Y1473977D03*
Y1479095D03*
X465000Y1478308D03*
X473662Y1489331D03*
Y1494449D03*
X465000Y1483426D03*
Y1493662D03*
Y1498780D03*
X473662Y1504685D03*
Y1509804D03*
X465000Y1509016D03*
Y1514134D03*
X473662Y1560985D03*
Y1566103D03*
X465000Y1565315D03*
Y1570434D03*
X473662Y1591693D03*
X465000Y1596024D03*
X473662Y1596811D03*
Y1607048D03*
Y1612166D03*
X465000Y1601142D03*
Y1611378D03*
Y1616496D03*
X490985Y1473977D03*
Y1479095D03*
X482323Y1478308D03*
X490985Y1489331D03*
Y1494449D03*
X482323Y1483426D03*
Y1493662D03*
Y1498780D03*
X490985Y1504685D03*
Y1509804D03*
X482323Y1509016D03*
Y1514134D03*
X490985Y1560985D03*
Y1566103D03*
X482323Y1565315D03*
Y1570434D03*
X490985Y1591693D03*
X482323Y1596024D03*
X490985Y1596811D03*
Y1607048D03*
Y1612166D03*
X482323Y1601142D03*
Y1611378D03*
Y1616496D03*
X499646Y1478308D03*
Y1483426D03*
Y1493662D03*
Y1498780D03*
Y1509016D03*
Y1514134D03*
Y1565315D03*
Y1570434D03*
Y1596024D03*
Y1601142D03*
Y1611378D03*
Y1616496D03*
X508307Y1473977D03*
X516969Y1478308D03*
X508307Y1479095D03*
X516969Y1483426D03*
X508307Y1489331D03*
X516969Y1493662D03*
X508307Y1494449D03*
X516969Y1498780D03*
X508307Y1504685D03*
X516969Y1509016D03*
X508307Y1509804D03*
X516969Y1514134D03*
X508307Y1560985D03*
X516969Y1565315D03*
X508307Y1566103D03*
X516969Y1570434D03*
X508307Y1591693D03*
X516969Y1596024D03*
X508307Y1596811D03*
X516969Y1601142D03*
X508307Y1607048D03*
X516969Y1611378D03*
X508307Y1612166D03*
X516969Y1616496D03*
X629567Y1458622D03*
Y1463741D03*
Y1473977D03*
Y1479095D03*
Y1489331D03*
Y1494449D03*
Y1504685D03*
Y1509804D03*
Y1560985D03*
Y1566103D03*
Y1576339D03*
Y1581457D03*
Y1591693D03*
Y1596811D03*
Y1607048D03*
Y1612166D03*
X646890Y1458622D03*
Y1463741D03*
X638228Y1462953D03*
X646890Y1473977D03*
Y1479095D03*
X638228Y1468071D03*
Y1478308D03*
X646890Y1489331D03*
Y1494449D03*
X638228Y1483426D03*
Y1493662D03*
Y1498780D03*
X646890Y1504685D03*
Y1509804D03*
X638228Y1509016D03*
Y1514134D03*
X646890Y1560985D03*
Y1566103D03*
Y1576339D03*
X638228Y1565315D03*
Y1570434D03*
X646890Y1581457D03*
Y1591693D03*
X638228Y1580670D03*
Y1585788D03*
Y1596024D03*
X646890Y1596811D03*
Y1607048D03*
Y1612166D03*
X638228Y1601142D03*
Y1611378D03*
Y1616496D03*
X664213Y1458622D03*
Y1463741D03*
X655551Y1462953D03*
X664213Y1473977D03*
Y1479095D03*
X655551Y1468071D03*
Y1478308D03*
X664213Y1489331D03*
Y1494449D03*
X655551Y1483426D03*
Y1493662D03*
Y1498780D03*
X664213Y1504685D03*
Y1509804D03*
X655551Y1509016D03*
Y1514134D03*
X664213Y1560985D03*
Y1566103D03*
Y1576339D03*
X655551Y1565315D03*
Y1570434D03*
X664213Y1581457D03*
Y1591693D03*
X655551Y1580670D03*
Y1585788D03*
Y1596024D03*
X664213Y1596811D03*
Y1607048D03*
Y1612166D03*
X655551Y1601142D03*
Y1611378D03*
Y1616496D03*
X681535Y1458622D03*
Y1463741D03*
X672874Y1462953D03*
X681535Y1473977D03*
Y1479095D03*
X672874Y1468071D03*
Y1478308D03*
X681535Y1489331D03*
Y1494449D03*
X672874Y1483426D03*
Y1493662D03*
Y1498780D03*
X681535Y1504685D03*
Y1509804D03*
X672874Y1509016D03*
Y1514134D03*
X681535Y1560985D03*
Y1566103D03*
Y1576339D03*
X672874Y1565315D03*
Y1570434D03*
X681535Y1581457D03*
Y1591693D03*
X672874Y1580670D03*
Y1585788D03*
Y1596024D03*
X681535Y1596811D03*
Y1607048D03*
Y1612166D03*
X672874Y1601142D03*
Y1611378D03*
Y1616496D03*
X690197Y1462953D03*
Y1468071D03*
Y1478308D03*
Y1483426D03*
Y1493662D03*
Y1498780D03*
Y1509016D03*
Y1514134D03*
Y1565315D03*
Y1570434D03*
Y1580670D03*
Y1585788D03*
Y1596024D03*
Y1601142D03*
Y1611378D03*
Y1616496D03*
X1131850Y1458622D03*
X1140511Y1462953D03*
X1131850Y1463741D03*
X1140511Y1468071D03*
X1131850Y1473977D03*
X1140511Y1478308D03*
X1131850Y1479095D03*
X1140511Y1483426D03*
X1131850Y1504685D03*
X1140511Y1509016D03*
X1131850Y1509804D03*
X1140511Y1514134D03*
X1131850Y1560985D03*
X1140511Y1565315D03*
X1131850Y1566103D03*
X1140511Y1570434D03*
X1131850Y1576339D03*
X1140511Y1580670D03*
X1131850Y1581457D03*
X1140511Y1585788D03*
X1131850Y1607048D03*
X1140511Y1611378D03*
X1131850Y1612166D03*
X1140511Y1616496D03*
X1149173Y1458622D03*
Y1463741D03*
Y1473977D03*
Y1479095D03*
Y1504685D03*
Y1509804D03*
Y1560985D03*
Y1566103D03*
Y1576339D03*
Y1581457D03*
Y1607048D03*
Y1612166D03*
X1166496Y1458622D03*
Y1463741D03*
X1157834Y1462953D03*
X1166496Y1473977D03*
Y1479095D03*
X1157834Y1468071D03*
Y1478308D03*
Y1483426D03*
X1166496Y1504685D03*
Y1509804D03*
X1157834Y1509016D03*
Y1514134D03*
X1166496Y1560985D03*
Y1566103D03*
Y1576339D03*
X1157834Y1565315D03*
Y1570434D03*
X1166496Y1581457D03*
X1157834Y1580670D03*
Y1585788D03*
X1166496Y1607048D03*
Y1612166D03*
X1157834Y1611378D03*
Y1616496D03*
X1183818Y1458622D03*
Y1463741D03*
X1175157Y1462953D03*
X1183818Y1473977D03*
Y1479095D03*
X1175157Y1468071D03*
Y1478308D03*
Y1483426D03*
X1183818Y1504685D03*
Y1509804D03*
X1175157Y1509016D03*
Y1514134D03*
X1183818Y1560985D03*
Y1566103D03*
Y1576339D03*
X1175157Y1565315D03*
Y1570434D03*
X1183818Y1581457D03*
X1175157Y1580670D03*
Y1585788D03*
X1183818Y1607048D03*
Y1612166D03*
X1175157Y1611378D03*
Y1616496D03*
X1192480Y1462953D03*
Y1468071D03*
Y1478308D03*
Y1483426D03*
Y1509016D03*
Y1514134D03*
Y1565315D03*
Y1570434D03*
Y1580670D03*
Y1585788D03*
Y1611378D03*
Y1616496D03*
X1305079Y1458622D03*
X1313740Y1462953D03*
X1305079Y1463741D03*
X1313740Y1468071D03*
X1305079Y1473977D03*
X1313740Y1478308D03*
X1305079Y1479095D03*
X1313740Y1483426D03*
X1305079Y1489331D03*
X1313740Y1493662D03*
X1305079Y1494449D03*
X1313740Y1498780D03*
X1305079Y1504685D03*
X1313740Y1509016D03*
X1305079Y1509804D03*
X1313740Y1514134D03*
X1305079Y1560985D03*
X1313740Y1565315D03*
X1305079Y1566103D03*
X1313740Y1570434D03*
X1305079Y1576339D03*
X1313740Y1580670D03*
X1305079Y1581457D03*
X1313740Y1585788D03*
X1305079Y1591693D03*
X1313740Y1596024D03*
X1305079Y1596811D03*
X1313740Y1601142D03*
X1305079Y1607048D03*
X1313740Y1611378D03*
X1305079Y1612166D03*
X1313740Y1616496D03*
X1322402Y1458622D03*
X1331063Y1462953D03*
X1322402Y1463741D03*
X1331063Y1468071D03*
X1322402Y1473977D03*
X1331063Y1478308D03*
X1322402Y1479095D03*
X1331063Y1483426D03*
X1322402Y1489331D03*
X1331063Y1493662D03*
X1322402Y1494449D03*
X1331063Y1498780D03*
X1322402Y1504685D03*
X1331063Y1509016D03*
X1322402Y1509804D03*
X1331063Y1514134D03*
X1322402Y1560985D03*
X1331063Y1565315D03*
X1322402Y1566103D03*
X1331063Y1570434D03*
X1322402Y1576339D03*
X1331063Y1580670D03*
X1322402Y1581457D03*
X1331063Y1585788D03*
X1322402Y1591693D03*
X1331063Y1596024D03*
X1322402Y1596811D03*
X1331063Y1601142D03*
X1322402Y1607048D03*
X1331063Y1611378D03*
X1322402Y1612166D03*
X1331063Y1616496D03*
X1339725Y1458622D03*
X1348386Y1462953D03*
X1339725Y1463741D03*
X1348386Y1468071D03*
X1339725Y1473977D03*
X1348386Y1478308D03*
X1339725Y1479095D03*
X1348386Y1483426D03*
X1339725Y1489331D03*
X1348386Y1493662D03*
X1339725Y1494449D03*
X1348386Y1498780D03*
X1339725Y1504685D03*
X1348386Y1509016D03*
X1339725Y1509804D03*
X1348386Y1514134D03*
X1339725Y1560985D03*
X1348386Y1565315D03*
X1339725Y1566103D03*
X1348386Y1570434D03*
X1339725Y1576339D03*
X1348386Y1580670D03*
X1339725Y1581457D03*
X1348386Y1585788D03*
X1339725Y1591693D03*
X1348386Y1596024D03*
X1339725Y1596811D03*
X1348386Y1601142D03*
X1339725Y1607048D03*
X1348386Y1611378D03*
X1339725Y1612166D03*
X1348386Y1616496D03*
X1357047Y1458622D03*
X1365709Y1462953D03*
X1357047Y1463741D03*
X1365709Y1468071D03*
X1357047Y1473977D03*
X1365709Y1478308D03*
X1357047Y1479095D03*
X1365709Y1483426D03*
X1357047Y1489331D03*
X1365709Y1493662D03*
X1357047Y1494449D03*
X1365709Y1498780D03*
X1357047Y1504685D03*
X1365709Y1509016D03*
X1357047Y1509804D03*
X1365709Y1514134D03*
X1357047Y1560985D03*
X1365709Y1565315D03*
X1357047Y1566103D03*
X1365709Y1570434D03*
X1357047Y1576339D03*
X1365709Y1580670D03*
X1357047Y1581457D03*
X1365709Y1585788D03*
X1357047Y1591693D03*
X1365709Y1596024D03*
X1357047Y1596811D03*
X1365709Y1601142D03*
X1357047Y1607048D03*
X1365709Y1611378D03*
X1357047Y1612166D03*
X1365709Y1616496D03*
X1478307Y1473977D03*
Y1479095D03*
Y1489331D03*
Y1494449D03*
Y1504685D03*
Y1509804D03*
Y1560985D03*
Y1566103D03*
Y1591693D03*
Y1596811D03*
Y1607048D03*
Y1612166D03*
X1495630Y1473977D03*
Y1479095D03*
X1486968Y1478308D03*
X1495630Y1489331D03*
Y1494449D03*
X1486968Y1483426D03*
Y1493662D03*
Y1498780D03*
X1495630Y1504685D03*
Y1509804D03*
X1486968Y1509016D03*
Y1514134D03*
X1495630Y1560985D03*
Y1566103D03*
X1486968Y1565315D03*
Y1570434D03*
X1495630Y1591693D03*
X1486968Y1596024D03*
X1495630Y1596811D03*
Y1607048D03*
Y1612166D03*
X1486968Y1601142D03*
Y1611378D03*
Y1616496D03*
X1512953Y1473977D03*
Y1479095D03*
X1504291Y1478308D03*
X1512953Y1489331D03*
Y1494449D03*
X1504291Y1483426D03*
Y1493662D03*
Y1498780D03*
X1512953Y1504685D03*
Y1509804D03*
X1504291Y1509016D03*
Y1514134D03*
X1512953Y1560985D03*
Y1566103D03*
X1504291Y1565315D03*
Y1570434D03*
X1512953Y1591693D03*
X1504291Y1596024D03*
X1512953Y1596811D03*
Y1607048D03*
Y1612166D03*
X1504291Y1601142D03*
Y1611378D03*
Y1616496D03*
X1530275Y1473977D03*
Y1479095D03*
X1521614Y1478308D03*
X1530275Y1489331D03*
Y1494449D03*
X1521614Y1483426D03*
Y1493662D03*
Y1498780D03*
X1530275Y1504685D03*
Y1509804D03*
X1521614Y1509016D03*
Y1514134D03*
X1530275Y1560985D03*
Y1566103D03*
X1521614Y1565315D03*
Y1570434D03*
X1530275Y1591693D03*
X1521614Y1596024D03*
X1530275Y1596811D03*
Y1607048D03*
Y1612166D03*
X1521614Y1601142D03*
Y1611378D03*
Y1616496D03*
X1538937Y1478308D03*
Y1483426D03*
Y1493662D03*
Y1498780D03*
Y1509016D03*
Y1514134D03*
Y1565315D03*
Y1570434D03*
Y1596024D03*
Y1601142D03*
Y1611378D03*
Y1616496D03*
X1651535Y1458622D03*
X1660196Y1462953D03*
X1651535Y1463741D03*
X1660196Y1468071D03*
X1651535Y1473977D03*
X1660196Y1478308D03*
X1651535Y1479095D03*
X1660196Y1483426D03*
X1651535Y1489331D03*
X1660196Y1493662D03*
X1651535Y1494449D03*
X1660196Y1498780D03*
X1651535Y1504685D03*
X1660196Y1509016D03*
X1651535Y1509804D03*
X1660196Y1514134D03*
X1651535Y1560985D03*
X1660196Y1565315D03*
X1651535Y1566103D03*
X1660196Y1570434D03*
X1651535Y1576339D03*
X1660196Y1580670D03*
X1651535Y1581457D03*
X1660196Y1585788D03*
X1651535Y1591693D03*
X1660196Y1596024D03*
X1651535Y1596811D03*
X1660196Y1601142D03*
X1651535Y1607048D03*
X1660196Y1611378D03*
X1651535Y1612166D03*
X1660196Y1616496D03*
X1668858Y1458622D03*
Y1463741D03*
Y1473977D03*
Y1479095D03*
Y1489331D03*
Y1494449D03*
Y1504685D03*
Y1509804D03*
Y1560985D03*
Y1566103D03*
Y1576339D03*
Y1581457D03*
Y1591693D03*
Y1596811D03*
Y1607048D03*
Y1612166D03*
X1686181Y1458622D03*
Y1463741D03*
X1677519Y1462953D03*
X1686181Y1473977D03*
Y1479095D03*
X1677519Y1468071D03*
Y1478308D03*
X1686181Y1489331D03*
Y1494449D03*
X1677519Y1483426D03*
Y1493662D03*
Y1498780D03*
X1686181Y1504685D03*
Y1509804D03*
X1677519Y1509016D03*
Y1514134D03*
X1686181Y1560985D03*
Y1566103D03*
Y1576339D03*
X1677519Y1565315D03*
Y1570434D03*
X1686181Y1581457D03*
Y1591693D03*
X1677519Y1580670D03*
Y1585788D03*
Y1596024D03*
X1686181Y1596811D03*
Y1607048D03*
Y1612166D03*
X1677519Y1601142D03*
Y1611378D03*
Y1616496D03*
X1703503Y1458622D03*
Y1463741D03*
X1694842Y1462953D03*
X1703503Y1473977D03*
Y1479095D03*
X1694842Y1468071D03*
Y1478308D03*
X1703503Y1489331D03*
Y1494449D03*
X1694842Y1483426D03*
Y1493662D03*
Y1498780D03*
X1703503Y1504685D03*
Y1509804D03*
X1694842Y1509016D03*
Y1514134D03*
X1703503Y1560985D03*
Y1566103D03*
Y1576339D03*
X1694842Y1565315D03*
Y1570434D03*
X1703503Y1581457D03*
Y1591693D03*
X1694842Y1580670D03*
Y1585788D03*
Y1596024D03*
X1703503Y1596811D03*
Y1607048D03*
Y1612166D03*
X1694842Y1601142D03*
Y1611378D03*
Y1616496D03*
X1712165Y1462953D03*
Y1468071D03*
Y1478308D03*
Y1483426D03*
Y1493662D03*
Y1498780D03*
Y1509016D03*
Y1514134D03*
Y1565315D03*
Y1570434D03*
Y1580670D03*
Y1585788D03*
Y1596024D03*
Y1601142D03*
Y1611378D03*
Y1616496D03*
G54D37*
X173829Y455492D03*
Y583957D03*
X202844Y455492D03*
Y583957D03*
X630915Y455492D03*
Y583957D03*
X659930Y455492D03*
Y583957D03*
X1088002Y455492D03*
Y583957D03*
X1117017Y455492D03*
Y583957D03*
X1545089Y455492D03*
Y583957D03*
X1574104Y455492D03*
Y583957D03*
G54D61*
X1795453Y812874D03*
Y834922D03*
G54D48*
X849441Y1367717D03*
G54D50*
X895384Y228740D03*
Y276772D03*
X923336Y226772D03*
Y278740D03*
G54D55*
X1030635Y764546D03*
G54D62*
X1803917Y823898D03*
G54D59*
X1747253Y1715189D03*
Y1744208D03*
X1747246Y1773377D03*
G54D60*
X1747253Y1802909D03*
G54D63*
X1817323Y1567323D03*
G54D13*
X19685Y-83298D03*
Y1801195D03*
X1821260Y-83298D03*
Y1801195D03*
G54D29*
X116731Y1066535D03*
Y1263386D03*
X352952Y1066535D03*
Y1263386D03*
X573818Y1066535D03*
Y1263386D03*
X810038Y1066535D03*
Y1263386D03*
X1030905Y1066535D03*
Y1263386D03*
X1267125Y1066535D03*
Y1263386D03*
X1487991Y1066535D03*
Y1263386D03*
X1724212Y1066535D03*
Y1263386D03*
G54D17*
X26789Y1373669D03*
X184851Y334492D03*
X235433Y1580079D03*
Y1626339D03*
X581890Y1580079D03*
Y1626339D03*
X1259055Y1580079D03*
Y1626339D03*
X1605512Y1580079D03*
Y1626339D03*
X1796847Y1517889D03*
X1809883Y120792D03*
G54D47*
X770472Y1490945D03*
X820079Y388583D03*
X1020866D03*
X1070472Y1490945D03*
G54D31*
X109882Y1453504D03*
Y1468859D03*
Y1484213D03*
Y1499567D03*
Y1514922D03*
Y1555867D03*
Y1571221D03*
Y1586575D03*
Y1601930D03*
Y1617284D03*
X127205Y1453504D03*
X118543Y1457835D03*
X127205Y1468859D03*
X118543Y1473189D03*
X127205Y1484213D03*
X118543Y1488544D03*
X127205Y1499567D03*
Y1514922D03*
X118543Y1503898D03*
Y1519252D03*
X127205Y1555867D03*
X118543Y1560197D03*
X127205Y1571221D03*
X118543Y1575552D03*
X127205Y1586575D03*
X118543Y1590906D03*
X127205Y1601930D03*
X118543Y1606260D03*
X127205Y1617284D03*
X118543Y1621615D03*
X144528Y1453504D03*
X135866Y1457835D03*
X144528Y1468859D03*
X135866Y1473189D03*
X144528Y1484213D03*
X135866Y1488544D03*
X144528Y1499567D03*
Y1514922D03*
X135866Y1503898D03*
Y1519252D03*
X144528Y1555867D03*
X135866Y1560197D03*
X144528Y1571221D03*
X135866Y1575552D03*
X144528Y1586575D03*
X135866Y1590906D03*
X144528Y1601930D03*
X135866Y1606260D03*
X144528Y1617284D03*
X135866Y1621615D03*
X161850Y1453504D03*
X153189Y1457835D03*
X161850Y1468859D03*
X153189Y1473189D03*
X161850Y1484213D03*
X153189Y1488544D03*
X161850Y1499567D03*
Y1514922D03*
X153189Y1503898D03*
Y1519252D03*
X161850Y1555867D03*
X153189Y1560197D03*
X161850Y1571221D03*
X153189Y1575552D03*
X161850Y1586575D03*
X153189Y1590906D03*
X161850Y1601930D03*
X153189Y1606260D03*
X161850Y1617284D03*
X153189Y1621615D03*
X179173Y1453504D03*
X170512Y1457835D03*
X179173Y1468859D03*
X170512Y1473189D03*
X179173Y1484213D03*
X170512Y1488544D03*
X179173Y1499567D03*
Y1514922D03*
X170512Y1503898D03*
Y1519252D03*
X179173Y1555867D03*
X170512Y1560197D03*
X179173Y1571221D03*
X170512Y1575552D03*
X179173Y1586575D03*
X170512Y1590906D03*
X179173Y1601930D03*
X170512Y1606260D03*
X179173Y1617284D03*
X170512Y1621615D03*
X187835Y1457835D03*
Y1473189D03*
Y1488544D03*
Y1503898D03*
Y1519252D03*
Y1560197D03*
Y1575552D03*
Y1590906D03*
Y1606260D03*
Y1621615D03*
X283110Y1453504D03*
X291771Y1457835D03*
X283110Y1468859D03*
X291771Y1473189D03*
X283110Y1484213D03*
X291771Y1488544D03*
X283110Y1499567D03*
X291771Y1503898D03*
X283110Y1514922D03*
X291771Y1519252D03*
X283110Y1555867D03*
X291771Y1560197D03*
X283110Y1571221D03*
X291771Y1575552D03*
X283110Y1586575D03*
X291771Y1590906D03*
X283110Y1601930D03*
X291771Y1606260D03*
X283110Y1617284D03*
X291771Y1621615D03*
X300433Y1453504D03*
X309094Y1457835D03*
X300433Y1468859D03*
X309094Y1473189D03*
X300433Y1484213D03*
X309094Y1488544D03*
X300433Y1499567D03*
X309094Y1503898D03*
X300433Y1514922D03*
X309094Y1519252D03*
X300433Y1555867D03*
X309094Y1560197D03*
X300433Y1571221D03*
X309094Y1575552D03*
X300433Y1586575D03*
X309094Y1590906D03*
X300433Y1601930D03*
X309094Y1606260D03*
X300433Y1617284D03*
X309094Y1621615D03*
X317756Y1453504D03*
X326417Y1457835D03*
X317756Y1468859D03*
X326417Y1473189D03*
X317756Y1484213D03*
X326417Y1488544D03*
X317756Y1499567D03*
X326417Y1503898D03*
X317756Y1514922D03*
X326417Y1519252D03*
X317756Y1555867D03*
X326417Y1560197D03*
X317756Y1571221D03*
X326417Y1575552D03*
X317756Y1586575D03*
X326417Y1590906D03*
X317756Y1601930D03*
X326417Y1606260D03*
X317756Y1617284D03*
X326417Y1621615D03*
X335078Y1453504D03*
X343740Y1457835D03*
X335078Y1468859D03*
X343740Y1473189D03*
X335078Y1484213D03*
X343740Y1488544D03*
X335078Y1499567D03*
X343740Y1503898D03*
X335078Y1514922D03*
X343740Y1519252D03*
X335078Y1555867D03*
X343740Y1560197D03*
X335078Y1571221D03*
X343740Y1575552D03*
X335078Y1586575D03*
X343740Y1590906D03*
X335078Y1601930D03*
X343740Y1606260D03*
X335078Y1617284D03*
X343740Y1621615D03*
X352401Y1453504D03*
X361063Y1457835D03*
X352401Y1468859D03*
X361063Y1473189D03*
X352401Y1484213D03*
X361063Y1488544D03*
X352401Y1499567D03*
X361063Y1503898D03*
X352401Y1514922D03*
X361063Y1519252D03*
X352401Y1555867D03*
X361063Y1560197D03*
X352401Y1571221D03*
X361063Y1575552D03*
X352401Y1586575D03*
X361063Y1590906D03*
X352401Y1601930D03*
X361063Y1606260D03*
X352401Y1617284D03*
X361063Y1621615D03*
X456339Y1453504D03*
Y1468859D03*
Y1484213D03*
Y1499567D03*
Y1514922D03*
Y1555867D03*
Y1571221D03*
Y1586575D03*
Y1601930D03*
Y1617284D03*
X473662Y1453504D03*
X465000Y1457835D03*
X473662Y1468859D03*
X465000Y1473189D03*
X473662Y1484213D03*
X465000Y1488544D03*
X473662Y1499567D03*
Y1514922D03*
X465000Y1503898D03*
Y1519252D03*
X473662Y1555867D03*
X465000Y1560197D03*
X473662Y1571221D03*
X465000Y1575552D03*
X473662Y1586575D03*
X465000Y1590906D03*
X473662Y1601930D03*
X465000Y1606260D03*
X473662Y1617284D03*
X465000Y1621615D03*
X490985Y1453504D03*
X482323Y1457835D03*
X490985Y1468859D03*
X482323Y1473189D03*
X490985Y1484213D03*
X482323Y1488544D03*
X490985Y1499567D03*
Y1514922D03*
X482323Y1503898D03*
Y1519252D03*
X490985Y1555867D03*
X482323Y1560197D03*
X490985Y1571221D03*
X482323Y1575552D03*
X490985Y1586575D03*
X482323Y1590906D03*
X490985Y1601930D03*
X482323Y1606260D03*
X490985Y1617284D03*
X482323Y1621615D03*
X508307Y1453504D03*
X499646Y1457835D03*
X508307Y1468859D03*
X499646Y1473189D03*
X508307Y1484213D03*
X499646Y1488544D03*
X508307Y1499567D03*
Y1514922D03*
X499646Y1503898D03*
Y1519252D03*
X508307Y1555867D03*
X499646Y1560197D03*
X508307Y1571221D03*
X499646Y1575552D03*
X508307Y1586575D03*
X499646Y1590906D03*
X508307Y1601930D03*
X499646Y1606260D03*
X508307Y1617284D03*
X499646Y1621615D03*
X516969Y1457835D03*
Y1473189D03*
Y1488544D03*
Y1503898D03*
Y1519252D03*
Y1560197D03*
Y1575552D03*
Y1590906D03*
Y1606260D03*
Y1621615D03*
X525630Y1453504D03*
X534292Y1457835D03*
X525630Y1468859D03*
X534292Y1473189D03*
X525630Y1484213D03*
X534292Y1488544D03*
X525630Y1499567D03*
X534292Y1503898D03*
X525630Y1514922D03*
X534292Y1519252D03*
X525630Y1555867D03*
X534292Y1560197D03*
X525630Y1571221D03*
X534292Y1575552D03*
X525630Y1586575D03*
X534292Y1590906D03*
X525630Y1601930D03*
X534292Y1606260D03*
X525630Y1617284D03*
X534292Y1621615D03*
X629567Y1453504D03*
X638228Y1457835D03*
X629567Y1468859D03*
X638228Y1473189D03*
X629567Y1484213D03*
X638228Y1488544D03*
X629567Y1499567D03*
X638228Y1503898D03*
X629567Y1514922D03*
X638228Y1519252D03*
X629567Y1555867D03*
X638228Y1560197D03*
X629567Y1571221D03*
X638228Y1575552D03*
X629567Y1586575D03*
X638228Y1590906D03*
X629567Y1601930D03*
X638228Y1606260D03*
X629567Y1617284D03*
X638228Y1621615D03*
X646890Y1453504D03*
Y1468859D03*
Y1484213D03*
Y1499567D03*
Y1514922D03*
Y1555867D03*
Y1571221D03*
Y1586575D03*
Y1601930D03*
Y1617284D03*
X664213Y1453504D03*
X655551Y1457835D03*
X664213Y1468859D03*
X655551Y1473189D03*
X664213Y1484213D03*
X655551Y1488544D03*
X664213Y1499567D03*
Y1514922D03*
X655551Y1503898D03*
Y1519252D03*
X664213Y1555867D03*
X655551Y1560197D03*
X664213Y1571221D03*
X655551Y1575552D03*
X664213Y1586575D03*
X655551Y1590906D03*
X664213Y1601930D03*
X655551Y1606260D03*
X664213Y1617284D03*
X655551Y1621615D03*
X681535Y1453504D03*
X672874Y1457835D03*
X681535Y1468859D03*
X672874Y1473189D03*
X681535Y1484213D03*
X672874Y1488544D03*
X681535Y1499567D03*
Y1514922D03*
X672874Y1503898D03*
Y1519252D03*
X681535Y1555867D03*
X672874Y1560197D03*
X681535Y1571221D03*
X672874Y1575552D03*
X681535Y1586575D03*
X672874Y1590906D03*
X681535Y1601930D03*
X672874Y1606260D03*
X681535Y1617284D03*
X672874Y1621615D03*
X698858Y1453504D03*
X690197Y1457835D03*
X698858Y1468859D03*
X690197Y1473189D03*
X698858Y1484213D03*
X690197Y1488544D03*
X698858Y1499567D03*
Y1514922D03*
X690197Y1503898D03*
Y1519252D03*
X698858Y1555867D03*
X690197Y1560197D03*
X698858Y1571221D03*
X690197Y1575552D03*
X698858Y1586575D03*
X690197Y1590906D03*
X698858Y1601930D03*
X690197Y1606260D03*
X698858Y1617284D03*
X690197Y1621615D03*
X707520Y1457835D03*
Y1473189D03*
Y1488544D03*
Y1503898D03*
Y1519252D03*
Y1560197D03*
Y1575552D03*
Y1590906D03*
Y1606260D03*
Y1621615D03*
X1131850Y1453504D03*
X1140511Y1457835D03*
X1131850Y1468859D03*
X1140511Y1473189D03*
X1131850Y1484213D03*
X1140511Y1488544D03*
X1131850Y1499567D03*
X1140511Y1503898D03*
X1131850Y1514922D03*
X1140511Y1519252D03*
X1131850Y1555867D03*
X1140511Y1560197D03*
X1131850Y1571221D03*
X1140511Y1575552D03*
X1131850Y1586575D03*
X1140511Y1590906D03*
X1131850Y1601930D03*
X1140511Y1606260D03*
X1131850Y1617284D03*
X1140511Y1621615D03*
X1149173Y1453504D03*
X1157834Y1457835D03*
X1149173Y1468859D03*
X1157834Y1473189D03*
X1149173Y1484213D03*
X1157834Y1488544D03*
X1149173Y1499567D03*
X1157834Y1503898D03*
X1149173Y1514922D03*
X1157834Y1519252D03*
X1149173Y1555867D03*
X1157834Y1560197D03*
X1149173Y1571221D03*
X1157834Y1575552D03*
X1149173Y1586575D03*
X1157834Y1590906D03*
X1149173Y1601930D03*
X1157834Y1606260D03*
X1149173Y1617284D03*
X1157834Y1621615D03*
X1166496Y1453504D03*
Y1468859D03*
Y1484213D03*
Y1499567D03*
Y1514922D03*
Y1555867D03*
Y1571221D03*
Y1586575D03*
Y1601930D03*
Y1617284D03*
X1183818Y1453504D03*
X1175157Y1457835D03*
X1183818Y1468859D03*
X1175157Y1473189D03*
X1183818Y1484213D03*
X1175157Y1488544D03*
X1183818Y1499567D03*
Y1514922D03*
X1175157Y1503898D03*
Y1519252D03*
X1183818Y1555867D03*
X1175157Y1560197D03*
X1183818Y1571221D03*
X1175157Y1575552D03*
X1183818Y1586575D03*
X1175157Y1590906D03*
X1183818Y1601930D03*
X1175157Y1606260D03*
X1183818Y1617284D03*
X1175157Y1621615D03*
X1201141Y1453504D03*
X1192480Y1457835D03*
X1201141Y1468859D03*
X1192480Y1473189D03*
X1201141Y1484213D03*
X1192480Y1488544D03*
X1201141Y1499567D03*
Y1514922D03*
X1192480Y1503898D03*
Y1519252D03*
X1201141Y1555867D03*
X1192480Y1560197D03*
X1201141Y1571221D03*
X1192480Y1575552D03*
X1201141Y1586575D03*
X1192480Y1590906D03*
X1201141Y1601930D03*
X1192480Y1606260D03*
X1201141Y1617284D03*
X1192480Y1621615D03*
X1209803Y1457835D03*
Y1473189D03*
Y1488544D03*
Y1503898D03*
Y1519252D03*
Y1560197D03*
Y1575552D03*
Y1590906D03*
Y1606260D03*
Y1621615D03*
X1305079Y1453504D03*
X1313740Y1457835D03*
X1305079Y1468859D03*
X1313740Y1473189D03*
X1305079Y1484213D03*
X1313740Y1488544D03*
X1305079Y1499567D03*
X1313740Y1503898D03*
X1305079Y1514922D03*
X1313740Y1519252D03*
X1305079Y1555867D03*
X1313740Y1560197D03*
X1305079Y1571221D03*
X1313740Y1575552D03*
X1305079Y1586575D03*
X1313740Y1590906D03*
X1305079Y1601930D03*
X1313740Y1606260D03*
X1305079Y1617284D03*
X1313740Y1621615D03*
X1322402Y1453504D03*
X1331063Y1457835D03*
X1322402Y1468859D03*
X1331063Y1473189D03*
X1322402Y1484213D03*
X1331063Y1488544D03*
X1322402Y1499567D03*
X1331063Y1503898D03*
X1322402Y1514922D03*
X1331063Y1519252D03*
X1322402Y1555867D03*
X1331063Y1560197D03*
X1322402Y1571221D03*
X1331063Y1575552D03*
X1322402Y1586575D03*
X1331063Y1590906D03*
X1322402Y1601930D03*
X1331063Y1606260D03*
X1322402Y1617284D03*
X1331063Y1621615D03*
X1339725Y1453504D03*
X1348386Y1457835D03*
X1339725Y1468859D03*
X1348386Y1473189D03*
X1339725Y1484213D03*
X1348386Y1488544D03*
X1339725Y1499567D03*
X1348386Y1503898D03*
X1339725Y1514922D03*
X1348386Y1519252D03*
X1339725Y1555867D03*
X1348386Y1560197D03*
X1339725Y1571221D03*
X1348386Y1575552D03*
X1339725Y1586575D03*
X1348386Y1590906D03*
X1339725Y1601930D03*
X1348386Y1606260D03*
X1339725Y1617284D03*
X1348386Y1621615D03*
X1357047Y1453504D03*
X1365709Y1457835D03*
X1357047Y1468859D03*
X1365709Y1473189D03*
X1357047Y1484213D03*
X1365709Y1488544D03*
X1357047Y1499567D03*
X1365709Y1503898D03*
X1357047Y1514922D03*
X1365709Y1519252D03*
X1357047Y1555867D03*
X1365709Y1560197D03*
X1357047Y1571221D03*
X1365709Y1575552D03*
X1357047Y1586575D03*
X1365709Y1590906D03*
X1357047Y1601930D03*
X1365709Y1606260D03*
X1357047Y1617284D03*
X1365709Y1621615D03*
X1374370Y1453504D03*
X1383032Y1457835D03*
X1374370Y1468859D03*
X1383032Y1473189D03*
X1374370Y1484213D03*
X1383032Y1488544D03*
X1374370Y1499567D03*
X1383032Y1503898D03*
X1374370Y1514922D03*
X1383032Y1519252D03*
X1374370Y1555867D03*
X1383032Y1560197D03*
X1374370Y1571221D03*
X1383032Y1575552D03*
X1374370Y1586575D03*
X1383032Y1590906D03*
X1374370Y1601930D03*
X1383032Y1606260D03*
X1374370Y1617284D03*
X1383032Y1621615D03*
X1478307Y1453504D03*
Y1468859D03*
Y1484213D03*
Y1499567D03*
Y1514922D03*
Y1555867D03*
Y1571221D03*
Y1586575D03*
Y1601930D03*
Y1617284D03*
X1495630Y1453504D03*
X1486968Y1457835D03*
X1495630Y1468859D03*
X1486968Y1473189D03*
X1495630Y1484213D03*
X1486968Y1488544D03*
X1495630Y1499567D03*
Y1514922D03*
X1486968Y1503898D03*
Y1519252D03*
X1495630Y1555867D03*
X1486968Y1560197D03*
X1495630Y1571221D03*
X1486968Y1575552D03*
X1495630Y1586575D03*
X1486968Y1590906D03*
X1495630Y1601930D03*
X1486968Y1606260D03*
X1495630Y1617284D03*
X1486968Y1621615D03*
X1512953Y1453504D03*
X1504291Y1457835D03*
X1512953Y1468859D03*
X1504291Y1473189D03*
X1512953Y1484213D03*
X1504291Y1488544D03*
X1512953Y1499567D03*
Y1514922D03*
X1504291Y1503898D03*
Y1519252D03*
X1512953Y1555867D03*
X1504291Y1560197D03*
X1512953Y1571221D03*
X1504291Y1575552D03*
X1512953Y1586575D03*
X1504291Y1590906D03*
X1512953Y1601930D03*
X1504291Y1606260D03*
X1512953Y1617284D03*
X1504291Y1621615D03*
X1530275Y1453504D03*
X1521614Y1457835D03*
X1530275Y1468859D03*
X1521614Y1473189D03*
X1530275Y1484213D03*
X1521614Y1488544D03*
X1530275Y1499567D03*
Y1514922D03*
X1521614Y1503898D03*
Y1519252D03*
X1530275Y1555867D03*
X1521614Y1560197D03*
X1530275Y1571221D03*
X1521614Y1575552D03*
X1530275Y1586575D03*
X1521614Y1590906D03*
X1530275Y1601930D03*
X1521614Y1606260D03*
X1530275Y1617284D03*
X1521614Y1621615D03*
X1547598Y1453504D03*
X1538937Y1457835D03*
X1547598Y1468859D03*
X1538937Y1473189D03*
X1547598Y1484213D03*
X1538937Y1488544D03*
X1547598Y1499567D03*
Y1514922D03*
X1538937Y1503898D03*
Y1519252D03*
X1547598Y1555867D03*
X1538937Y1560197D03*
X1547598Y1571221D03*
X1538937Y1575552D03*
X1547598Y1586575D03*
X1538937Y1590906D03*
X1547598Y1601930D03*
X1538937Y1606260D03*
X1547598Y1617284D03*
X1538937Y1621615D03*
X1556260Y1457835D03*
Y1473189D03*
Y1488544D03*
Y1503898D03*
Y1519252D03*
Y1560197D03*
Y1575552D03*
Y1590906D03*
Y1606260D03*
Y1621615D03*
X1651535Y1453504D03*
X1660196Y1457835D03*
X1651535Y1468859D03*
X1660196Y1473189D03*
X1651535Y1484213D03*
X1660196Y1488544D03*
X1651535Y1499567D03*
X1660196Y1503898D03*
X1651535Y1514922D03*
X1660196Y1519252D03*
X1651535Y1555867D03*
X1660196Y1560197D03*
X1651535Y1571221D03*
X1660196Y1575552D03*
X1651535Y1586575D03*
X1660196Y1590906D03*
X1651535Y1601930D03*
X1660196Y1606260D03*
X1651535Y1617284D03*
X1660196Y1621615D03*
X1668858Y1453504D03*
X1677519Y1457835D03*
X1668858Y1468859D03*
X1677519Y1473189D03*
X1668858Y1484213D03*
X1677519Y1488544D03*
X1668858Y1499567D03*
X1677519Y1503898D03*
X1668858Y1514922D03*
X1677519Y1519252D03*
X1668858Y1555867D03*
X1677519Y1560197D03*
X1668858Y1571221D03*
X1677519Y1575552D03*
X1668858Y1586575D03*
X1677519Y1590906D03*
X1668858Y1601930D03*
X1677519Y1606260D03*
X1668858Y1617284D03*
X1677519Y1621615D03*
X1686181Y1453504D03*
Y1468859D03*
Y1484213D03*
Y1499567D03*
Y1514922D03*
Y1555867D03*
Y1571221D03*
Y1586575D03*
Y1601930D03*
Y1617284D03*
X1703503Y1453504D03*
X1694842Y1457835D03*
X1703503Y1468859D03*
X1694842Y1473189D03*
X1703503Y1484213D03*
X1694842Y1488544D03*
X1703503Y1499567D03*
Y1514922D03*
X1694842Y1503898D03*
Y1519252D03*
X1703503Y1555867D03*
X1694842Y1560197D03*
X1703503Y1571221D03*
X1694842Y1575552D03*
X1703503Y1586575D03*
X1694842Y1590906D03*
X1703503Y1601930D03*
X1694842Y1606260D03*
X1703503Y1617284D03*
X1694842Y1621615D03*
X1720826Y1453504D03*
X1712165Y1457835D03*
X1720826Y1468859D03*
X1712165Y1473189D03*
X1720826Y1484213D03*
X1712165Y1488544D03*
X1720826Y1499567D03*
Y1514922D03*
X1712165Y1503898D03*
Y1519252D03*
X1720826Y1555867D03*
X1712165Y1560197D03*
X1720826Y1571221D03*
X1712165Y1575552D03*
X1720826Y1586575D03*
X1712165Y1590906D03*
X1720826Y1601930D03*
X1712165Y1606260D03*
X1720826Y1617284D03*
X1712165Y1621615D03*
X1729488Y1457835D03*
Y1473189D03*
Y1488544D03*
Y1503898D03*
Y1519252D03*
Y1560197D03*
Y1575552D03*
Y1590906D03*
Y1606260D03*
Y1621615D03*
G54D39*
X235433Y1606142D03*
X581890D03*
X1259055D03*
X1605512D03*
G54D16*
X15139Y198883D03*
Y201683D03*
X18564Y238589D03*
X6690Y1496782D03*
X34520Y213539D03*
X36201Y238714D03*
X21530Y236121D03*
X27966Y238689D03*
X27625Y663094D03*
X25818Y682139D03*
X28818D03*
X32079Y1517641D03*
X65189Y228961D03*
Y231461D03*
Y223661D03*
Y226461D03*
X54733Y231226D03*
Y228726D03*
Y223726D03*
Y226226D03*
X67622Y572842D03*
X64408Y572975D03*
X73110Y101701D03*
X78501Y110445D03*
Y115401D03*
Y129574D03*
Y124618D03*
X73158Y229286D03*
X76851Y222212D03*
Y224712D03*
X73158Y231786D03*
X75777Y585507D03*
X71184D03*
X71730Y579475D03*
X71228Y590145D03*
X75822Y590190D03*
X75684Y605443D03*
X83684D03*
X78129Y656900D03*
X72314Y680207D03*
Y683407D03*
X82714Y674707D03*
X71928Y873683D03*
X88903Y117557D03*
Y122513D03*
Y131731D03*
Y136687D03*
X94390Y293645D03*
Y290845D03*
Y288345D03*
X91890Y293645D03*
Y290845D03*
Y288345D03*
X93456Y649838D03*
X89432Y668293D03*
X92134D03*
X85614Y674707D03*
X87714Y684607D03*
X117501Y198883D03*
Y201683D03*
X111275Y1008262D03*
Y1011762D03*
X130328Y238689D03*
X123892Y236121D03*
X120926Y238589D03*
X136882Y213539D03*
X138563Y238714D03*
X143186Y402291D03*
Y397335D03*
X140786Y416465D03*
Y411509D03*
Y425682D03*
Y430638D03*
Y439855D03*
Y444811D03*
Y468609D03*
Y473565D03*
Y487738D03*
Y482782D03*
Y512743D03*
Y517699D03*
Y531872D03*
Y526916D03*
X157095Y228726D03*
Y231226D03*
X167551Y223661D03*
X157095Y226226D03*
Y223726D03*
X151188Y390223D03*
Y395179D03*
Y404396D03*
Y409352D03*
Y423525D03*
Y418569D03*
Y432743D03*
Y437699D03*
Y489895D03*
Y480677D03*
Y475721D03*
Y494851D03*
Y519855D03*
Y538984D03*
Y534028D03*
Y524811D03*
X175472Y101701D03*
X175520Y229286D03*
X179213Y224712D03*
Y222212D03*
X167551Y231461D03*
Y228961D03*
Y226461D03*
X175520Y231786D03*
X194189Y103621D03*
X196752Y293645D03*
Y290845D03*
Y288345D03*
X194252Y293645D03*
Y290845D03*
Y288345D03*
X203740Y567914D03*
Y565414D03*
Y570414D03*
Y575414D03*
Y572914D03*
X219863Y198883D03*
Y201683D03*
X226254Y236121D03*
X223288Y238589D03*
X239244Y213539D03*
X232690Y238689D03*
X240925Y238714D03*
X259457Y228726D03*
Y231226D03*
Y226226D03*
Y223726D03*
X251802Y824128D03*
X277834Y101701D03*
X269913Y228961D03*
Y226461D03*
Y223661D03*
X277882Y229286D03*
X269913Y231461D03*
X277882Y231786D03*
X286129Y36971D03*
X296551Y103621D03*
X281575Y224712D03*
Y222212D03*
X296614Y293645D03*
Y290845D03*
Y288345D03*
X309106Y37543D03*
X299114Y290845D03*
Y288345D03*
Y293645D03*
X302966Y324139D03*
X310013Y316731D03*
X301158Y380307D03*
X301308Y395346D03*
X301393Y400039D03*
X322225Y198883D03*
Y201683D03*
X325650Y238589D03*
X328616Y236121D03*
X321549Y445315D03*
Y448115D03*
X323489Y471484D03*
Y466528D03*
Y480701D03*
Y485657D03*
Y515617D03*
Y510661D03*
Y529791D03*
Y524835D03*
Y565657D03*
Y560701D03*
Y574874D03*
Y579830D03*
Y589047D03*
Y594003D03*
Y603221D03*
Y608177D03*
X330905Y11806D03*
Y23806D03*
Y31806D03*
X341606Y213539D03*
X335052Y238689D03*
X343287Y238714D03*
X345050Y458334D03*
X333891Y473640D03*
Y487813D03*
Y478596D03*
Y492769D03*
Y522730D03*
Y517774D03*
Y531947D03*
Y536903D03*
Y572769D03*
Y567813D03*
Y586943D03*
Y581987D03*
Y596160D03*
Y601116D03*
Y610333D03*
Y615289D03*
X347450Y447486D03*
X353670Y488618D03*
Y491118D03*
Y493618D03*
Y496118D03*
X372275Y226461D03*
X361819Y231226D03*
Y228726D03*
Y223726D03*
Y226226D03*
X372275Y228961D03*
Y231461D03*
Y223661D03*
X364954Y450091D03*
X367564Y452740D03*
X365332Y490070D03*
Y487570D03*
X361887Y493758D03*
Y496258D03*
X377020Y782535D03*
X368491Y815092D03*
X368273Y928100D03*
X380196Y101701D03*
X380244Y229286D03*
X383937Y222212D03*
Y224712D03*
X380244Y231786D03*
X393837Y466409D03*
X393823Y487382D03*
X398913Y103621D03*
X398976Y293645D03*
X401476D03*
Y288345D03*
Y290845D03*
X398976Y288345D03*
Y290845D03*
X406843Y399161D03*
Y401661D03*
Y396661D03*
X405603Y668060D03*
X408103D03*
X403103D03*
X400603D03*
Y678060D03*
X405603D03*
X408103D03*
X403103D03*
X406967Y878764D03*
X406415Y874840D03*
X399285Y1081599D03*
X398915Y1097278D03*
X396415D03*
X401711Y1419771D03*
X406667D03*
X400911Y1537902D03*
X407048D03*
X400911Y1544424D03*
X407048Y1549936D03*
X400911D03*
X420050Y33425D03*
X418876Y401661D03*
Y396661D03*
Y399161D03*
X411754Y474513D03*
X424731Y508152D03*
Y513452D03*
Y515952D03*
X414275Y508217D03*
Y510717D03*
Y515717D03*
Y513217D03*
X424731Y510952D03*
X410603Y668060D03*
Y678060D03*
X425759Y869921D03*
Y872721D03*
Y875521D03*
Y867121D03*
Y878321D03*
X411214Y892109D03*
X413012Y1537902D03*
Y1544098D03*
X426196Y1534087D03*
X413012Y1549936D03*
X421616Y1549885D03*
X442704Y506427D03*
X427693Y506520D03*
X438353Y508685D03*
X427693Y509020D03*
X432700Y516277D03*
X429210Y784833D03*
X428759Y869921D03*
Y867121D03*
Y872721D03*
Y875521D03*
Y878321D03*
X432332Y892049D03*
Y897649D03*
Y894849D03*
Y900449D03*
X453544Y461961D03*
X451144Y472809D03*
X447836Y711199D03*
X451889Y1301067D03*
X456832Y1299121D03*
X451889Y1306023D03*
X472226Y198883D03*
Y201683D03*
X473658Y467215D03*
X471048Y464566D03*
X469495Y1011303D03*
Y1023303D03*
Y1017303D03*
X491607Y213539D03*
X478617Y236121D03*
X475651Y238589D03*
X485053Y238689D03*
X481495Y1011303D03*
X475495D03*
X481495Y1023303D03*
Y1017303D03*
X475495Y1023303D03*
X484800Y1302000D03*
X493288Y238714D03*
X522276Y223661D03*
Y226461D03*
Y228961D03*
Y231461D03*
X511820Y231226D03*
Y228726D03*
Y223726D03*
Y226226D03*
X521494Y572975D03*
X524475Y952290D03*
X509471Y981608D03*
X517374Y1287222D03*
X514363Y1287370D03*
X520548Y1287181D03*
X530197Y101701D03*
X530245Y229286D03*
X533938Y222212D03*
Y224712D03*
X530245Y231786D03*
X524708Y572842D03*
X532863Y585507D03*
X528270D03*
X528816Y579475D03*
X532908Y590190D03*
X528314Y590145D03*
X532770Y605443D03*
X528868Y873683D03*
X548914Y103621D03*
X551477Y288345D03*
Y290845D03*
X548977Y288345D03*
Y290845D03*
Y293645D03*
X551477D03*
X540770Y605443D03*
X574588Y201683D03*
X568362Y1008262D03*
Y1011762D03*
X574588Y198883D03*
X587415Y238689D03*
X580979Y236121D03*
X578013Y238589D03*
X577249Y965445D03*
X593969Y213539D03*
X595650Y238714D03*
X600272Y397335D03*
Y402291D03*
X597872Y425682D03*
Y416465D03*
Y411509D03*
Y439855D03*
Y430638D03*
Y444811D03*
Y468609D03*
Y473565D03*
Y487738D03*
Y482782D03*
Y517699D03*
Y531872D03*
Y526916D03*
X606142Y965665D03*
X614182Y223726D03*
Y226226D03*
Y231226D03*
Y228726D03*
X608274Y390223D03*
Y395179D03*
Y404396D03*
Y409352D03*
Y418569D03*
Y423525D03*
Y432743D03*
Y437699D03*
Y489895D03*
Y480677D03*
Y475721D03*
Y494851D03*
Y519855D03*
Y538984D03*
Y534028D03*
Y524811D03*
X632559Y101701D03*
X624638Y231461D03*
X636300Y222212D03*
Y224712D03*
X632607Y229286D03*
X624638Y223661D03*
Y226461D03*
Y228961D03*
X632607Y231786D03*
X651276Y103621D03*
X651339Y290845D03*
Y293645D03*
X653839D03*
Y288345D03*
Y290845D03*
X651339Y288345D03*
X660826Y570414D03*
Y567914D03*
Y565414D03*
Y575414D03*
Y572914D03*
X676950Y201683D03*
X680375Y238589D03*
X683341Y236121D03*
X696331Y213539D03*
X698012Y238714D03*
X689777Y238689D03*
X716544Y228726D03*
Y231226D03*
Y226226D03*
Y223726D03*
X704446Y760611D03*
X713425Y786029D03*
X734921Y101701D03*
X727000Y228961D03*
Y226461D03*
Y223661D03*
X734969Y229286D03*
X727000Y231461D03*
X734969Y231786D03*
X721218Y742131D03*
X720271Y782481D03*
X738662Y224712D03*
Y222212D03*
X744069Y746617D03*
X735576Y861780D03*
X753638Y103621D03*
X760407Y324494D03*
X767099Y316731D03*
X767310Y1599164D03*
X756358Y1616917D03*
X779312Y198883D03*
Y201683D03*
X782737Y238589D03*
X780575Y471484D03*
Y466528D03*
Y480701D03*
Y485657D03*
Y510661D03*
Y515617D03*
Y524835D03*
Y529791D03*
Y560701D03*
Y565657D03*
Y579830D03*
Y574874D03*
Y589047D03*
Y594003D03*
Y603221D03*
Y608177D03*
X798693Y213539D03*
X792139Y238689D03*
X785703Y236121D03*
X790977Y473640D03*
Y487813D03*
Y478596D03*
Y492769D03*
Y517774D03*
Y522730D03*
Y531947D03*
Y536903D03*
Y567813D03*
Y572769D03*
Y581987D03*
Y586943D03*
Y601116D03*
Y596160D03*
Y615289D03*
Y610333D03*
X800374Y238714D03*
X804536Y441486D03*
X802136Y452334D03*
X810756Y491118D03*
Y488618D03*
Y483618D03*
Y486118D03*
X815492Y732917D03*
X829362Y231461D03*
Y228961D03*
Y226461D03*
Y223661D03*
X818906Y228726D03*
Y231226D03*
Y226226D03*
Y223726D03*
X829381Y348036D03*
X824650Y446740D03*
X822040Y444091D03*
X826262Y462326D03*
Y459326D03*
X818973Y491258D03*
Y488758D03*
X822418Y485070D03*
Y482570D03*
X823790Y713375D03*
X823843Y732109D03*
X819890Y736924D03*
X828423Y964731D03*
X837283Y101701D03*
X837331Y229286D03*
X841024Y224712D03*
Y222212D03*
X837331Y231786D03*
X839573Y325327D03*
X856000Y103621D03*
X858563Y293645D03*
Y290845D03*
X856063Y293645D03*
Y290845D03*
X858563Y288345D03*
X856063D03*
X854622Y359004D03*
X873885Y340892D03*
X873733Y357844D03*
X871382Y373971D03*
X875907Y486256D03*
X870137Y669461D03*
X875916Y808965D03*
X886026Y346584D03*
X896592Y362369D03*
Y366369D03*
Y370369D03*
X882907Y480350D03*
X892023Y570176D03*
X890959Y579788D03*
X890956Y588325D03*
X894015Y588253D03*
X895933Y618143D03*
X910076Y304843D03*
X905120D03*
X913206Y336489D03*
X910040Y353532D03*
X902169Y413002D03*
Y418002D03*
Y415502D03*
X913853Y561487D03*
X904393Y570176D03*
X908517D03*
X898815D03*
X898232Y588320D03*
X902635Y588305D03*
X906999Y588274D03*
X905313Y709259D03*
X905050Y720268D03*
X913716Y800815D03*
X899916D03*
X911053Y800510D03*
X901428Y1136426D03*
X904897Y1145169D03*
X902397D03*
X929978Y186854D03*
Y184054D03*
X917906Y321670D03*
X922629Y336609D03*
X922198Y342051D03*
X917858Y331453D03*
X927309Y357267D03*
X921389D03*
X915395D03*
Y363212D03*
X927309Y363239D03*
Y369210D03*
X921468D03*
X915395D03*
X927072Y386992D03*
X919072D03*
X923072D03*
X914202Y418002D03*
Y413002D03*
Y415502D03*
X916590Y800636D03*
X921790Y810965D03*
X926044Y1545370D03*
Y1542370D03*
X938125Y230891D03*
X942805Y223860D03*
X936369Y221292D03*
X940158Y245707D03*
X946064Y252998D03*
X941845Y278968D03*
X939606Y310521D03*
X939653Y317474D03*
X940924Y328959D03*
X936608Y326058D03*
X945120Y326441D03*
X930398Y342050D03*
X936453Y345336D03*
X945599Y345383D03*
X940972Y338238D03*
X943663Y355674D03*
X944900Y363700D03*
X938499Y362202D03*
X940600Y370600D03*
X939314Y707847D03*
X931244Y720471D03*
X936026Y730600D03*
X941916Y808965D03*
X949359Y198710D03*
X951040Y223885D03*
X956348Y356371D03*
X952170Y356131D03*
X958823Y362802D03*
X954888Y369513D03*
X948400Y370045D03*
X956035Y1545333D03*
X959035D03*
X953035D03*
X950035D03*
X959035Y1542333D03*
X956035D03*
X953035D03*
X950035D03*
X968906Y223726D03*
Y228726D03*
Y231226D03*
X979362Y223661D03*
X968906Y226226D03*
X973338Y345018D03*
X978581Y572975D03*
X971144Y908972D03*
X965405Y1136426D03*
X987283Y101701D03*
X987331Y229286D03*
X991024Y224712D03*
Y222212D03*
X979362Y231461D03*
Y228961D03*
Y226461D03*
X987331Y231786D03*
X992045Y366559D03*
X984045D03*
X988045D03*
X981795Y572842D03*
X985903Y579475D03*
X985357Y585507D03*
X989950D03*
X985401Y590145D03*
X989995Y590190D03*
X989857Y605443D03*
X983712Y722064D03*
X1006000Y103621D03*
X1008563Y293645D03*
X1006063D03*
Y290845D03*
Y288345D03*
X1008563Y290845D03*
Y288345D03*
X997857Y605443D03*
X1010606Y1547824D03*
X1010659Y1568771D03*
Y1565771D03*
X1010653Y1571669D03*
X1021451Y322879D03*
X1026032Y322906D03*
X1018238Y678647D03*
X1018155Y684132D03*
X1025116Y698332D03*
X1024932Y717856D03*
X1016320Y828481D03*
X1026340Y917761D03*
X1025448Y1008262D03*
Y1011762D03*
X1013606Y1547824D03*
X1016606D03*
X1019606D03*
X1013659Y1568771D03*
X1016659D03*
X1019659D03*
X1013659Y1565771D03*
X1016659D03*
X1019659D03*
X1013653Y1571669D03*
X1016653D03*
X1019653D03*
X1031674Y198883D03*
Y201683D03*
X1038065Y236121D03*
X1035099Y238589D03*
X1030184Y288709D03*
X1038068Y298789D03*
X1033112D03*
X1030753Y732213D03*
X1051055Y213539D03*
X1044501Y238689D03*
X1052736Y238714D03*
X1048695Y280161D03*
X1057359Y402291D03*
Y397335D03*
X1054959Y411509D03*
Y425682D03*
Y416465D03*
Y430638D03*
Y439855D03*
Y444811D03*
Y468609D03*
Y473565D03*
Y487738D03*
Y482782D03*
Y517699D03*
Y512743D03*
Y531872D03*
Y526916D03*
X1071268Y226226D03*
Y223726D03*
Y228726D03*
Y231226D03*
X1065361Y390223D03*
Y395179D03*
Y404396D03*
Y409352D03*
Y423525D03*
Y418569D03*
Y432743D03*
Y437699D03*
Y489895D03*
Y480677D03*
Y475721D03*
Y494851D03*
Y519855D03*
Y524811D03*
Y538984D03*
Y534028D03*
X1089645Y101701D03*
X1081724Y226461D03*
Y223661D03*
X1089693Y229286D03*
X1081724Y231461D03*
Y228961D03*
X1089693Y231786D03*
X1079863Y345660D03*
X1090747Y1617415D03*
X1108362Y103621D03*
X1093386Y224712D03*
Y222212D03*
X1108425Y293645D03*
Y290845D03*
Y288345D03*
X1096264Y1562285D03*
X1093713Y1585583D03*
X1110925Y293645D03*
Y290845D03*
Y288345D03*
X1117913Y565414D03*
Y567914D03*
Y570414D03*
Y572914D03*
Y575414D03*
X1122718Y598857D03*
X1121191Y612555D03*
X1120512Y617332D03*
X1121022Y607750D03*
X1134036Y198883D03*
Y201683D03*
X1137461Y238589D03*
X1140427Y236121D03*
X1138166Y534759D03*
X1153417Y213539D03*
X1146863Y238689D03*
X1155098Y238714D03*
X1149437Y728541D03*
X1152316Y746625D03*
X1173630Y226226D03*
Y223726D03*
Y228726D03*
Y231226D03*
X1161274Y550462D03*
X1170603Y715281D03*
X1163751Y719498D03*
X1168577Y733812D03*
X1169266Y800799D03*
X1184086Y231461D03*
Y228961D03*
Y226461D03*
Y223661D03*
X1176577Y885974D03*
X1188431Y936568D03*
X1192007Y101701D03*
X1192055Y229286D03*
X1195748Y224712D03*
Y222212D03*
X1192055Y231786D03*
X1192990Y914873D03*
X1195118Y936296D03*
X1210724Y103621D03*
X1213287Y293645D03*
Y290845D03*
Y288345D03*
X1210787Y293645D03*
Y290845D03*
Y288345D03*
X1217139Y324139D03*
X1222909Y-83456D03*
Y-78500D03*
Y-68500D03*
Y-73456D03*
X1228265Y-44406D03*
Y-39450D03*
Y-29450D03*
Y-34406D03*
X1236398Y198883D03*
Y201683D03*
X1224186Y316731D03*
X1237662Y466528D03*
Y471484D03*
Y480701D03*
Y485657D03*
Y515617D03*
Y510661D03*
Y524835D03*
Y529791D03*
Y565657D03*
Y560701D03*
Y589047D03*
Y574874D03*
Y579830D03*
Y603221D03*
Y594003D03*
Y608177D03*
X1239823Y238589D03*
X1242789Y236121D03*
X1248064Y473640D03*
Y487813D03*
Y478596D03*
Y492769D03*
Y517774D03*
Y522730D03*
Y531947D03*
Y536903D03*
X1255779Y213539D03*
X1257460Y238714D03*
X1264481Y300223D03*
X1261623Y447486D03*
X1259223Y458334D03*
X1267843Y488618D03*
Y491118D03*
Y493618D03*
X1275992Y223726D03*
Y226226D03*
Y231226D03*
Y228726D03*
X1286448Y223661D03*
Y226461D03*
Y228961D03*
Y231461D03*
X1279127Y450091D03*
X1281737Y452740D03*
X1279505Y487570D03*
Y490070D03*
X1276060Y496258D03*
Y493758D03*
X1294369Y101701D03*
X1294417Y229286D03*
X1298110Y222212D03*
Y224712D03*
X1294417Y231786D03*
X1313086Y103621D03*
X1313149Y288345D03*
Y290845D03*
Y293645D03*
X1315649Y288345D03*
Y290845D03*
Y293645D03*
X1308010Y466409D03*
X1307996Y487382D03*
X1313459Y1081599D03*
X1310589Y1097278D03*
X1313089D03*
X1334223Y33425D03*
X1333049Y399268D03*
Y401768D03*
Y396768D03*
X1321016Y399161D03*
Y401661D03*
Y396661D03*
X1325927Y474513D03*
X1386399Y201683D03*
X1383669Y1011303D03*
Y1017303D03*
Y1023303D03*
X1386399Y198883D03*
X1399226Y238689D03*
X1392790Y236121D03*
X1389824Y238589D03*
X1395669Y1011303D03*
X1389669D03*
X1395669Y1017303D03*
Y1023303D03*
X1389669D03*
X1405780Y213539D03*
X1407461Y238714D03*
X1425993Y231226D03*
Y228726D03*
Y226226D03*
Y223726D03*
X1444370Y101701D03*
X1436449Y228961D03*
X1444418Y229286D03*
X1436449Y226461D03*
Y223661D03*
X1448111Y222212D03*
Y224712D03*
X1436449Y231461D03*
X1444418Y231786D03*
X1438882Y572842D03*
X1447037Y585507D03*
X1442444D03*
X1442990Y579475D03*
X1435668Y572975D03*
X1442488Y590145D03*
X1447082Y590190D03*
X1446944Y605443D03*
X1443041Y873683D03*
X1463087Y103621D03*
X1465650Y293645D03*
Y288345D03*
Y290845D03*
X1463150Y288345D03*
Y290845D03*
Y293645D03*
X1454944Y605443D03*
X1479409Y-83456D03*
Y-78500D03*
Y-68500D03*
Y-73456D03*
X1476822Y40780D03*
X1498621Y15043D03*
Y35043D03*
Y27043D03*
X1488761Y198883D03*
Y201683D03*
X1492186Y238589D03*
X1495152Y236121D03*
X1483813Y368516D03*
X1482535Y1008262D03*
Y1002453D03*
Y1011762D03*
X1514765Y-44536D03*
Y-39580D03*
Y-29580D03*
Y-34536D03*
X1508142Y213539D03*
X1509823Y238714D03*
X1501588Y238689D03*
X1514446Y402291D03*
Y397335D03*
X1512046Y411509D03*
Y425682D03*
Y416465D03*
Y439855D03*
Y430638D03*
Y444811D03*
Y468609D03*
Y473565D03*
Y487738D03*
Y482782D03*
Y517699D03*
Y512743D03*
Y531872D03*
Y526916D03*
X1528355Y228726D03*
Y223726D03*
Y226226D03*
Y231226D03*
X1515779Y351594D03*
X1522448Y390223D03*
Y395179D03*
Y404396D03*
Y409352D03*
Y423525D03*
Y418569D03*
Y437699D03*
Y432743D03*
Y489895D03*
Y480677D03*
Y475721D03*
Y494851D03*
Y519855D03*
Y538984D03*
Y534028D03*
Y524811D03*
X1546732Y101701D03*
X1538811Y226461D03*
Y228961D03*
Y231461D03*
X1546780Y229286D03*
X1538811Y223661D03*
X1546780Y231786D03*
X1550473Y222212D03*
Y224712D03*
X1565449Y103621D03*
X1565512Y288345D03*
X1568012Y293645D03*
Y290845D03*
Y288345D03*
X1565512Y293645D03*
Y290845D03*
X1575000Y565414D03*
Y567914D03*
Y570414D03*
Y572914D03*
Y575414D03*
X1579753Y599100D03*
X1578679Y613047D03*
X1578114Y607563D03*
X1591123Y198883D03*
Y201683D03*
X1594548Y238589D03*
X1610504Y213539D03*
X1597514Y236121D03*
X1612185Y238714D03*
X1603950Y238689D03*
X1641173Y231461D03*
X1630717Y223726D03*
Y226226D03*
Y231226D03*
Y228726D03*
X1641173Y223661D03*
Y226461D03*
Y228961D03*
X1649094Y101701D03*
X1649142Y229286D03*
X1652835Y222212D03*
Y224712D03*
X1649142Y231786D03*
X1667811Y103621D03*
X1670374Y290845D03*
Y288345D03*
X1667874Y290845D03*
Y288345D03*
X1670374Y293645D03*
X1667874D03*
X1674226Y324139D03*
X1693485Y198883D03*
Y201683D03*
X1681273Y316731D03*
X1699876Y236121D03*
X1696910Y238589D03*
X1706312Y238689D03*
X1694749Y466528D03*
Y471484D03*
X1705151Y473640D03*
Y487813D03*
Y478596D03*
X1694749Y480701D03*
Y485657D03*
X1705151Y492769D03*
Y517774D03*
Y522730D03*
X1694749Y510661D03*
Y515617D03*
X1705151Y536903D03*
Y531947D03*
X1694749Y524835D03*
Y529791D03*
X1705151Y572769D03*
Y567813D03*
X1694749Y565657D03*
Y560701D03*
Y579830D03*
X1705151Y586943D03*
Y581987D03*
X1694749Y589047D03*
Y574874D03*
Y603221D03*
X1705151Y601116D03*
Y596160D03*
X1694749Y594003D03*
X1705151Y615289D03*
X1694749Y608177D03*
X1705151Y610333D03*
X1712866Y213539D03*
X1714547Y238714D03*
X1718710Y447486D03*
X1716310Y458334D03*
X1724930Y491118D03*
Y488618D03*
Y493618D03*
Y496118D03*
X1733909Y-83456D03*
Y-78500D03*
Y-68500D03*
Y-73456D03*
X1733079Y223726D03*
Y226226D03*
Y231226D03*
Y228726D03*
X1743535Y223661D03*
X1738824Y452740D03*
X1736214Y450091D03*
X1736592Y487570D03*
Y490070D03*
X1733147Y493758D03*
Y496258D03*
X1751456Y101701D03*
X1743535Y226461D03*
X1755197Y224712D03*
X1743535Y228961D03*
Y231461D03*
X1751504Y229286D03*
X1755197Y222212D03*
X1751504Y231786D03*
X1770173Y103621D03*
X1772736Y293645D03*
X1770236D03*
Y290845D03*
Y288345D03*
X1772736Y290845D03*
Y288345D03*
X1765097Y466409D03*
X1765083Y487382D03*
X1772768Y818696D03*
X1790136Y399161D03*
Y401661D03*
Y396661D03*
X1778103Y399161D03*
Y401661D03*
Y396661D03*
X1783014Y474513D03*
X1778801Y836469D03*
X1786256Y927626D03*
X1784306Y924601D03*
X1786256Y930626D03*
X1799265Y-44666D03*
Y-39710D03*
Y-29710D03*
Y-34666D03*
X1791302Y829031D03*
X1816385Y1136912D03*
X1813885D03*
Y1144912D03*
X1816385D03*
G54D21*
X51043Y60709D03*
Y150197D03*
X153405Y60709D03*
Y150197D03*
X255767Y60709D03*
Y150197D03*
X279360Y368760D03*
Y421555D03*
Y501752D03*
Y550020D03*
Y636752D03*
X358129Y60709D03*
Y150197D03*
X508130Y60709D03*
Y150197D03*
X610492Y60709D03*
Y150197D03*
X712854Y60709D03*
Y150197D03*
X736446Y368760D03*
Y421555D03*
Y501752D03*
Y550020D03*
Y636752D03*
X815216Y60709D03*
Y150197D03*
X965216Y60709D03*
Y150197D03*
X1067578Y60709D03*
Y150197D03*
X1169940Y60709D03*
Y150197D03*
X1193533Y368760D03*
Y421555D03*
Y501752D03*
Y550020D03*
Y636752D03*
X1272302Y60709D03*
Y150197D03*
X1422303Y60709D03*
Y150197D03*
X1524665Y60709D03*
Y150197D03*
X1627027Y60709D03*
Y150197D03*
X1650620Y368760D03*
Y421555D03*
Y501752D03*
Y550020D03*
Y636752D03*
X1729389Y60709D03*
Y150197D03*
G54D49*
X843012Y1592787D03*
Y1602787D03*
Y1612787D03*
Y1622787D03*
X853012Y1592787D03*
Y1602787D03*
Y1612787D03*
Y1622787D03*
X878012Y1592787D03*
Y1602787D03*
Y1612787D03*
Y1622787D03*
X888012Y1592787D03*
Y1602787D03*
Y1612787D03*
Y1622787D03*
X913012Y1592787D03*
Y1602787D03*
Y1612787D03*
Y1622787D03*
X923012Y1592787D03*
Y1602787D03*
Y1612787D03*
Y1622787D03*
X948012Y1592787D03*
Y1602787D03*
Y1612787D03*
Y1622787D03*
X958012Y1592787D03*
Y1602787D03*
Y1612787D03*
Y1622787D03*
X983012Y1592787D03*
X993012D03*
X983012Y1602787D03*
Y1612787D03*
X993012Y1602787D03*
Y1612787D03*
X983012Y1622787D03*
X993012D03*
X1018012Y1592787D03*
X1028012D03*
X1018012Y1602787D03*
Y1612787D03*
X1028012Y1602787D03*
Y1612787D03*
X1018012Y1622787D03*
X1028012D03*
G54D12*
X3035Y1578036D03*
X3017Y1639466D03*
X14751Y62381D03*
X12601Y92110D03*
X9364Y107501D03*
X16728Y107910D03*
X12652Y116894D03*
X13615Y153263D03*
X10966Y155873D03*
Y152873D03*
X12709Y175777D03*
X9745Y245784D03*
X19075Y278429D03*
X7036Y268371D03*
X14252Y1121333D03*
X11552D03*
X16752D03*
X8952D03*
X14152Y1111633D03*
X11452D03*
X8852D03*
X16652D03*
X14252Y1130333D03*
X16752D03*
X14306Y1138705D03*
X16806D03*
X20079Y1429347D03*
X12327Y1519202D03*
X11995Y1535134D03*
X6567Y1554215D03*
X14375Y1553121D03*
X18409Y1554202D03*
X12000Y1644980D03*
X33288Y109410D03*
Y116497D03*
X30788D03*
X25988D03*
X22439Y106495D03*
X30788Y123584D03*
X33288Y123583D03*
X25988Y123584D03*
X33288Y130670D03*
X30788D03*
X25988D03*
X30788Y137757D03*
X25988D03*
X29201Y151651D03*
X26201D03*
X20709Y175777D03*
X28740Y247292D03*
X21449Y253198D03*
X28740Y267292D03*
X21386Y273198D03*
X23479Y295619D03*
X32452Y581222D03*
X29652D03*
X35252D03*
Y591215D03*
X29652D03*
X32452D03*
X34254Y611091D03*
X29451Y633560D03*
X30369Y663048D03*
X27854Y671553D03*
X30414Y671508D03*
X26596Y874520D03*
X26844Y920354D03*
X24132Y958151D03*
X25371Y980696D03*
X34314Y1215403D03*
X22284Y1464612D03*
X32079Y1525641D03*
X35237Y1532096D03*
X35850Y1556096D03*
X32000Y1644980D03*
X46450Y82984D03*
Y77784D03*
Y75184D03*
Y80384D03*
X48364Y92473D03*
X46450Y85584D03*
X37988Y109410D03*
Y102323D03*
Y116496D03*
Y130670D03*
Y123583D03*
X52437Y137756D03*
X37988D03*
X45984Y163264D03*
X37284Y285272D03*
X42690Y451466D03*
X48596Y458466D03*
X39643Y555194D03*
X36843D03*
X39643Y563194D03*
X36843D03*
X39643Y571194D03*
X36843D03*
X49265Y886660D03*
X52922Y900295D03*
X47916Y947622D03*
X50366Y1086981D03*
Y1082388D03*
X38200Y1089721D03*
X44365Y1086404D03*
X38216Y1093757D03*
X49500Y1199066D03*
X51197Y1218206D03*
X39452Y1250932D03*
X48195Y1511279D03*
X48079Y1525641D03*
Y1529641D03*
Y1521641D03*
X52048Y1556062D03*
X52000Y1644980D03*
X56098Y109410D03*
Y116496D03*
X55964Y103037D03*
X56098Y123583D03*
Y130670D03*
X68896Y226141D03*
X58279Y293796D03*
X66293Y285690D03*
X68793D03*
X66293Y288190D03*
X68793D03*
X60779Y293796D03*
X65759Y437508D03*
X61759D03*
X57759D03*
X54936Y449352D03*
X59522Y448874D03*
X68619Y447269D03*
X68497Y450201D03*
X64550Y504699D03*
X62050D03*
X59550D03*
X68236Y519458D03*
X61752Y516979D03*
X64252D03*
X59252D03*
X55318Y629362D03*
X53129Y627948D03*
X55307Y688473D03*
X66342Y880067D03*
X67316Y865869D03*
X64175Y897500D03*
X67461Y912983D03*
X63303Y912835D03*
X57178Y981386D03*
X69263Y1053152D03*
X55049Y1082343D03*
X55004Y1086937D03*
X58981Y1105100D03*
X56381D03*
X61581D03*
X64281D03*
X61681Y1114800D03*
X56481D03*
X59081D03*
X64381D03*
X57218Y1123867D03*
X55397Y1133688D03*
X57897D03*
X58250Y1220896D03*
X65940Y1209382D03*
X58250Y1227796D03*
Y1230296D03*
Y1237196D03*
Y1234696D03*
Y1223396D03*
X57185Y1480808D03*
X57144Y1491047D03*
X56114Y1556061D03*
X68743Y1583498D03*
X73381Y94017D03*
X69381D03*
X71422Y151540D03*
X75072Y191941D03*
X81572Y184619D03*
X74939Y188727D03*
X83552Y206760D03*
X71696Y226141D03*
X76766Y256535D03*
X84766D03*
X71593Y285690D03*
Y288190D03*
X75819Y290755D03*
X79819D03*
X83819D03*
X71826Y480705D03*
X75736Y519458D03*
X73236D03*
X70736D03*
X81740Y636250D03*
X69670Y633205D03*
Y636005D03*
X81740Y633450D03*
X69670Y638805D03*
X81740Y639050D03*
X74414Y681907D03*
X76991Y946134D03*
X84679Y1018368D03*
X70059Y1071656D03*
X69373Y1063389D03*
X70059Y1079656D03*
X80290Y1345691D03*
Y1350683D03*
X75334Y1345691D03*
Y1350683D03*
X80290Y1357603D03*
Y1362595D03*
X75334Y1357603D03*
Y1362595D03*
X80290Y1381801D03*
Y1369889D03*
Y1374881D03*
X75334Y1381801D03*
Y1374881D03*
Y1369889D03*
X80290Y1386793D03*
X75334D03*
X87000Y1597855D03*
X76005Y1580680D03*
X82433Y1580590D03*
X72000Y1644980D03*
X88080Y103603D03*
X87002Y146461D03*
X85904Y152367D03*
X87604Y180572D03*
X92287Y180527D03*
X96010Y192421D03*
X92242Y185121D03*
X87604Y185165D03*
X85796Y279208D03*
X89900Y281307D03*
X90257Y445506D03*
X88875Y840940D03*
X91581Y877859D03*
Y874859D03*
X87853Y899220D03*
X91128Y1006487D03*
X99836Y997860D03*
X95836D03*
X100594Y1035088D03*
X97247Y1030568D03*
X103124Y1165091D03*
X87574Y1345691D03*
Y1350683D03*
X99814D03*
Y1345691D03*
X92530D03*
Y1350683D03*
X87574Y1362595D03*
Y1357603D03*
X99814Y1362595D03*
Y1357603D03*
X92530Y1362595D03*
Y1357603D03*
X87574Y1374881D03*
Y1369795D03*
Y1381801D03*
X99814D03*
Y1374881D03*
Y1369889D03*
X92530Y1374881D03*
Y1369795D03*
Y1381801D03*
X87574Y1399079D03*
Y1393993D03*
Y1386793D03*
X99814Y1399079D03*
Y1394087D03*
Y1386793D03*
X92530Y1393993D03*
Y1399079D03*
Y1386793D03*
X87574Y1410991D03*
Y1405999D03*
X99814Y1410991D03*
Y1405999D03*
X92530Y1410991D03*
Y1405999D03*
X92000Y1644980D03*
X107364Y113394D03*
Y110394D03*
X110013Y110784D03*
X110152Y130898D03*
X117607Y133298D03*
X111754Y134579D03*
X107540Y172665D03*
Y180665D03*
X107572Y200864D03*
Y212864D03*
Y216864D03*
Y221864D03*
X109329Y252371D03*
X112474Y716315D03*
X114397Y727974D03*
X113601Y881266D03*
X107641Y865224D03*
X103836Y997860D03*
X111836D03*
X114770Y1009354D03*
X107836Y997860D03*
X115836D03*
X108933Y1102091D03*
X112433D03*
X103124D03*
X112433Y1114691D03*
X103124D03*
X108933D03*
Y1127291D03*
X112433D03*
X103124D03*
X112433Y1139891D03*
X103124Y1152491D03*
X108933D03*
X112433D03*
X108933Y1165091D03*
X112433D03*
X103184Y1177691D03*
X108933D03*
X112433D03*
X109415Y1202103D03*
X112795Y1223749D03*
X104770Y1350683D03*
Y1345691D03*
X112054D03*
Y1350683D03*
X117010Y1345691D03*
Y1350683D03*
X104770Y1362595D03*
Y1357603D03*
X112054Y1362595D03*
Y1357603D03*
X117010Y1362595D03*
Y1357603D03*
Y1369889D03*
Y1374881D03*
Y1381801D03*
X104770D03*
Y1374881D03*
Y1369889D03*
X112054D03*
Y1374881D03*
Y1381801D03*
X104770Y1399079D03*
Y1394087D03*
Y1386793D03*
X112054Y1399079D03*
Y1394087D03*
Y1386793D03*
X117010Y1394087D03*
Y1399079D03*
Y1386793D03*
X104770Y1410991D03*
Y1405999D03*
X112054Y1410991D03*
Y1405999D03*
X117010Y1410991D03*
Y1405999D03*
X107669Y1456451D03*
Y1465913D03*
X116330Y1465513D03*
X107669Y1461182D03*
X116330Y1460782D03*
X107669Y1481267D03*
X116330Y1480867D03*
X107669Y1476536D03*
X116330Y1476136D03*
Y1470244D03*
X107669Y1471805D03*
X116330Y1491490D03*
Y1485598D03*
X107669Y1487159D03*
Y1496621D03*
X116330Y1496221D03*
X107669Y1491890D03*
X116330Y1506845D03*
Y1500952D03*
X107669Y1502514D03*
X116330Y1511576D03*
X107669Y1511976D03*
Y1507245D03*
X116330Y1516307D03*
X107669Y1563544D03*
X116330Y1563144D03*
X107669Y1558813D03*
Y1568275D03*
X116330Y1567875D03*
X107669Y1578898D03*
X116330Y1578498D03*
Y1572606D03*
X107669Y1574167D03*
Y1583629D03*
X116330Y1583229D03*
X107669Y1594253D03*
X116330Y1593853D03*
Y1587960D03*
X107669Y1589522D03*
Y1609607D03*
X116330Y1609207D03*
X107669Y1598984D03*
X116330Y1598584D03*
Y1603315D03*
X107669Y1604876D03*
X116330Y1613938D03*
Y1618669D03*
X107669Y1614338D03*
X112000Y1644980D03*
X128350Y116497D03*
X133150D03*
X124606Y106495D03*
X125599Y109172D03*
X122599D03*
X133150Y123584D03*
X128350D03*
X133150Y130670D03*
X128350D03*
Y137757D03*
X133150D03*
X126246Y141228D03*
X124340Y146012D03*
X129134Y150847D03*
X131102Y247292D03*
X123811Y253198D03*
X125125Y362403D03*
X118122Y747565D03*
X122887Y884000D03*
X127067Y891495D03*
X124079Y1009354D03*
X119836Y997860D03*
X131836D03*
X127836D03*
X123836D03*
X120579Y1009354D03*
Y1021954D03*
X124079D03*
X133870Y1105091D03*
Y1117691D03*
Y1130291D03*
Y1142891D03*
Y1155491D03*
Y1168091D03*
X121211Y1215195D03*
X126937Y1209607D03*
X124294Y1350683D03*
Y1345691D03*
X129250Y1350683D03*
Y1345691D03*
X124294Y1362595D03*
Y1357603D03*
X129250D03*
Y1362595D03*
X124294Y1374881D03*
Y1369889D03*
Y1381801D03*
X129250Y1374881D03*
Y1369889D03*
Y1381801D03*
X124294Y1394087D03*
Y1399079D03*
Y1386793D03*
X129250Y1394087D03*
Y1399079D03*
Y1386793D03*
X124294Y1405999D03*
Y1410991D03*
X129250Y1405999D03*
Y1410991D03*
X124992Y1465913D03*
Y1456451D03*
Y1461182D03*
X133653Y1465513D03*
Y1460782D03*
X124992Y1471805D03*
Y1476536D03*
Y1481267D03*
X133653Y1476136D03*
Y1470244D03*
Y1480867D03*
Y1496221D03*
X124992Y1487159D03*
Y1491890D03*
Y1496621D03*
X133653Y1491490D03*
Y1485598D03*
Y1506845D03*
Y1500952D03*
Y1511576D03*
X124992Y1511976D03*
Y1507245D03*
Y1502514D03*
X133653Y1516307D03*
X124992Y1558813D03*
Y1563544D03*
X133653Y1563144D03*
Y1567875D03*
X124992Y1574167D03*
Y1578898D03*
X133653Y1578498D03*
Y1572606D03*
X124992Y1568275D03*
Y1589522D03*
Y1594253D03*
X133653Y1593853D03*
Y1587960D03*
X124992Y1583629D03*
X133653Y1583229D03*
X124992Y1609607D03*
Y1604876D03*
Y1598984D03*
X133653Y1609207D03*
Y1598584D03*
Y1603315D03*
X124992Y1614338D03*
X133653Y1613938D03*
Y1618669D03*
X132000Y1644980D03*
X148812Y80384D03*
Y82984D03*
Y75184D03*
Y77784D03*
Y85584D03*
X135650Y109410D03*
X140350Y116496D03*
Y109410D03*
Y102323D03*
X135650Y116497D03*
Y123583D03*
Y130670D03*
X140350D03*
Y123583D03*
Y137756D03*
X136604Y450750D03*
X140703Y536382D03*
X145670Y597580D03*
X147893Y599588D03*
X147155Y589556D03*
X147094Y592354D03*
X145609Y594668D03*
X147896Y596095D03*
X147925Y615600D03*
X147893Y607588D03*
X139836Y997860D03*
X147836D03*
X143836D03*
X135836D03*
X145516Y1024954D03*
Y1012354D03*
X148534Y1046476D03*
X134457Y1180654D03*
X141490Y1345691D03*
Y1350683D03*
X136534D03*
Y1345691D03*
X148774Y1350683D03*
Y1345691D03*
X141490Y1357603D03*
Y1362595D03*
X136534D03*
Y1357603D03*
X148774D03*
Y1362595D03*
X141490Y1369889D03*
Y1374881D03*
Y1381801D03*
X136534Y1369889D03*
Y1381801D03*
Y1374881D03*
X148774Y1369889D03*
Y1381801D03*
Y1374881D03*
X141490Y1386793D03*
Y1394087D03*
Y1399079D03*
X136534D03*
Y1394087D03*
Y1386793D03*
X148774Y1394087D03*
Y1399079D03*
Y1386793D03*
X141490Y1405999D03*
Y1410991D03*
X136534D03*
Y1405999D03*
X148774D03*
Y1410991D03*
X142315Y1456451D03*
Y1461182D03*
Y1465913D03*
Y1471805D03*
Y1476536D03*
Y1481267D03*
Y1487159D03*
Y1491890D03*
Y1496621D03*
Y1507245D03*
Y1502514D03*
Y1511976D03*
Y1558813D03*
Y1563544D03*
Y1574167D03*
Y1578898D03*
Y1568275D03*
Y1589522D03*
Y1594253D03*
Y1583629D03*
Y1609607D03*
Y1604876D03*
Y1598984D03*
Y1614338D03*
X151366Y92849D03*
X158460Y116496D03*
X158326Y103037D03*
X158460Y109410D03*
Y130670D03*
Y123583D03*
X155051Y137756D03*
X163141Y293796D03*
X160641D03*
X166528Y312392D03*
X157375Y555234D03*
X157090Y562003D03*
X152386Y634946D03*
X151836Y997860D03*
X159836D03*
X164028Y1041468D03*
X155513Y1065148D03*
X161014Y1345691D03*
Y1350683D03*
X153730Y1345691D03*
Y1350683D03*
X165970Y1345691D03*
Y1350683D03*
X161014Y1362595D03*
Y1357603D03*
X153730Y1362595D03*
Y1357603D03*
X165970Y1362595D03*
Y1357603D03*
X161014Y1381801D03*
Y1369889D03*
Y1374881D03*
X153730Y1369889D03*
Y1381801D03*
Y1374881D03*
X165970D03*
Y1381801D03*
Y1369889D03*
X161014Y1394087D03*
Y1386793D03*
X153730Y1394087D03*
Y1386793D03*
X165970Y1394087D03*
Y1386793D03*
X161014Y1399079D03*
X153730D03*
X165970D03*
X161014Y1410991D03*
Y1405999D03*
X153730D03*
Y1410991D03*
X165970D03*
Y1405999D03*
X159637Y1461182D03*
X150976Y1465513D03*
Y1460782D03*
X159637Y1465913D03*
Y1456451D03*
X150976Y1476136D03*
Y1470244D03*
Y1480867D03*
X159637Y1471805D03*
Y1476536D03*
Y1481267D03*
Y1496621D03*
X150976Y1491490D03*
Y1485598D03*
Y1496221D03*
X159637Y1487159D03*
Y1491890D03*
X150976Y1500952D03*
Y1511576D03*
X159637Y1507245D03*
Y1502514D03*
Y1511976D03*
X150976Y1506845D03*
Y1516307D03*
X159637Y1558813D03*
Y1563544D03*
X150976Y1563144D03*
X159637Y1578898D03*
X150976Y1567875D03*
Y1578498D03*
Y1572606D03*
X159637Y1568275D03*
Y1574167D03*
X150976Y1583229D03*
Y1593853D03*
Y1587960D03*
X159637Y1583629D03*
Y1589522D03*
Y1594253D03*
X150976Y1609207D03*
Y1598584D03*
Y1603315D03*
X159637Y1609607D03*
Y1604876D03*
Y1598984D03*
X150976Y1613938D03*
Y1618669D03*
X159637Y1614338D03*
X152000Y1644980D03*
X179743Y94017D03*
X175743D03*
X171743D03*
X175871Y110445D03*
X180863Y115401D03*
Y110445D03*
X175871Y115401D03*
X180863Y129574D03*
Y124618D03*
X175871Y129574D03*
Y124618D03*
X173784Y151540D03*
X177434Y191941D03*
X177301Y188727D03*
X171258Y226141D03*
X174058D03*
X179128Y256535D03*
X173955Y285690D03*
Y288190D03*
X171155Y285690D03*
X168655Y288190D03*
X171155D03*
X168655Y285690D03*
X182181Y290755D03*
X178181D03*
X177369Y389154D03*
Y396240D03*
Y403327D03*
Y410413D03*
Y417500D03*
Y424587D03*
Y431673D03*
Y438760D03*
Y445847D03*
Y467539D03*
Y474626D03*
Y488799D03*
Y481713D03*
Y495886D03*
Y511673D03*
Y518760D03*
Y525847D03*
Y532933D03*
Y540020D03*
Y547106D03*
X176650Y602197D03*
X177114Y595108D03*
X173254Y1345691D03*
Y1350683D03*
X178210Y1345691D03*
Y1350683D03*
X173254Y1362595D03*
Y1357603D03*
X178210D03*
Y1362595D03*
X173254Y1374881D03*
Y1369889D03*
Y1381801D03*
X178210Y1374881D03*
Y1369889D03*
Y1381801D03*
X173254Y1394087D03*
Y1386793D03*
X178210Y1394087D03*
Y1386793D03*
X173254Y1399079D03*
X178210D03*
X173254Y1405999D03*
Y1410991D03*
X178210Y1405999D03*
Y1410991D03*
X168299Y1465513D03*
Y1460782D03*
X176960Y1465914D03*
Y1456452D03*
Y1461183D03*
X168299Y1476136D03*
Y1470244D03*
Y1480867D03*
X176960Y1476537D03*
Y1471806D03*
Y1481268D03*
X168299Y1491490D03*
Y1485598D03*
Y1496221D03*
X176960Y1491891D03*
Y1487160D03*
Y1496622D03*
Y1507246D03*
Y1502515D03*
X168299Y1506845D03*
Y1500952D03*
Y1511576D03*
X176960Y1511977D03*
X168299Y1516307D03*
Y1563144D03*
X176960Y1563544D03*
Y1558813D03*
Y1568275D03*
X168299Y1578498D03*
Y1572606D03*
Y1567875D03*
Y1583229D03*
X176960Y1583629D03*
X168299Y1593853D03*
Y1587960D03*
X176960Y1594253D03*
Y1589522D03*
X168299Y1609207D03*
Y1598584D03*
Y1603315D03*
X176960Y1609607D03*
Y1598984D03*
Y1604876D03*
X168299Y1613938D03*
Y1618669D03*
X176960Y1614338D03*
X172000Y1644980D03*
X188820Y80140D03*
Y84140D03*
Y76140D03*
X183752Y94017D03*
X186273Y117557D03*
X191265D03*
X186273Y131731D03*
Y122513D03*
X191265D03*
Y131731D03*
X189364Y146461D03*
X186273Y136687D03*
X191265D03*
X188266Y152367D03*
X194649Y180527D03*
X189966Y180572D03*
X198372Y192421D03*
X189966Y185165D03*
X194604Y185121D03*
X183934Y184619D03*
X185914Y206760D03*
X187128Y256535D03*
X188158Y279208D03*
X192262Y281307D03*
X186181Y290755D03*
X191988Y389154D03*
X190518Y396240D03*
X194603Y422864D03*
X195295Y414823D03*
X194673Y429832D03*
X194278Y436447D03*
X196313Y447953D03*
X195480Y467539D03*
X194222Y472772D03*
X194956Y487711D03*
X195069Y479104D03*
X195480Y495886D03*
X190829Y516841D03*
X194080Y510565D03*
X185654Y552872D03*
X185776Y550123D03*
X185099Y562443D03*
X186867Y560675D03*
X187408Y572334D03*
X185640Y574102D03*
X193723Y656942D03*
X185494Y1345597D03*
Y1350683D03*
X190450Y1345597D03*
Y1350683D03*
X197734Y1345691D03*
Y1350683D03*
X185494Y1362595D03*
Y1357603D03*
X197734Y1362595D03*
Y1357603D03*
X190450Y1362595D03*
Y1357603D03*
X185494Y1374881D03*
Y1381801D03*
Y1369889D03*
X197734D03*
Y1381801D03*
Y1374881D03*
X190450Y1369889D03*
Y1374881D03*
Y1381801D03*
X185494Y1393993D03*
Y1386793D03*
X190450Y1393993D03*
Y1386793D03*
X197734Y1394087D03*
Y1386793D03*
X185494Y1399079D03*
X190450D03*
X197734D03*
X185494Y1410991D03*
Y1405999D03*
X190450Y1410991D03*
Y1405999D03*
X197734D03*
Y1410991D03*
X185622Y1465513D03*
Y1460782D03*
Y1480868D03*
Y1476137D03*
Y1470244D03*
Y1485599D03*
X192000Y1644980D03*
X211262Y60922D03*
X206398Y55513D03*
X208463Y96472D03*
X202195Y117261D03*
X209726Y113394D03*
Y110394D03*
X212375Y110784D03*
X211969Y133298D03*
X214116Y134579D03*
X209902Y172665D03*
Y180665D03*
X209934Y200864D03*
Y212864D03*
Y216864D03*
Y221864D03*
X211691Y252371D03*
X215380Y389153D03*
X210580D03*
X215380Y396240D03*
X208080Y403327D03*
X215380Y403326D03*
X210580D03*
X208080Y410413D03*
X210580D03*
X215380D03*
X208080Y396240D03*
X210580D03*
X208080Y417500D03*
X215380Y417499D03*
X210580D03*
X208080Y424586D03*
X210580D03*
X215380D03*
X208080Y431673D03*
Y438760D03*
X210580D03*
X215380D03*
Y431673D03*
X210580D03*
X208080Y445847D03*
X215380Y467539D03*
X210580D03*
X208080Y474626D03*
X210580D03*
X215380D03*
Y488799D03*
X208080D03*
X210580D03*
Y481712D03*
X208080D03*
X215380D03*
X208080Y495886D03*
X215380Y518760D03*
X210580D03*
X208080D03*
X210580Y511673D03*
X215380D03*
X210580Y532933D03*
X208080D03*
Y540020D03*
Y525846D03*
X210580D03*
X215380D03*
Y532933D03*
X212460Y560500D03*
X209429Y625300D03*
X202690Y1345597D03*
Y1350683D03*
Y1362595D03*
Y1357603D03*
Y1369889D03*
Y1381801D03*
Y1374881D03*
Y1394087D03*
Y1386793D03*
Y1399079D03*
Y1405999D03*
Y1410991D03*
X211473Y1446675D03*
X213296Y1438215D03*
X211473Y1451631D03*
Y1462631D03*
Y1457675D03*
X224961Y109172D03*
X226968Y106495D03*
X230712Y116497D03*
X227961Y109172D03*
X230712Y123584D03*
Y130670D03*
X219969Y133298D03*
X228608Y141228D03*
X230712Y137757D03*
X226702Y146012D03*
X231496Y150847D03*
X226173Y253198D03*
X228760Y316122D03*
X223925Y543925D03*
X224500Y555000D03*
X222646Y607542D03*
X217945Y1423924D03*
X217799Y1433684D03*
X216465Y1446675D03*
X222253Y1438483D03*
X216465Y1451631D03*
Y1462631D03*
Y1457675D03*
X229260Y1469587D03*
X218171Y1474460D03*
X224176Y1492816D03*
X223235Y1506770D03*
X222908Y1502028D03*
X226957Y1510442D03*
X216342Y1515642D03*
X217519Y1537172D03*
X242712Y116496D03*
Y109410D03*
Y102323D03*
X238012Y116497D03*
X235512D03*
X238012Y109410D03*
Y123583D03*
Y130670D03*
X235512D03*
X242712D03*
Y123583D03*
X235512Y123584D03*
Y137757D03*
X242712Y137756D03*
X233464Y247292D03*
X236349Y339428D03*
X247333Y599506D03*
X241967Y616063D03*
X243078Y636486D03*
X240249Y628328D03*
X241084Y638243D03*
X246583Y665140D03*
X241850Y678462D03*
X247600Y848500D03*
X240845Y1345691D03*
Y1350683D03*
X245801Y1345691D03*
Y1350683D03*
X240845Y1357603D03*
Y1362595D03*
X245801Y1357603D03*
Y1362595D03*
X240845Y1381801D03*
Y1374881D03*
Y1369889D03*
X245801Y1381801D03*
Y1374881D03*
Y1369889D03*
X240845Y1386793D03*
X245801D03*
X232675Y1466801D03*
X240466Y1503857D03*
X243268Y1501903D03*
X237700Y1531600D03*
X251174Y77784D03*
Y80384D03*
Y82984D03*
Y75184D03*
Y85584D03*
X253728Y92849D03*
X260688Y103037D03*
X260822Y116496D03*
Y109410D03*
Y130670D03*
Y123583D03*
X257413Y137756D03*
X263003Y293796D03*
X257226Y312081D03*
X265011Y403307D03*
X255000Y427017D03*
X254692Y431029D03*
X253758Y435029D03*
X254678Y449873D03*
X261605Y465492D03*
Y472579D03*
X259105D03*
X254305D03*
X261605Y486752D03*
X254305D03*
X259105Y479666D03*
X261605D03*
X254305D03*
X259105Y486752D03*
X254305Y493839D03*
X259105D03*
X261605Y516713D03*
X259105D03*
Y523800D03*
X261605D03*
X254305D03*
Y516713D03*
X261605Y509626D03*
Y530886D03*
X259105D03*
Y537973D03*
X254305Y530886D03*
Y537973D03*
Y566752D03*
X261605Y559665D03*
Y566752D03*
X259105D03*
X261605Y588012D03*
X259105Y588013D03*
X254305Y573839D03*
X261605D03*
X259105D03*
X261605Y580926D03*
X259105D03*
X254305D03*
Y588013D03*
X259105Y602186D03*
X254305D03*
Y595099D03*
X259105D03*
X261605D03*
Y602185D03*
X254305Y609272D03*
X259105D03*
X261605D03*
X259105Y616359D03*
X254305D03*
X248984Y638125D03*
X258867Y680499D03*
X258041Y1350683D03*
Y1345691D03*
X253085Y1350683D03*
Y1345691D03*
X258041Y1362595D03*
X253085D03*
X258041Y1357603D03*
X253085D03*
X258041Y1381801D03*
Y1369795D03*
Y1374881D03*
X253085Y1381801D03*
Y1369795D03*
Y1374881D03*
Y1393993D03*
Y1399079D03*
X258041Y1386793D03*
Y1399079D03*
Y1393993D03*
X253085Y1386793D03*
X258041Y1405999D03*
Y1410991D03*
X253085Y1405999D03*
Y1410991D03*
X248042Y1532900D03*
X274105Y94017D03*
X278105D03*
X278233Y115401D03*
Y110445D03*
Y129574D03*
Y124618D03*
X276146Y151540D03*
X279796Y191941D03*
X279663Y188727D03*
X276420Y226141D03*
X273620D03*
X276317Y288190D03*
X273517Y285690D03*
X271017Y288190D03*
X273517D03*
X271017Y285690D03*
X265503Y293796D03*
X276317Y285690D03*
X274425Y390500D03*
X265011Y410394D03*
X266405Y451319D03*
Y458406D03*
Y465492D03*
X266229Y462264D03*
X266405Y472579D03*
Y479665D03*
Y486752D03*
Y493839D03*
Y523799D03*
Y516713D03*
Y509626D03*
Y530886D03*
Y537973D03*
Y566752D03*
Y559665D03*
Y580926D03*
Y588012D03*
Y573839D03*
Y602185D03*
Y595099D03*
Y609272D03*
Y616358D03*
X269700Y884600D03*
X269900Y914200D03*
X270100Y946500D03*
X277565Y1350683D03*
Y1345691D03*
X265325D03*
Y1350683D03*
X270281Y1345691D03*
Y1350683D03*
X277565Y1362595D03*
X265325D03*
X270281D03*
X277565Y1357603D03*
X265325D03*
X270281D03*
X277565Y1381801D03*
Y1374881D03*
Y1369889D03*
X265325D03*
Y1374881D03*
Y1381801D03*
X270281Y1369889D03*
Y1374881D03*
Y1381801D03*
X277565Y1386793D03*
Y1394087D03*
Y1399079D03*
X265325Y1394087D03*
Y1399079D03*
Y1386793D03*
X270281Y1399079D03*
Y1394087D03*
Y1386793D03*
X265325Y1405999D03*
Y1410991D03*
X270281Y1405999D03*
Y1410991D03*
X277565Y1405999D03*
Y1410991D03*
X272000Y1644980D03*
X291182Y84140D03*
Y80140D03*
Y76140D03*
X282105Y94017D03*
X286114D03*
X288635Y117557D03*
X283225Y115401D03*
Y110445D03*
X293627Y117557D03*
X288635Y131731D03*
Y122513D03*
X283225Y129574D03*
Y124618D03*
X293627Y122513D03*
Y131731D03*
X291726Y146461D03*
X293627Y136687D03*
X288635D03*
X290628Y152367D03*
X292328Y180572D03*
Y185165D03*
X286296Y184619D03*
X288276Y206760D03*
X281490Y256535D03*
X289490D03*
X290520Y279208D03*
X294624Y281307D03*
X284543Y290755D03*
X280543D03*
X288543D03*
X284075Y381500D03*
X284482Y460250D03*
X284516Y465492D03*
X282247Y470136D03*
X284516Y472579D03*
Y479665D03*
Y486752D03*
Y493839D03*
Y516713D03*
Y509626D03*
X283377Y532756D03*
X283456Y525483D03*
X280976Y537973D03*
X284516Y559665D03*
Y566752D03*
X284366Y579978D03*
X284516Y573839D03*
X284580Y608117D03*
X282521Y1345691D03*
X289805Y1350683D03*
Y1345691D03*
X294761Y1350683D03*
Y1345691D03*
X282521Y1350683D03*
X289805Y1362595D03*
X294761D03*
X282521D03*
X289805Y1357603D03*
X294761D03*
X282521D03*
X289805Y1374881D03*
Y1369889D03*
Y1381801D03*
X294761Y1374881D03*
Y1369889D03*
Y1381801D03*
X282521D03*
Y1374881D03*
Y1369889D03*
X289805Y1394087D03*
Y1399079D03*
Y1386793D03*
X294761Y1394087D03*
Y1399079D03*
Y1386793D03*
X282521D03*
Y1399079D03*
Y1394087D03*
X289805Y1405999D03*
Y1410991D03*
X294761Y1405999D03*
Y1410991D03*
X282521Y1405999D03*
Y1410991D03*
X280897Y1465913D03*
X289558Y1465513D03*
X280897Y1461182D03*
X289558Y1460782D03*
X280897Y1456451D03*
X289558Y1480867D03*
X280897Y1476536D03*
X289558Y1476136D03*
Y1470244D03*
X280897Y1471805D03*
Y1481267D03*
Y1491890D03*
X289558Y1491490D03*
Y1485598D03*
X280897Y1487159D03*
Y1496621D03*
X289558Y1496221D03*
X280897Y1507245D03*
X289558Y1506845D03*
Y1500952D03*
X280897Y1502514D03*
X289558Y1511576D03*
X280897Y1511976D03*
X289558Y1516307D03*
X280897Y1563544D03*
X289558Y1563144D03*
X280897Y1558813D03*
Y1574167D03*
Y1568275D03*
X289558Y1567875D03*
X280897Y1578898D03*
X289558Y1578498D03*
Y1572606D03*
Y1593853D03*
Y1587960D03*
X280897Y1589522D03*
Y1583629D03*
X289558Y1583229D03*
X280897Y1594253D03*
Y1609607D03*
X289558Y1609207D03*
X280897Y1598984D03*
X289558Y1598584D03*
Y1603315D03*
X280897Y1604876D03*
Y1614338D03*
X289558Y1613938D03*
Y1618669D03*
X292000Y1644980D03*
X308760Y55513D03*
X310882Y96613D03*
X305953Y91951D03*
X312088Y113394D03*
X304557Y117261D03*
X297011Y180527D03*
X312264Y172665D03*
Y180665D03*
X299759Y190285D03*
X296966Y185121D03*
X312296Y212864D03*
Y200864D03*
Y221864D03*
Y216864D03*
X306812Y342319D03*
X309258Y389912D03*
Y393924D03*
Y385912D03*
Y409924D03*
Y405924D03*
Y401924D03*
X306673Y418838D03*
X298507Y445908D03*
X302457Y445787D03*
X302045Y1345691D03*
Y1350683D03*
X307001D03*
Y1345691D03*
X302045Y1362595D03*
X307001D03*
X302045Y1357603D03*
X307001D03*
X302045Y1374881D03*
Y1381801D03*
Y1369889D03*
X307001Y1374881D03*
Y1369889D03*
Y1381801D03*
X302045Y1386793D03*
Y1394087D03*
Y1399079D03*
X307001Y1386793D03*
Y1399079D03*
Y1394087D03*
X302045Y1405999D03*
Y1410991D03*
X307001Y1405999D03*
Y1410991D03*
X298220Y1465913D03*
Y1456451D03*
Y1461182D03*
X306881Y1465513D03*
Y1460782D03*
Y1470244D03*
Y1480867D03*
X298220Y1471805D03*
Y1476536D03*
Y1481267D03*
X306881Y1476136D03*
X298220Y1487159D03*
Y1491890D03*
Y1496621D03*
X306881Y1491490D03*
Y1485598D03*
Y1496221D03*
X298220Y1507245D03*
Y1502514D03*
X306881Y1506845D03*
Y1500952D03*
Y1511576D03*
X298220Y1511976D03*
X306881Y1516307D03*
X298220Y1558813D03*
Y1563544D03*
X306881Y1563144D03*
X298220Y1568275D03*
X306881Y1567875D03*
X298220Y1574167D03*
Y1578898D03*
X306881Y1578498D03*
Y1572606D03*
X298220Y1583629D03*
X306881Y1583229D03*
X298220Y1589522D03*
Y1594253D03*
X306881Y1593853D03*
Y1587960D03*
Y1598584D03*
Y1603315D03*
X298220Y1609607D03*
Y1604876D03*
Y1598984D03*
X306881Y1609207D03*
X298220Y1614338D03*
X306881Y1613938D03*
Y1618669D03*
X312000Y1644980D03*
X313624Y60922D03*
X327323Y109172D03*
X314737Y110784D03*
X314854Y130898D03*
X322331Y133298D03*
X329064Y146012D03*
X316478Y134579D03*
X328535Y253198D03*
X314053Y252371D03*
X323882Y303839D03*
X315904Y336324D03*
X320483Y353506D03*
X319241Y1350683D03*
Y1345691D03*
X314285D03*
Y1350683D03*
X326525Y1345691D03*
Y1350683D03*
X319241Y1362595D03*
X314285D03*
X326525D03*
X319241Y1357603D03*
X314285D03*
X326525D03*
X319241Y1374881D03*
Y1381801D03*
Y1369889D03*
X314285Y1374881D03*
Y1381801D03*
Y1369889D03*
X326525Y1381801D03*
Y1369889D03*
Y1374881D03*
X319241Y1386793D03*
Y1399079D03*
Y1394087D03*
X314285Y1386793D03*
Y1399079D03*
Y1394087D03*
X326525Y1399079D03*
Y1394087D03*
Y1386793D03*
X319241Y1410991D03*
Y1405999D03*
X314285Y1410991D03*
Y1405999D03*
X326525Y1410991D03*
Y1405999D03*
X315543Y1465913D03*
Y1456451D03*
Y1461182D03*
X324204Y1465513D03*
Y1460782D03*
Y1480867D03*
X315543Y1471805D03*
Y1476536D03*
Y1481267D03*
X324204Y1476136D03*
Y1470244D03*
X315543Y1487159D03*
Y1491890D03*
Y1496621D03*
X324204Y1491490D03*
Y1485598D03*
Y1496221D03*
Y1500952D03*
Y1511576D03*
X315543Y1507245D03*
Y1502514D03*
Y1511976D03*
X324204Y1506845D03*
Y1516307D03*
X315543Y1558813D03*
Y1563544D03*
X324204Y1563144D03*
X315543Y1574167D03*
Y1578898D03*
X324204Y1567875D03*
Y1578498D03*
Y1572606D03*
X315543Y1568275D03*
Y1583629D03*
Y1589522D03*
Y1594253D03*
X324204Y1583229D03*
Y1593853D03*
Y1587960D03*
X315543Y1609607D03*
Y1604876D03*
Y1598984D03*
X324204Y1609207D03*
Y1598584D03*
Y1603315D03*
X315543Y1614338D03*
X324204Y1613938D03*
Y1618669D03*
X329330Y106495D03*
X345074Y116496D03*
X337874Y116497D03*
X340374D03*
X345074Y109410D03*
Y102323D03*
X340374Y109410D03*
X333074Y116497D03*
X330323Y109172D03*
X337874Y130670D03*
X345074D03*
Y123583D03*
X340374D03*
X337874Y123584D03*
X333074D03*
Y130670D03*
X340374D03*
X333074Y137757D03*
X337874D03*
X330970Y141228D03*
X345074Y137756D03*
X333858Y150847D03*
X335826Y247292D03*
X338358Y554861D03*
X337564Y1018294D03*
X337629Y1186071D03*
X336901Y1196407D03*
X338765Y1350683D03*
Y1345691D03*
X331481D03*
Y1350683D03*
X343721Y1345691D03*
Y1350683D03*
X331481Y1362595D03*
X343721D03*
X338765D03*
X331481Y1357603D03*
X343721D03*
X338765D03*
X331481Y1374881D03*
Y1381801D03*
Y1369889D03*
X343721Y1381801D03*
Y1369889D03*
Y1374881D03*
X338765Y1381801D03*
Y1369889D03*
Y1374881D03*
X331481Y1399079D03*
Y1394087D03*
Y1386793D03*
X343721D03*
Y1394087D03*
Y1399079D03*
X338765Y1386793D03*
Y1394087D03*
Y1399079D03*
X331481Y1410991D03*
Y1405999D03*
X343721Y1410991D03*
Y1405999D03*
X338765Y1410991D03*
Y1405999D03*
X341527Y1460782D03*
X332865Y1465913D03*
Y1456451D03*
Y1461182D03*
X341527Y1465513D03*
Y1476136D03*
Y1470244D03*
Y1480867D03*
X332865Y1471805D03*
Y1476536D03*
Y1481267D03*
X341527Y1491490D03*
Y1485598D03*
Y1496221D03*
X332865Y1487159D03*
Y1491890D03*
Y1496621D03*
Y1511976D03*
X341527Y1506845D03*
Y1500952D03*
Y1511576D03*
X332865Y1507245D03*
Y1502514D03*
X341527Y1516307D03*
X332865Y1558813D03*
Y1563544D03*
X341527Y1563144D03*
X332865Y1578898D03*
X341527Y1567875D03*
Y1578498D03*
Y1572606D03*
X332865Y1568275D03*
Y1574167D03*
Y1583629D03*
Y1589522D03*
Y1594253D03*
X341527Y1583229D03*
Y1593853D03*
Y1587960D03*
X332865Y1598984D03*
X341527Y1609207D03*
Y1598584D03*
Y1603315D03*
X332865Y1609607D03*
Y1604876D03*
X341527Y1613938D03*
Y1618669D03*
X332865Y1614338D03*
X332000Y1644980D03*
X353536Y82984D03*
Y80384D03*
Y77784D03*
Y75184D03*
X356090Y92849D03*
X353536Y85584D03*
X359525Y137756D03*
X356423Y301288D03*
X348375Y322284D03*
X348968Y333138D03*
X359278Y491870D03*
X356778D03*
X358096Y867459D03*
X358086Y884616D03*
X357962Y898800D03*
X358024Y912085D03*
X358085Y923327D03*
X355929Y1132042D03*
X351563Y1132410D03*
X349700Y1148000D03*
X357947Y1159455D03*
X352536Y1160168D03*
X357297Y1192709D03*
X360659Y1209789D03*
X355961Y1350683D03*
X351005Y1345597D03*
Y1350683D03*
X355961Y1345597D03*
X351005Y1362595D03*
X355961D03*
X351005Y1357603D03*
X355961D03*
X351005Y1374881D03*
Y1381801D03*
Y1369889D03*
X355961Y1381801D03*
Y1374881D03*
Y1369889D03*
X351005Y1399079D03*
Y1393993D03*
Y1386793D03*
X355961D03*
Y1399079D03*
Y1393993D03*
X351005Y1410991D03*
Y1405999D03*
X355961D03*
Y1410991D03*
X350188Y1491891D03*
Y1487160D03*
Y1496622D03*
Y1507246D03*
Y1502515D03*
Y1511977D03*
X358850Y1511576D03*
Y1506845D03*
Y1516307D03*
X350188Y1563544D03*
Y1558813D03*
Y1568275D03*
Y1578898D03*
Y1574167D03*
Y1583629D03*
Y1594253D03*
Y1589522D03*
Y1604876D03*
Y1609607D03*
Y1598984D03*
Y1614338D03*
X352000Y1644980D03*
X376467Y94017D03*
X363050Y103037D03*
X363184Y116496D03*
Y109410D03*
Y130670D03*
Y123583D03*
X375982Y226141D03*
X378782D03*
X365365Y293796D03*
X367865D03*
X373379Y288190D03*
X375879Y285690D03*
X373379D03*
X375879Y288190D03*
X368057Y354184D03*
X364933Y374232D03*
X373264Y370010D03*
X366443Y472189D03*
X373504Y517954D03*
X375040Y932959D03*
X371424Y937185D03*
X367944Y946082D03*
X368657Y1146937D03*
X366133Y1162817D03*
X368661Y1182649D03*
X368917Y1195419D03*
X365029Y1214158D03*
X362735Y1211864D03*
X369839Y1218940D03*
X363245Y1345691D03*
Y1350683D03*
X368201Y1345691D03*
Y1350683D03*
X363245Y1362595D03*
X368201D03*
X363245Y1357603D03*
X368201D03*
X363245Y1369889D03*
Y1381801D03*
Y1374881D03*
X368201D03*
Y1381801D03*
Y1369889D03*
X363245Y1399079D03*
Y1394087D03*
Y1386793D03*
X368201D03*
Y1394087D03*
Y1399079D03*
X363245Y1405999D03*
Y1410991D03*
X368201D03*
Y1405999D03*
X372000Y1644980D03*
X393544Y76140D03*
Y84140D03*
Y80140D03*
X384467Y94017D03*
X388476D03*
X380467D03*
X390997Y117557D03*
X385587Y115401D03*
X380595D03*
X385587Y110445D03*
X380595D03*
X390997Y131731D03*
Y122513D03*
X385587Y129574D03*
X380595D03*
X385587Y124618D03*
X380595D03*
X390997Y136687D03*
X382158Y191941D03*
X388658Y184619D03*
X382025Y188727D03*
X390638Y206760D03*
X391852Y256535D03*
X383852D03*
X392882Y279208D03*
X378679Y285690D03*
Y288190D03*
X386905Y290755D03*
X382905D03*
X390905D03*
X392387Y337599D03*
Y342555D03*
X392444Y401949D03*
X393893Y413611D03*
X393833Y423944D03*
X393652Y482382D03*
X393746Y478382D03*
X388593Y664232D03*
X386350Y693559D03*
X391478Y690675D03*
X391614Y938651D03*
X381377Y1003008D03*
X381045Y1009444D03*
X391284Y1307238D03*
X394000Y1508100D03*
X382017Y1555700D03*
Y1547700D03*
Y1551700D03*
X392000Y1644980D03*
X408493Y117577D03*
X395989Y117557D03*
Y131731D03*
Y122513D03*
Y136687D03*
X399373Y180527D03*
X394690Y180572D03*
X403096Y192421D03*
X394690Y185165D03*
X399328Y185121D03*
X396986Y281307D03*
X409484Y314921D03*
X398951Y333711D03*
X397374Y344439D03*
X407493Y354142D03*
X394237Y370899D03*
X394944Y398949D03*
X399518Y402642D03*
X402018D03*
X396633Y423944D03*
X396693Y413611D03*
X399193D03*
X401693D03*
X401633Y423944D03*
X399133D03*
X409284Y741316D03*
X401121Y936686D03*
X409121Y939186D03*
X401121D03*
X409121Y936686D03*
X409231Y1123101D03*
X406105Y1139435D03*
X410131Y1129301D03*
X407631D03*
X409231Y1125801D03*
X406105Y1131935D03*
Y1134435D03*
Y1136935D03*
Y1141935D03*
Y1146935D03*
Y1144435D03*
X403263Y1152684D03*
X406319Y1204405D03*
Y1206905D03*
Y1211905D03*
Y1209405D03*
X397695Y1287071D03*
X399716Y1295198D03*
X408523Y1332967D03*
X404657D03*
X408937Y1351568D03*
X403981D03*
X401990Y1446807D03*
X399731Y1442755D03*
X397245Y1511640D03*
X404053Y1513673D03*
X397220Y1521207D03*
X409461Y1569560D03*
X405461D03*
X426147Y151540D03*
X414626Y180665D03*
Y172665D03*
X414658Y212864D03*
Y200864D03*
Y216864D03*
Y221864D03*
X422873Y309966D03*
X419955Y306966D03*
X414999D03*
X411984Y314921D03*
X421231Y338523D03*
Y331255D03*
Y345776D03*
X413432Y346797D03*
X416318Y367903D03*
X424479Y367859D03*
X418754Y468607D03*
X418226Y653288D03*
Y646480D03*
Y648980D03*
Y655788D03*
X425121Y936686D03*
Y939186D03*
X417121Y936686D03*
Y939186D03*
X417677Y1052215D03*
X425175Y1098767D03*
X417171Y1098887D03*
X419987Y1098518D03*
X419731Y1123101D03*
X417231D03*
X422631Y1125801D03*
X425131Y1129301D03*
X422631D03*
X420131D03*
X417631D03*
X415131D03*
X412631D03*
X420131Y1125801D03*
X417631D03*
X425131D03*
X422495Y1152713D03*
Y1155213D03*
X412095Y1152713D03*
Y1155213D03*
X422934Y1200821D03*
Y1198321D03*
X420619Y1204617D03*
Y1207117D03*
Y1209617D03*
Y1212117D03*
X411174Y1282776D03*
X418537Y1300197D03*
X423741Y1300115D03*
X413354Y1300197D03*
X425582Y1291743D03*
X423762Y1305298D03*
X413374D03*
X418558Y1310523D03*
X413395Y1310481D03*
X423721Y1310523D03*
X425283Y1373958D03*
X411147Y1474993D03*
X419818Y1474945D03*
X415241Y1492990D03*
X415095Y1502750D03*
X411353Y1519440D03*
X419467Y1519706D03*
X420279Y1525978D03*
X410626Y1525991D03*
X413461Y1569560D03*
X412000Y1644980D03*
X441727Y146461D03*
X440629Y152367D03*
X435703Y306966D03*
X430747D03*
X427829Y309966D03*
X428459Y331255D03*
X435793D03*
X428500Y345776D03*
X435793Y345738D03*
X430439Y358115D03*
X435702Y367813D03*
X430746D03*
X427782Y464026D03*
X438396Y511493D03*
X435834Y509580D03*
X431804Y536682D03*
Y539182D03*
X441832Y626193D03*
X433206Y1055498D03*
X430706D03*
Y1057998D03*
X433206D03*
Y1060498D03*
Y1062998D03*
X430706D03*
Y1060498D03*
X441359Y1123101D03*
X438233Y1139435D03*
X441359Y1125801D03*
X439759Y1129301D03*
X442259D03*
X429331Y1136935D03*
Y1134435D03*
Y1139435D03*
Y1131935D03*
X435733D03*
Y1134435D03*
Y1136935D03*
Y1139435D03*
X438233Y1131935D03*
Y1134435D03*
Y1136935D03*
X429331Y1141935D03*
X435733D03*
Y1146935D03*
Y1144435D03*
X438233Y1141935D03*
Y1146935D03*
Y1144435D03*
X437231Y1154902D03*
Y1152402D03*
X429331Y1146935D03*
Y1144435D03*
X433249Y1204405D03*
Y1209405D03*
Y1211905D03*
Y1206905D03*
X437991Y1286544D03*
X440896Y1311366D03*
X432485Y1325784D03*
X439624Y1345691D03*
Y1350683D03*
Y1357603D03*
Y1362595D03*
Y1381801D03*
Y1369889D03*
Y1374881D03*
X436002Y1382252D03*
X439624Y1386793D03*
X437675Y1550158D03*
X429784Y1548222D03*
X432000Y1644980D03*
X458454Y328963D03*
Y324007D03*
Y339755D03*
Y344711D03*
X453463Y370694D03*
X448092Y375770D03*
X443094Y491251D03*
X455104Y536582D03*
Y539082D03*
X447279Y633881D03*
X454815Y974622D03*
X448999Y994483D03*
X456210Y1004680D03*
X452319Y1000828D03*
X449731Y1000855D03*
X453710Y1018825D03*
X443091Y1022766D03*
Y1030266D03*
X450063Y1043140D03*
X449767Y1047047D03*
X457303Y1098767D03*
X452115Y1098518D03*
X446863Y1098428D03*
X449359Y1123101D03*
X451859D03*
X457259Y1129301D03*
X449759Y1125801D03*
X452259D03*
X444759Y1129301D03*
X447259D03*
X449759D03*
X452259D03*
X454759Y1125801D03*
X457259D03*
X454759Y1129301D03*
X443223Y1155213D03*
Y1152713D03*
X452623D03*
Y1155213D03*
X447549Y1204617D03*
X449864Y1198321D03*
Y1200821D03*
X447549Y1209617D03*
Y1207117D03*
Y1212117D03*
X454120Y1269498D03*
X456213Y1286776D03*
X451304Y1293045D03*
X456820Y1345691D03*
X451864D03*
Y1350683D03*
X456820D03*
X444580Y1345691D03*
Y1350683D03*
X456820Y1362595D03*
Y1357603D03*
X451864Y1362595D03*
Y1357603D03*
X444580D03*
Y1362595D03*
X456820Y1374881D03*
X451864D03*
X444580Y1369889D03*
X456820Y1369795D03*
X451864D03*
X444580Y1374881D03*
Y1381801D03*
X456820D03*
X451864D03*
X456820Y1399079D03*
X451864Y1393993D03*
Y1399079D03*
X456820Y1393993D03*
Y1386793D03*
X451864D03*
X444580D03*
X456820Y1405999D03*
X451864D03*
Y1410991D03*
X456820D03*
X454125Y1461182D03*
Y1465913D03*
Y1471805D03*
Y1481267D03*
Y1476536D03*
Y1491890D03*
Y1487159D03*
Y1496621D03*
Y1511976D03*
Y1507245D03*
Y1502514D03*
Y1558813D03*
Y1578898D03*
Y1568275D03*
Y1563544D03*
Y1574167D03*
Y1583629D03*
Y1589522D03*
Y1594253D03*
Y1609607D03*
Y1598984D03*
Y1604876D03*
Y1614338D03*
X452000Y1644980D03*
X464738Y110784D03*
X462089Y113394D03*
X472332Y133298D03*
X464332D03*
X466479Y134579D03*
X464054Y252371D03*
X461454Y336837D03*
Y331881D03*
Y347629D03*
Y352585D03*
X466375Y366365D03*
X470389Y389553D03*
X468558Y491669D03*
Y503669D03*
Y507669D03*
Y512669D03*
X462242Y809792D03*
X475032Y843252D03*
X474678Y857919D03*
X463134Y859203D03*
X460455Y867050D03*
X475046Y885952D03*
X467494Y924532D03*
X462427Y1030218D03*
X460277Y1090268D03*
Y1093068D03*
X474818Y1123101D03*
X469192Y1131935D03*
X474818Y1125801D03*
X473218Y1129301D03*
X461459Y1136935D03*
Y1134435D03*
Y1139435D03*
Y1131935D03*
X471692Y1139435D03*
Y1136935D03*
Y1134435D03*
Y1131935D03*
X469192Y1139435D03*
Y1136935D03*
Y1134435D03*
X471692Y1146935D03*
Y1141935D03*
X469192Y1144435D03*
Y1146935D03*
Y1141935D03*
X471692Y1144435D03*
X461459D03*
X462687Y1152684D03*
X468850D03*
X461459Y1141935D03*
Y1146935D03*
X463216Y1254164D03*
Y1250760D03*
Y1244055D03*
X461613Y1286776D03*
X469060Y1345691D03*
Y1350683D03*
X464104Y1345691D03*
Y1350683D03*
X469060Y1357603D03*
Y1362595D03*
X464104D03*
Y1357603D03*
Y1381801D03*
X469060D03*
X464104Y1369889D03*
X469060D03*
X464104Y1374881D03*
X469060D03*
Y1386793D03*
X464104D03*
X469060Y1399079D03*
X464104Y1394087D03*
X469060D03*
X464104Y1399079D03*
Y1405999D03*
X469060D03*
X464104Y1410991D03*
X469060D03*
X471448Y1461182D03*
X462786Y1460782D03*
X471448Y1465913D03*
X462786Y1465513D03*
X471448Y1481267D03*
X462786Y1480867D03*
X471448Y1471805D03*
Y1476536D03*
X462786Y1476136D03*
Y1470244D03*
X471448Y1496621D03*
X462786Y1496221D03*
X471448Y1491890D03*
X462786Y1491490D03*
Y1485598D03*
X471448Y1487159D03*
Y1511976D03*
Y1502514D03*
Y1507245D03*
X462786Y1511576D03*
Y1506845D03*
Y1500952D03*
Y1516307D03*
Y1563144D03*
X471448Y1558813D03*
X462786Y1578498D03*
X471448Y1574167D03*
Y1568275D03*
Y1563544D03*
X462786Y1567875D03*
Y1572606D03*
X471448Y1578898D03*
Y1594253D03*
X462786Y1593853D03*
X471448Y1589522D03*
Y1583629D03*
X462786Y1583229D03*
Y1587960D03*
X471448Y1598984D03*
X462786Y1609207D03*
Y1598584D03*
Y1603315D03*
X471448Y1609607D03*
Y1604876D03*
Y1614338D03*
X462786Y1613938D03*
Y1618669D03*
X472000Y1644980D03*
X480324Y109172D03*
X477324D03*
X479331Y106495D03*
X483075Y116497D03*
X487875D03*
X490375Y109410D03*
Y116497D03*
X483075Y130670D03*
X487875Y123584D03*
Y130670D03*
X490375Y123583D03*
Y130670D03*
X483075Y123584D03*
X479065Y146012D03*
X480971Y141228D03*
X483075Y137757D03*
X487875D03*
X483859Y150847D03*
X485827Y247292D03*
X478536Y253198D03*
X483242Y366481D03*
X483584Y375840D03*
X483736Y371266D03*
X483541Y380306D03*
X481724Y391589D03*
Y387089D03*
X488438Y425464D03*
X482532Y418464D03*
X482484Y444517D03*
X486738Y581222D03*
X489538D03*
Y591215D03*
X486738D03*
X491340Y611091D03*
X485005Y659771D03*
X491324Y667293D03*
X485303Y681841D03*
X486246Y804497D03*
X485824Y819787D03*
X481593Y826387D03*
X491453Y834546D03*
X491527Y843206D03*
X488469Y857013D03*
X481943Y924633D03*
X488388Y938903D03*
X483636Y952152D03*
X490143Y989521D03*
X476148Y1057998D03*
Y1055498D03*
X478648D03*
Y1057998D03*
X476148Y1060498D03*
Y1062998D03*
X478648D03*
Y1060498D03*
X490762Y1098767D03*
X485574Y1098518D03*
X480322Y1098428D03*
X485318Y1123101D03*
X482818D03*
X490718Y1129301D03*
X483218Y1125801D03*
X485718D03*
X475718Y1129301D03*
X478218D03*
X480718D03*
X483218D03*
X485718D03*
X488218Y1125801D03*
X490718D03*
X488218Y1129301D03*
X477682Y1152713D03*
Y1155213D03*
X488082D03*
Y1152713D03*
X479521Y1204405D03*
Y1206905D03*
Y1211905D03*
Y1209405D03*
X488584Y1345691D03*
Y1350683D03*
X481300Y1345691D03*
X476344D03*
X481300Y1350683D03*
X476344D03*
X488584Y1357603D03*
Y1362595D03*
X481300D03*
Y1357603D03*
X476344Y1362595D03*
Y1357603D03*
X488584Y1381801D03*
X481300D03*
X488584Y1374881D03*
Y1369889D03*
X481300D03*
Y1374881D03*
X476344Y1381801D03*
Y1369889D03*
Y1374881D03*
X488584Y1386793D03*
X481300D03*
Y1399079D03*
X476344Y1394087D03*
Y1399079D03*
X488584Y1394087D03*
X481300D03*
X488584Y1399079D03*
X476344Y1386793D03*
Y1410991D03*
X481300Y1405999D03*
X476344D03*
X488584D03*
Y1410991D03*
X481300D03*
X480109Y1460782D03*
Y1465513D03*
X488771Y1465913D03*
Y1461182D03*
X480109Y1476136D03*
Y1470244D03*
X488771Y1471805D03*
Y1476536D03*
Y1481267D03*
X480109Y1480867D03*
Y1496221D03*
X488771Y1487159D03*
Y1491890D03*
X480109Y1491490D03*
Y1485598D03*
X488771Y1496621D03*
Y1511976D03*
X480109Y1511576D03*
Y1506845D03*
Y1500952D03*
X488771Y1502514D03*
Y1507245D03*
X480109Y1516307D03*
X488771Y1558813D03*
X480109Y1563144D03*
X488771Y1578898D03*
X480109Y1578498D03*
X488771Y1574167D03*
Y1568275D03*
Y1563544D03*
X480109Y1567875D03*
Y1572606D03*
X488771Y1589522D03*
Y1583629D03*
X480109Y1583229D03*
Y1587960D03*
X488771Y1594253D03*
X480109Y1593853D03*
X488771Y1609607D03*
Y1604876D03*
Y1598984D03*
X480109Y1609207D03*
Y1598584D03*
Y1603315D03*
X488771Y1614338D03*
X480109Y1613938D03*
Y1618669D03*
X503537Y77784D03*
Y75184D03*
Y80384D03*
Y82984D03*
X506091Y92849D03*
X503537Y85584D03*
X495075Y116496D03*
Y102323D03*
Y109410D03*
Y130670D03*
Y123583D03*
Y137756D03*
X497424Y354559D03*
X492317Y376252D03*
X503682Y455466D03*
X497776Y448466D03*
X493929Y555194D03*
X496729D03*
X493929Y563194D03*
X496729D03*
X493929Y571194D03*
X496729D03*
X492338Y581222D03*
Y591215D03*
X494632Y654622D03*
X501618Y698355D03*
X499012Y699819D03*
X503311Y715652D03*
X500705Y705524D03*
X507546Y738539D03*
X505673Y767961D03*
X500717D03*
X504341Y812040D03*
X491655Y829173D03*
X506246Y824689D03*
X492799Y846488D03*
X503741Y846830D03*
X497467Y833027D03*
X499640Y861538D03*
X499595Y963963D03*
X493050Y976078D03*
X506566Y1000766D03*
Y1004766D03*
Y1016266D03*
Y1030766D03*
X505981Y1052487D03*
X506946Y1123101D03*
Y1125801D03*
X505346Y1129301D03*
X507846D03*
X503820Y1139435D03*
Y1136935D03*
Y1134435D03*
Y1131935D03*
X501320Y1139435D03*
Y1136935D03*
Y1134435D03*
Y1131935D03*
X494918Y1136935D03*
Y1134435D03*
Y1139435D03*
Y1131935D03*
X503820Y1144435D03*
Y1146935D03*
Y1141935D03*
X501320Y1144435D03*
Y1146935D03*
Y1141935D03*
X494918Y1146935D03*
Y1144435D03*
Y1141935D03*
X502562Y1152713D03*
Y1155213D03*
X506451Y1204405D03*
X493821Y1204617D03*
X496136Y1200821D03*
Y1198321D03*
X506451Y1206905D03*
Y1211905D03*
Y1209405D03*
X493821Y1207117D03*
Y1209617D03*
Y1212117D03*
X500824Y1350683D03*
Y1345691D03*
X505780Y1350683D03*
Y1345691D03*
X493540D03*
Y1350683D03*
X505780Y1362595D03*
Y1357603D03*
X500824Y1362595D03*
Y1357603D03*
X493540Y1362595D03*
Y1357603D03*
Y1381801D03*
Y1374881D03*
Y1369889D03*
X505780Y1381801D03*
Y1374881D03*
Y1369889D03*
X500824D03*
Y1381801D03*
Y1374881D03*
Y1394087D03*
X505780Y1399079D03*
X500824D03*
X505780Y1394087D03*
X493540Y1386793D03*
Y1394087D03*
Y1399079D03*
X505780Y1386793D03*
X500824D03*
X505780Y1410991D03*
X500824D03*
X505780Y1405999D03*
X500824D03*
X493540D03*
Y1410991D03*
X497432Y1465513D03*
X506093Y1465913D03*
X497432Y1460782D03*
X506093Y1461182D03*
X497432Y1480867D03*
X506093Y1481267D03*
X497432Y1476136D03*
Y1470244D03*
X506093Y1471805D03*
Y1476536D03*
X497432Y1496221D03*
Y1491490D03*
Y1485598D03*
X506093Y1487159D03*
Y1491890D03*
Y1496621D03*
Y1511976D03*
X497432Y1506845D03*
Y1500952D03*
X506093Y1502514D03*
Y1507245D03*
X497432Y1511576D03*
Y1516307D03*
Y1563144D03*
X506093Y1558813D03*
X497432Y1578498D03*
X506093Y1578898D03*
X497432Y1567875D03*
Y1572606D03*
X506093Y1574167D03*
Y1568275D03*
Y1563544D03*
X497432Y1587960D03*
X506093Y1589522D03*
Y1583629D03*
X497432Y1593853D03*
X506093Y1594253D03*
X497432Y1583229D03*
X506093Y1604876D03*
Y1598984D03*
X497432Y1609207D03*
X506093Y1609607D03*
X497432Y1598584D03*
Y1603315D03*
Y1613938D03*
Y1618669D03*
X506093Y1614338D03*
X492000Y1644980D03*
X513051Y103037D03*
X513185Y116496D03*
Y109410D03*
Y130670D03*
Y123583D03*
X509251Y137756D03*
X517866Y293796D03*
X515366D03*
X523380Y285690D03*
Y288190D03*
X511342Y311124D03*
X520845Y434508D03*
X516845D03*
X512845D03*
X514608Y445874D03*
X510022Y446352D03*
X523705Y444269D03*
X523583Y447201D03*
X521636Y504699D03*
X516636D03*
X519136D03*
X516338Y516979D03*
X521338D03*
X518838D03*
X512404Y629362D03*
X510215Y627948D03*
X511990Y686365D03*
X518001Y694940D03*
X522410Y694881D03*
X518067Y699378D03*
X518530Y703584D03*
X522628Y703884D03*
X508237Y723585D03*
X512502Y738539D03*
X516953Y738575D03*
X521909D03*
X520159Y758832D03*
X509063Y782867D03*
X517194Y773232D03*
X522316Y793574D03*
X509316Y793224D03*
X508130Y787488D03*
X521178Y814001D03*
X521565Y820931D03*
X520720Y846133D03*
X517832Y834558D03*
X508049Y877789D03*
X523272Y880067D03*
X509428Y888390D03*
X521115Y897500D03*
X511025Y911443D03*
X509673Y900295D03*
X516256Y939157D03*
X514886Y952189D03*
X519792Y1031271D03*
X517702Y1098518D03*
X512450Y1098428D03*
X522890Y1098767D03*
X514946Y1123101D03*
X517446D03*
X522846Y1129301D03*
X515346Y1125801D03*
X517846D03*
X510346Y1129301D03*
X512846D03*
X515346D03*
X517846D03*
X520346Y1125801D03*
X522846D03*
X520346Y1129301D03*
X518210Y1155213D03*
Y1152713D03*
X508810D03*
Y1155213D03*
X520751Y1204617D03*
X523066Y1200821D03*
Y1198321D03*
X520751Y1207117D03*
Y1209617D03*
Y1212117D03*
X513064Y1345691D03*
X518020Y1350683D03*
X513064D03*
X518020Y1345691D03*
Y1357603D03*
X513064Y1362595D03*
Y1357603D03*
X518020Y1362595D03*
X513064Y1369889D03*
Y1381801D03*
Y1374881D03*
X518020Y1369889D03*
Y1381801D03*
Y1374881D03*
Y1394087D03*
Y1399079D03*
X513064Y1394087D03*
Y1399079D03*
Y1386793D03*
X518020D03*
Y1405999D03*
Y1410991D03*
X513064D03*
Y1405999D03*
X514755Y1460782D03*
Y1465513D03*
Y1480867D03*
Y1476136D03*
Y1470244D03*
Y1491490D03*
Y1485598D03*
Y1496221D03*
Y1511576D03*
Y1506845D03*
Y1500952D03*
Y1516307D03*
Y1563144D03*
Y1567875D03*
Y1572606D03*
Y1578498D03*
Y1593853D03*
Y1583229D03*
Y1587960D03*
Y1603315D03*
Y1609207D03*
Y1598584D03*
Y1613938D03*
Y1618669D03*
X512000Y1644980D03*
X526468Y94017D03*
X534468D03*
X538477D03*
X530468D03*
X530596Y115401D03*
X535588Y110445D03*
Y115401D03*
X530596Y110445D03*
Y124618D03*
Y129574D03*
X535588Y124618D03*
Y129574D03*
X528509Y151540D03*
X538659Y184619D03*
X532159Y191941D03*
X532026Y188727D03*
X528783Y226141D03*
X525983D03*
X533853Y256535D03*
X525880Y285690D03*
X528680D03*
X525880Y288190D03*
X528680D03*
X532906Y290755D03*
X536906D03*
X540906D03*
X524206Y354119D03*
X533027Y351836D03*
X530215Y364422D03*
X535142Y397552D03*
X532936Y519544D03*
X527936D03*
X525436D03*
X530436D03*
X538826Y633450D03*
X526756Y636005D03*
Y633205D03*
X538826Y636250D03*
Y639050D03*
X526756Y638805D03*
X524653Y643595D03*
X534940Y684489D03*
X539111Y681459D03*
X526956Y694959D03*
X526951Y699443D03*
X535387Y712617D03*
X526933Y703820D03*
X532628Y720776D03*
X526276Y721339D03*
X539763Y734097D03*
X534807D03*
X531763Y739097D03*
X526807D03*
X532450Y767474D03*
X532278Y762736D03*
X531501Y792331D03*
X531260Y794934D03*
X531666Y815724D03*
X531313Y822693D03*
X527733Y847026D03*
X527346Y911458D03*
X528674Y964851D03*
X527046Y1131935D03*
Y1139435D03*
Y1134435D03*
Y1136935D03*
X528274Y1152684D03*
X527046Y1146935D03*
Y1144435D03*
Y1141935D03*
X525304Y1345691D03*
X530260D03*
X537544Y1350683D03*
X525304D03*
X530260D03*
X537544Y1345691D03*
Y1357603D03*
X525304Y1362595D03*
X530260D03*
X525304Y1357603D03*
X530260D03*
X537544Y1362595D03*
Y1374881D03*
X525304Y1369889D03*
Y1381801D03*
Y1374881D03*
X530260Y1369889D03*
Y1381801D03*
Y1374881D03*
X537544Y1369889D03*
Y1381801D03*
Y1399079D03*
Y1394087D03*
X530260D03*
Y1399079D03*
X525304Y1394087D03*
Y1399079D03*
X537544Y1386793D03*
X525304D03*
X530260D03*
X537544Y1410991D03*
Y1405999D03*
X530260D03*
X525304D03*
X530260Y1410991D03*
X525304D03*
X532000Y1644980D03*
X543545Y84140D03*
Y80140D03*
Y76140D03*
X540998Y117557D03*
X545990D03*
Y122513D03*
Y131731D03*
X540998Y122513D03*
Y131731D03*
X544089Y146461D03*
X545990Y136687D03*
X540998D03*
X542991Y152367D03*
X549374Y180527D03*
X544691Y180572D03*
X553097Y192421D03*
X549329Y185121D03*
X544691Y185165D03*
X540639Y206760D03*
X541853Y256535D03*
X542883Y279208D03*
X546987Y281307D03*
X541644Y389047D03*
X553731Y388487D03*
X541706Y381723D03*
X552905Y430829D03*
X550274Y658676D03*
X556574Y684031D03*
Y700031D03*
Y688987D03*
Y716031D03*
Y704987D03*
Y720987D03*
X552384Y762892D03*
X552188Y766577D03*
X553871Y811298D03*
X545741Y804149D03*
X548464Y823156D03*
X540807Y816556D03*
X541129Y828335D03*
Y838865D03*
X545981Y846389D03*
X549241Y841388D03*
X545237Y850319D03*
X548521Y877859D03*
Y874859D03*
X545144Y909025D03*
X544793Y899220D03*
X548215Y1006560D03*
X552923Y997860D03*
X541766Y1018368D03*
X557681Y1035088D03*
X554740Y1345597D03*
X542500Y1345691D03*
X549784Y1345597D03*
X542500Y1350683D03*
X549784D03*
X554740D03*
Y1362595D03*
Y1357603D03*
X542500Y1362595D03*
X549784D03*
X542500Y1357603D03*
X549784D03*
X554740Y1381801D03*
Y1374881D03*
X542500D03*
X549784Y1369889D03*
Y1381801D03*
Y1374881D03*
X542500Y1369889D03*
Y1381801D03*
X554740Y1369889D03*
Y1399079D03*
Y1393993D03*
X542500Y1399079D03*
X549784Y1393993D03*
Y1399079D03*
X542500Y1394087D03*
X554740Y1386793D03*
X549784D03*
X542500D03*
X554740Y1410991D03*
Y1405999D03*
X542500Y1410991D03*
X549784D03*
X542500Y1405999D03*
X549784D03*
X552000Y1644980D03*
X566287Y60922D03*
X561123Y55513D03*
X563224Y96813D03*
X558316Y91951D03*
X556920Y117261D03*
X567100Y110784D03*
X564451Y113394D03*
X567290Y130898D03*
X568841Y134579D03*
X564627Y180665D03*
Y172665D03*
X569969Y195176D03*
X564659Y212864D03*
Y200864D03*
X569829Y203393D03*
X564659Y221864D03*
Y216864D03*
X566416Y252371D03*
X570634Y375453D03*
X559074Y696987D03*
Y692031D03*
Y712987D03*
Y708031D03*
X561886Y728138D03*
X559625Y739609D03*
X557813Y747814D03*
X570578Y749800D03*
X570695Y767052D03*
X564276Y776701D03*
X558241Y796389D03*
X569186Y787332D03*
X561401Y811242D03*
X567316Y806224D03*
X561061Y803606D03*
X563099Y829943D03*
X567316Y827724D03*
X559741Y822149D03*
X572171Y842346D03*
X559196Y846296D03*
X569577Y886913D03*
X560814Y901022D03*
X564923Y997860D03*
X560923D03*
X568923D03*
X556923D03*
X571857Y1009354D03*
X565451Y1035102D03*
X569520Y1102091D03*
X560211D03*
X566020D03*
X569520Y1114691D03*
X566020D03*
X560211D03*
X569520Y1139891D03*
X566020D03*
X560211D03*
X566020Y1127291D03*
X560211D03*
X569520D03*
X566020Y1152491D03*
X560211D03*
X569520D03*
X566020Y1165091D03*
X560211D03*
X569520D03*
X560211Y1177691D03*
X566020D03*
X569520D03*
X566502Y1202103D03*
X569882Y1223749D03*
X562024Y1350683D03*
Y1345691D03*
X566980D03*
Y1350683D03*
X562024Y1357603D03*
X566980D03*
Y1362595D03*
X562024D03*
Y1369889D03*
Y1381801D03*
Y1374881D03*
X566980Y1369889D03*
Y1381801D03*
Y1374881D03*
Y1399079D03*
Y1394087D03*
X562024Y1399079D03*
Y1394087D03*
X566980Y1386793D03*
X562024D03*
X566980Y1410991D03*
X562024D03*
X566980Y1405999D03*
X562024D03*
X565600Y1530800D03*
X569349Y1541947D03*
X560635Y1543531D03*
X566800Y1541800D03*
X582686Y109172D03*
X579686D03*
X581693Y106495D03*
X585437Y116497D03*
X574694Y133298D03*
X585437Y123584D03*
Y130670D03*
X581427Y146012D03*
X583333Y141228D03*
X585437Y137757D03*
X586221Y150847D03*
X588189Y247292D03*
X580898Y253198D03*
X581487Y336676D03*
X573805Y728301D03*
X574620Y772724D03*
X584624Y781850D03*
X581001Y814123D03*
X579758Y817753D03*
X579827Y884000D03*
X579251Y903364D03*
X582706Y908959D03*
X580923Y997860D03*
X576923D03*
X588923D03*
X577666Y1009354D03*
X581166D03*
X572923Y997860D03*
X584923D03*
X581166Y1021954D03*
X577666D03*
X578298Y1215195D03*
X584024Y1209607D03*
X587689Y1505724D03*
X583661Y1529142D03*
X573784Y1530646D03*
X575332Y1523740D03*
X583800Y1518000D03*
X583740Y1520640D03*
X587858Y1517942D03*
X577645Y1540982D03*
X580700Y1544100D03*
X592737Y109410D03*
X590237Y116497D03*
X592737D03*
X597437Y102323D03*
Y109410D03*
Y116496D03*
Y123583D03*
Y130670D03*
X592737Y123583D03*
X590237Y123584D03*
Y130670D03*
X592737D03*
X597437Y137756D03*
X590237Y137757D03*
X590178Y309760D03*
X593690Y450750D03*
X597872Y512743D03*
X592880D03*
X597789Y536382D03*
X602756Y597580D03*
X604979Y599588D03*
X604241Y589556D03*
X604180Y592354D03*
X602695Y594668D03*
X604982Y596095D03*
X605011Y615600D03*
X604979Y607588D03*
X592238Y880612D03*
X597129Y913386D03*
X602385Y940920D03*
X596923Y997860D03*
X592923D03*
X604923D03*
X600923D03*
X602603Y1012354D03*
Y1024954D03*
X604405Y1034870D03*
X591898Y1035011D03*
X590957Y1105091D03*
Y1117691D03*
Y1130291D03*
Y1155491D03*
Y1142891D03*
Y1168091D03*
Y1180691D03*
X592978Y1514812D03*
X591858Y1523542D03*
X598800Y1546400D03*
X605899Y80384D03*
Y82984D03*
Y77784D03*
Y75184D03*
X608453Y92849D03*
X605899Y85584D03*
X615413Y103037D03*
X615547Y116496D03*
Y109410D03*
Y130670D03*
Y123583D03*
X612138Y137756D03*
X617728Y293796D03*
X620228D03*
X614461Y555234D03*
X614176Y562003D03*
X609472Y634946D03*
X612489Y941024D03*
X616923Y997860D03*
X608923D03*
X620151Y1040363D03*
X619086Y1056453D03*
X620715Y1046785D03*
X612000Y1644980D03*
X636830Y94017D03*
X628830D03*
X632830D03*
X632958Y110445D03*
Y115401D03*
Y124618D03*
Y129574D03*
X630871Y151540D03*
X634521Y191941D03*
X634388Y188727D03*
X631145Y226141D03*
X628345D03*
X636215Y256535D03*
X631042Y288190D03*
Y285690D03*
X625742Y288190D03*
X628242Y285690D03*
X625742D03*
X628242Y288190D03*
X635268Y290755D03*
X634455Y389154D03*
Y396240D03*
Y403327D03*
Y410413D03*
Y417500D03*
Y424587D03*
Y431673D03*
Y438760D03*
Y445847D03*
Y467539D03*
Y474626D03*
Y488799D03*
Y481713D03*
Y495886D03*
Y511673D03*
Y518760D03*
Y525847D03*
Y532933D03*
Y540020D03*
Y547106D03*
X633736Y602197D03*
X634200Y595108D03*
X622270Y864781D03*
X630466Y1394087D03*
X625510Y1399079D03*
Y1394087D03*
X630466Y1399079D03*
X625510Y1405999D03*
X630466D03*
X625510Y1410991D03*
X630466D03*
X636015Y1460782D03*
X627354Y1461182D03*
X636015Y1465513D03*
X627354Y1465913D03*
Y1456451D03*
X636015Y1476136D03*
X627354Y1476536D03*
X636015Y1480867D03*
X627354Y1481267D03*
Y1471805D03*
X636015Y1470244D03*
X627354Y1487159D03*
X636015Y1485598D03*
Y1491490D03*
X627354Y1491890D03*
X636015Y1496221D03*
X627354Y1496621D03*
Y1507245D03*
Y1511976D03*
X636015Y1511576D03*
X627354Y1502514D03*
X636015Y1500952D03*
Y1506845D03*
Y1516307D03*
X627354Y1558813D03*
X636015Y1563144D03*
X627354Y1563544D03*
X636015Y1567875D03*
X627354Y1568275D03*
Y1574167D03*
X636015Y1572606D03*
Y1578498D03*
X627354Y1578898D03*
X636015Y1593853D03*
X627354Y1594253D03*
X636015Y1583229D03*
X627354Y1583629D03*
Y1589522D03*
X636015Y1587960D03*
X627354Y1604876D03*
X636015Y1603315D03*
Y1598584D03*
X627354Y1598984D03*
X636015Y1609207D03*
X627354Y1609607D03*
X636015Y1618669D03*
Y1613938D03*
X627354Y1614338D03*
X632000Y1644980D03*
X645907Y76140D03*
Y84140D03*
Y80140D03*
X640839Y94017D03*
X643360Y117557D03*
X637950Y110445D03*
Y115401D03*
X648352Y117557D03*
X643360Y122513D03*
Y131731D03*
X637950Y124618D03*
Y129574D03*
X648352Y122513D03*
Y131731D03*
X646451Y146461D03*
X643360Y136687D03*
X648352D03*
X645353Y152367D03*
X647053Y180572D03*
X651736Y180527D03*
X651691Y185121D03*
X647053Y185165D03*
X641021Y184619D03*
X643001Y206760D03*
X644215Y256535D03*
X645245Y279208D03*
X649349Y281307D03*
X639268Y290755D03*
X643268D03*
X649074Y389154D03*
X647604Y396240D03*
X652381Y414823D03*
X651689Y422864D03*
X651759Y429832D03*
X651364Y436447D03*
X653399Y447953D03*
X652566Y467539D03*
X651308Y472772D03*
X652042Y487711D03*
X652155Y479104D03*
X652566Y495886D03*
X647915Y516841D03*
X651166Y510565D03*
X642862Y550123D03*
X642740Y552872D03*
X644494Y572334D03*
X642185Y562443D03*
X643953Y560675D03*
X642726Y574102D03*
X647361Y653161D03*
X648352Y645467D03*
X650958Y677843D03*
X649990Y1350683D03*
Y1345691D03*
Y1357603D03*
Y1362595D03*
Y1381801D03*
X642706Y1374881D03*
Y1381801D03*
Y1369889D03*
X649990Y1374881D03*
Y1369889D03*
X637750Y1374881D03*
Y1381801D03*
Y1369889D03*
X649990Y1399079D03*
Y1394087D03*
X642706Y1386793D03*
X649990D03*
X637750Y1399079D03*
X642706Y1394087D03*
X637750D03*
X642706Y1399079D03*
X637750Y1386793D03*
X649990Y1405999D03*
Y1410991D03*
X637750D03*
X642706D03*
Y1405999D03*
X637750D03*
X653338Y1465513D03*
X644677Y1461182D03*
Y1456451D03*
Y1465913D03*
X653338Y1460782D03*
X644677Y1476536D03*
Y1471805D03*
X653338Y1480867D03*
Y1470244D03*
Y1476136D03*
X644677Y1481267D03*
X653338Y1491490D03*
X644677Y1496621D03*
Y1491890D03*
Y1487159D03*
X653338Y1496221D03*
Y1485598D03*
X644677Y1511976D03*
X653338Y1511576D03*
Y1500952D03*
Y1506845D03*
X644677Y1502514D03*
Y1507245D03*
X653338Y1516307D03*
X644677Y1558813D03*
X653338Y1563144D03*
X644677Y1563544D03*
X653338Y1572606D03*
Y1578498D03*
X644677Y1578898D03*
Y1574167D03*
X653338Y1567875D03*
X644677Y1568275D03*
X653338Y1587960D03*
Y1593853D03*
X644677Y1594253D03*
Y1589522D03*
X653338Y1583229D03*
X644677Y1583629D03*
X653338Y1609207D03*
X644677Y1598984D03*
Y1604876D03*
Y1609607D03*
X653338Y1603315D03*
Y1598584D03*
Y1613938D03*
X644677Y1614338D03*
X653338Y1618669D03*
X652000Y1644980D03*
X668649Y60922D03*
X666209Y57297D03*
X665423Y96853D03*
X660678Y91951D03*
X659282Y117261D03*
X666813Y113394D03*
X669462Y110784D03*
X669056Y133298D03*
X666989Y172665D03*
Y180665D03*
X655459Y192421D03*
X667021Y200864D03*
Y212864D03*
Y221864D03*
Y216864D03*
X668778Y252371D03*
X667666Y389153D03*
X665166Y396240D03*
X667666D03*
X665166Y403327D03*
X667666Y403326D03*
X665166Y410413D03*
X667666D03*
Y417499D03*
X665166Y424586D03*
X667666D03*
X665166Y417500D03*
Y431673D03*
Y438760D03*
X667666D03*
Y431673D03*
X665166Y445847D03*
X667666Y467539D03*
X665166Y474626D03*
X667666D03*
X665166Y488799D03*
X667666D03*
Y481712D03*
X665166D03*
Y495886D03*
X667666Y518760D03*
X665166D03*
X667666Y511673D03*
Y532933D03*
X665166D03*
Y540020D03*
Y525846D03*
X667666D03*
X669546Y560500D03*
X655752Y668885D03*
X661776Y662981D03*
X656157Y691851D03*
X661768Y705043D03*
X654946Y1350683D03*
X662230D03*
X667186D03*
Y1345691D03*
X654946D03*
X662230D03*
X654946Y1357603D03*
Y1362595D03*
X662230Y1357603D03*
Y1362595D03*
X667186Y1357603D03*
Y1362595D03*
X662230Y1369889D03*
X667186Y1374881D03*
Y1381801D03*
Y1369889D03*
X662230Y1374881D03*
Y1381801D03*
X654946D03*
Y1369889D03*
Y1374881D03*
X667186Y1399079D03*
Y1393993D03*
X662230D03*
Y1399079D03*
X655046D03*
Y1394087D03*
X667186Y1386793D03*
X662230D03*
X654946D03*
X667186Y1410991D03*
Y1405999D03*
X662230D03*
Y1410991D03*
X655046Y1405999D03*
Y1410991D03*
X662000Y1456451D03*
Y1465913D03*
Y1461182D03*
Y1481267D03*
Y1476536D03*
Y1471805D03*
Y1496621D03*
Y1491890D03*
Y1487159D03*
Y1511976D03*
Y1502514D03*
Y1507245D03*
Y1563544D03*
Y1558813D03*
Y1568275D03*
Y1578898D03*
Y1574167D03*
Y1594253D03*
Y1589522D03*
Y1583629D03*
Y1598984D03*
Y1604876D03*
Y1609607D03*
Y1614338D03*
X682048Y109172D03*
X685048D03*
X684055Y106495D03*
X677056Y133298D03*
X671203Y134579D03*
X683789Y146012D03*
X685695Y141228D03*
X677331Y195176D03*
X676950Y198883D03*
X683260Y253198D03*
X686012Y339795D03*
X672466Y389153D03*
Y410413D03*
Y396240D03*
Y403326D03*
Y424586D03*
Y417499D03*
Y438760D03*
Y431673D03*
Y467539D03*
Y474626D03*
Y488799D03*
Y481712D03*
Y518760D03*
Y511673D03*
Y525846D03*
Y532933D03*
X681586Y555000D03*
X681011Y543925D03*
X679426Y1350683D03*
X674470Y1345691D03*
X679426D03*
X674470Y1350683D03*
Y1357603D03*
Y1362595D03*
X679426Y1357603D03*
Y1362595D03*
Y1374881D03*
X674470D03*
Y1381801D03*
X679426D03*
Y1369889D03*
X674470D03*
X679426Y1399079D03*
X674470Y1394087D03*
X679426D03*
X674470Y1399079D03*
Y1386793D03*
X679426D03*
X674470Y1405999D03*
X679426D03*
X674470Y1410991D03*
X679426D03*
X679322Y1461182D03*
Y1456451D03*
Y1465913D03*
X670661Y1460782D03*
Y1465513D03*
Y1470244D03*
Y1476136D03*
X679322Y1481267D03*
Y1476536D03*
Y1471805D03*
X670661Y1480867D03*
X679322Y1487159D03*
X670661Y1496221D03*
Y1485598D03*
Y1491490D03*
X679322Y1496621D03*
Y1491890D03*
X670661Y1500952D03*
Y1506845D03*
X679322Y1511976D03*
Y1502514D03*
Y1507245D03*
X670661Y1511576D03*
Y1516307D03*
X679322Y1558813D03*
X670661Y1563144D03*
X679322Y1563544D03*
Y1578898D03*
Y1574167D03*
Y1568275D03*
X670661Y1572606D03*
Y1578498D03*
Y1567875D03*
X679322Y1583629D03*
X670661Y1587960D03*
Y1593853D03*
Y1583229D03*
X679322Y1594253D03*
Y1589522D03*
Y1604876D03*
Y1609607D03*
X670661Y1603315D03*
Y1598584D03*
Y1609207D03*
X679322Y1598984D03*
Y1614338D03*
X670661Y1618669D03*
Y1613938D03*
X672000Y1644980D03*
X695099Y109410D03*
X687799Y116497D03*
X692599D03*
X695099D03*
X699799Y116496D03*
Y109410D03*
Y102323D03*
X687799Y123584D03*
X695099Y123583D03*
X692599Y123584D03*
X687799Y130670D03*
X692599D03*
X695099D03*
X699799Y123583D03*
Y130670D03*
X687799Y137757D03*
X692599D03*
X699799Y137756D03*
X688583Y150847D03*
X690551Y247292D03*
X700164Y636842D03*
X698936Y678462D03*
X702691Y766471D03*
Y753471D03*
X702677Y771159D03*
Y784659D03*
X698950Y1350683D03*
Y1345597D03*
X686710Y1350683D03*
X691666D03*
X686710Y1345691D03*
X691666D03*
X698950Y1362595D03*
Y1357603D03*
X686710D03*
Y1362595D03*
X691666Y1357603D03*
Y1362595D03*
X698950Y1374881D03*
Y1381801D03*
Y1369889D03*
X691666D03*
Y1374881D03*
Y1381801D03*
X686710Y1374881D03*
Y1369889D03*
Y1381801D03*
X698950Y1399079D03*
Y1394087D03*
X686710D03*
Y1399079D03*
X691666Y1394087D03*
Y1399079D03*
X698950Y1386793D03*
X691666D03*
X686710D03*
X698950Y1405999D03*
Y1410991D03*
X686710D03*
X691666D03*
X686710Y1405999D03*
X691666D03*
X696645Y1461183D03*
Y1456452D03*
Y1465914D03*
X687984Y1460782D03*
Y1465513D03*
Y1470244D03*
Y1476136D03*
X696645Y1481268D03*
Y1471806D03*
Y1476537D03*
X687984Y1480867D03*
X696645Y1491891D03*
X687984Y1496221D03*
Y1485598D03*
Y1491490D03*
X696645Y1496622D03*
Y1487160D03*
Y1511977D03*
Y1502515D03*
Y1507246D03*
X687984Y1511576D03*
Y1500952D03*
Y1506845D03*
Y1516307D03*
X696645Y1558813D03*
Y1563544D03*
X687984Y1563144D03*
X696645Y1574167D03*
Y1578898D03*
X687984Y1572606D03*
Y1578498D03*
X696645Y1568275D03*
X687984Y1567875D03*
Y1583229D03*
X696645Y1589522D03*
Y1594253D03*
X687984Y1587960D03*
Y1593853D03*
X696645Y1583629D03*
Y1598984D03*
Y1609607D03*
X687984Y1603315D03*
Y1598584D03*
Y1609207D03*
X696645Y1604876D03*
X687984Y1613938D03*
X696645Y1614338D03*
X687984Y1618669D03*
X692000Y1644980D03*
X718488Y-27642D03*
X718503Y-25127D03*
X708261Y82984D03*
Y80384D03*
Y77784D03*
Y75184D03*
X710815Y92849D03*
X708261Y85584D03*
X717775Y103037D03*
X717909Y116496D03*
Y109410D03*
Y130670D03*
Y123583D03*
X714500Y137756D03*
X713162Y434493D03*
X711764Y449873D03*
X718691Y465492D03*
Y472579D03*
X716191D03*
X711391D03*
X716191Y479666D03*
X718691D03*
X711391D03*
Y486752D03*
X716191D03*
X718691D03*
X711391Y493839D03*
X716191D03*
Y516713D03*
Y523800D03*
X718691D03*
X711391D03*
Y516713D03*
X718691D03*
Y509626D03*
Y530886D03*
X716191D03*
Y537973D03*
X711391Y530886D03*
Y537973D03*
Y566752D03*
X718691Y559665D03*
Y566752D03*
X716191D03*
X711391Y573839D03*
X718691D03*
X716191D03*
X711391Y588013D03*
X718691Y588012D03*
X716191Y588013D03*
X718691Y580926D03*
X716191D03*
X711391D03*
X716191Y602186D03*
X711391D03*
X718691Y602185D03*
Y595099D03*
X711391D03*
X716191D03*
X711391Y609272D03*
X716191D03*
X718691D03*
X716191Y616359D03*
X711391D03*
X706070Y638125D03*
X716656Y646429D03*
X703669Y665140D03*
X716350Y699477D03*
X703604Y699653D03*
X716146Y1350683D03*
X711190D03*
X716146Y1345691D03*
X711190D03*
X703906Y1350683D03*
Y1345597D03*
X716146Y1357603D03*
X711190D03*
Y1362595D03*
X716146D03*
X703906Y1357603D03*
Y1362595D03*
X716146Y1374881D03*
Y1381801D03*
Y1369889D03*
X711190D03*
Y1374881D03*
Y1381801D03*
X703906D03*
Y1369889D03*
Y1374881D03*
X716146Y1399079D03*
X711190D03*
X716146Y1393993D03*
X711190D03*
X703906Y1394087D03*
Y1399079D03*
X716146Y1386793D03*
X711190D03*
X703906D03*
X716146Y1405999D03*
X711190D03*
X716146Y1410991D03*
X711190D03*
X703906Y1405999D03*
Y1410991D03*
X712000Y1644980D03*
X721741Y-27628D03*
X721756Y-25113D03*
X724781Y-26433D03*
X735192Y94017D03*
X731192D03*
X733233Y151540D03*
X736750Y188727D03*
X730707Y226141D03*
X733507D03*
X733404Y285690D03*
X720090Y293796D03*
X722590D03*
X728104Y288190D03*
X730604Y285690D03*
X728104D03*
X730604Y288190D03*
X733404D03*
X731511Y390500D03*
X734606Y379562D03*
X722097Y410394D03*
Y403307D03*
X723491Y458406D03*
Y451319D03*
Y465492D03*
X723315Y462264D03*
X723491Y472579D03*
Y479665D03*
Y486752D03*
Y493839D03*
Y523799D03*
Y516713D03*
Y509626D03*
Y530886D03*
Y537973D03*
Y566752D03*
Y559665D03*
Y573839D03*
Y588012D03*
Y580926D03*
Y595099D03*
Y602185D03*
Y609272D03*
Y616358D03*
X734819Y646429D03*
X725318Y890354D03*
X720373Y940310D03*
X724547Y958287D03*
X723430Y1350683D03*
X728386Y1345691D03*
X723430D03*
X728386Y1350683D03*
Y1357603D03*
Y1362595D03*
X723430Y1357603D03*
Y1362595D03*
X728386Y1381801D03*
Y1374881D03*
Y1369889D03*
X723430D03*
Y1381801D03*
Y1374881D03*
X728386Y1386793D03*
X723430D03*
X728386Y1398985D03*
Y1393993D03*
X723430Y1398985D03*
Y1393993D03*
X728386Y1410897D03*
Y1405905D03*
X723430Y1410897D03*
Y1405905D03*
X732000Y1644980D03*
X748269Y84140D03*
Y76140D03*
Y80140D03*
X743201Y94017D03*
X739192D03*
X750714Y117557D03*
X745722D03*
X740312Y115401D03*
Y110445D03*
X735320D03*
Y115401D03*
X745722Y131731D03*
Y122513D03*
X740312Y129574D03*
Y124618D03*
X735320D03*
Y129574D03*
X750714Y131731D03*
Y122513D03*
Y136687D03*
X745722D03*
X748813Y146461D03*
X747715Y152367D03*
X749415Y180572D03*
Y185165D03*
X743383Y184619D03*
X736883Y191941D03*
X745363Y206760D03*
X738577Y256535D03*
X746577D03*
X747607Y279208D03*
X751711Y281307D03*
X741630Y290755D03*
X737630D03*
X745630D03*
X741161Y381500D03*
X741602Y465492D03*
X741568Y460250D03*
X739333Y470136D03*
X741602Y472579D03*
X741072Y478958D03*
X741602Y486752D03*
Y493839D03*
Y509626D03*
Y516713D03*
X738062Y537973D03*
X740542Y525483D03*
X740463Y532756D03*
X741602Y559665D03*
Y566752D03*
X741452Y579978D03*
X741602Y573839D03*
X741666Y608117D03*
X741000Y771100D03*
X738707Y987952D03*
X745673Y1007009D03*
X747910Y1345691D03*
Y1350683D03*
X735670D03*
X740626D03*
X735670Y1345691D03*
X740626D03*
X747910Y1357603D03*
Y1362595D03*
X735670Y1357603D03*
Y1362595D03*
X740626Y1357603D03*
Y1362595D03*
X747910Y1374881D03*
Y1381801D03*
Y1369889D03*
X740626Y1381801D03*
Y1369889D03*
Y1374881D03*
X735670Y1381801D03*
Y1369889D03*
Y1374881D03*
X747910Y1386793D03*
X735670Y1393993D03*
X740626D03*
Y1398985D03*
X735670D03*
X740626Y1386793D03*
X735670D03*
Y1405905D03*
Y1410897D03*
X740626Y1405905D03*
Y1410897D03*
X742655Y1445733D03*
X747590Y1627871D03*
X765847Y55513D03*
X762065Y117040D03*
X754098Y180527D03*
X757821Y192421D03*
X754053Y185121D03*
X756201Y288345D03*
Y290845D03*
X753701Y288345D03*
Y290845D03*
Y293645D03*
X756201D03*
X763898Y342319D03*
X766344Y393924D03*
Y389912D03*
Y385912D03*
X758038Y381143D03*
X766344Y409924D03*
Y405924D03*
Y401924D03*
X752341Y407148D03*
X756800Y403824D03*
X758381Y395391D03*
X759543Y445787D03*
X755593Y445908D03*
X765106Y1350683D03*
Y1345597D03*
X760150D03*
Y1350683D03*
X752866Y1345691D03*
Y1350683D03*
X765106Y1362595D03*
Y1357603D03*
X760150D03*
Y1362595D03*
X752866Y1357603D03*
Y1362595D03*
X765106Y1374881D03*
Y1381801D03*
Y1369889D03*
X760150Y1374881D03*
Y1381801D03*
Y1369889D03*
X752866Y1374881D03*
Y1381801D03*
Y1369889D03*
X765106Y1386793D03*
X760150D03*
X752866D03*
X766433Y1583713D03*
X752150Y1627871D03*
X762776Y1629415D03*
X752000Y1644980D03*
X771011Y60922D03*
X767929Y96890D03*
X771824Y110784D03*
X769175Y113394D03*
X779418Y133298D03*
X771960Y130898D03*
X773565Y134579D03*
X769351Y172665D03*
Y180665D03*
X769383Y200864D03*
Y212864D03*
Y221864D03*
Y216864D03*
X771140Y252371D03*
X780968Y303839D03*
X772990Y336324D03*
X777569Y353506D03*
X772390Y1350683D03*
X777346D03*
Y1345691D03*
X772390D03*
Y1357603D03*
Y1362595D03*
X777346Y1357603D03*
Y1362595D03*
X777114Y1442270D03*
X778045Y1622545D03*
X782289Y1620109D03*
X773822Y1627418D03*
X772000Y1644980D03*
X784410Y109172D03*
X787410D03*
X794961Y116497D03*
X797461D03*
X790161D03*
X786417Y106495D03*
X797461Y109410D03*
Y123583D03*
X794961Y123584D03*
X790161D03*
X794961Y130670D03*
X797461D03*
X790161D03*
X794961Y137757D03*
X790161D03*
X788057Y141228D03*
X786151Y146012D03*
X793221Y140296D03*
X790945Y150847D03*
X792913Y247292D03*
X785622Y253198D03*
X788522Y290304D03*
X799937Y347340D03*
X791686Y1025440D03*
X794716Y1186071D03*
X792183Y1334030D03*
Y1331230D03*
X789383Y1334030D03*
Y1331230D03*
X794506Y1411307D03*
X793723Y1468071D03*
X793564Y1642682D03*
X810623Y77784D03*
Y82984D03*
Y80384D03*
Y75184D03*
X813177Y92849D03*
X810623Y85584D03*
X802161Y116496D03*
Y109410D03*
Y102323D03*
Y130670D03*
Y123583D03*
Y137756D03*
X816364Y486870D03*
X813864D03*
X813566Y744187D03*
X812661Y810032D03*
X812980Y824166D03*
X816016Y838036D03*
X813182Y852800D03*
X814731Y889365D03*
X812811Y908162D03*
X809682Y1133284D03*
X806787Y1148000D03*
X815034Y1159455D03*
X809623Y1160168D03*
X809393Y1187252D03*
X807487Y1193019D03*
X815487D03*
X811487D03*
X817446Y1210089D03*
X800627Y1392748D03*
X800703Y1426779D03*
X811457Y1639797D03*
X820137Y103037D03*
X820271Y116496D03*
Y109410D03*
Y130670D03*
Y123583D03*
X816637Y137756D03*
X824952Y293796D03*
X822452D03*
X830466Y285690D03*
Y288190D03*
X825792Y305225D03*
X823529Y467189D03*
X830318Y674164D03*
X829784Y713939D03*
X832284Y731216D03*
X830484Y746701D03*
X819993Y754109D03*
X817500Y760000D03*
X820547Y780314D03*
X826925Y769000D03*
X820500Y777500D03*
X826925Y787000D03*
X820500Y792000D03*
X818500Y814000D03*
X820432Y800529D03*
X826925Y805000D03*
Y823000D03*
X826165Y863000D03*
X819134Y863607D03*
X829000Y852000D03*
X825686Y869496D03*
X826797Y883756D03*
X825508Y913869D03*
X822462Y915095D03*
X818347Y939610D03*
X828193Y949324D03*
X832432Y977982D03*
X832711Y993268D03*
X828385Y1120599D03*
X817006Y1133027D03*
X822006Y1130208D03*
X825744Y1146937D03*
X823220Y1162817D03*
X823487Y1193019D03*
X819487D03*
X826612Y1219254D03*
X819522Y1212164D03*
X821816Y1214458D03*
X832084Y1461072D03*
X831457Y1639797D03*
X844781Y-65613D03*
X841756Y-64293D03*
X838503Y-64307D03*
X841741Y-66808D03*
X838488Y-66822D03*
X841554Y94017D03*
X837554D03*
X845563D03*
X833554D03*
X837682Y110445D03*
Y115401D03*
X848084Y117557D03*
X842674Y115401D03*
Y110445D03*
Y129574D03*
Y124618D03*
X837682D03*
Y129574D03*
X848084Y131731D03*
Y122513D03*
Y136687D03*
X839112Y188727D03*
X839245Y191941D03*
X845745Y184619D03*
X847725Y206760D03*
X833069Y226141D03*
X835869D03*
X848939Y256535D03*
X840939D03*
X832966Y288190D03*
Y285690D03*
X835766Y288190D03*
Y285690D03*
X843992Y290755D03*
X839992D03*
X847992D03*
X835236Y533174D03*
X845729Y661263D03*
X836503Y667845D03*
X845784Y713939D03*
X848284Y731181D03*
X846484Y746701D03*
X841500Y758161D03*
Y776161D03*
Y794161D03*
Y812161D03*
X838685Y832987D03*
X845654Y895437D03*
X833870Y881860D03*
X839381Y915839D03*
X839122Y939655D03*
X843734Y1008778D03*
X848520Y1016855D03*
X850631Y84140D03*
Y80140D03*
Y76140D03*
X864006Y117261D03*
X853076Y117557D03*
Y131731D03*
Y122513D03*
Y136687D03*
X851777Y180572D03*
X856460Y180527D03*
X860183Y192421D03*
X851777Y185165D03*
X856415Y185121D03*
X849969Y279208D03*
X854073Y281307D03*
X864920Y343168D03*
X854086Y385000D03*
X858586D03*
X850733Y461382D03*
X850832Y473382D03*
X850738Y477382D03*
X850909Y482382D03*
X853900Y627700D03*
X858202Y646330D03*
X851111Y656635D03*
X856145Y677887D03*
X855646Y685230D03*
X858186Y713170D03*
X867227Y722060D03*
X849500Y761000D03*
X864575Y770500D03*
X849500Y779000D03*
X864575Y788500D03*
X849500Y797000D03*
Y815000D03*
X864575Y806500D03*
X865004Y831273D03*
X864464Y828503D03*
X864575Y824500D03*
X851782Y823720D03*
X851161Y855205D03*
X856628Y915242D03*
X864253D03*
X849600Y915266D03*
X855867Y935540D03*
X849088Y951081D03*
X852247Y1009529D03*
X849996Y1091073D03*
X850023Y1095179D03*
X863342Y1120636D03*
X855542D03*
X858142D03*
X860842D03*
X863442Y1130336D03*
X858242D03*
X855642D03*
X860942D03*
Y1139336D03*
X863442D03*
X861119Y1148080D03*
X863619D03*
X851457Y1639797D03*
X873373Y60922D03*
X868209Y55513D03*
X870395Y96738D03*
X865402Y91951D03*
X871713Y172665D03*
Y180665D03*
X871745Y200864D03*
Y212864D03*
Y216864D03*
Y221864D03*
X876246Y302754D03*
X869313Y688486D03*
X872069Y700894D03*
X876286Y686970D03*
X880501Y710611D03*
X873021Y715729D03*
X877616Y749484D03*
X873318Y744597D03*
X873250Y798750D03*
X872700Y816615D03*
X872628Y915242D03*
X880628D03*
X876481Y941126D03*
X868908Y933640D03*
X867199Y949372D03*
X869390Y978003D03*
X878004Y1224406D03*
X883142Y1259935D03*
X875700Y1299700D03*
X871457Y1639797D03*
X886011Y154100D03*
X895780Y237517D03*
Y232634D03*
X886261Y252090D03*
X885741Y261150D03*
X894844Y418983D03*
X889219Y426952D03*
X887770Y415290D03*
X890270D03*
X897344Y418983D03*
X894519Y426952D03*
X889596Y437264D03*
X896388Y437614D03*
X887096Y437264D03*
X892019Y426952D03*
X897019D03*
X882891Y536122D03*
X896449Y550863D03*
X893949Y550363D03*
X882949Y557363D03*
X887949Y608863D03*
X894449Y606363D03*
X884903Y694119D03*
X886836Y729778D03*
X889083Y780371D03*
X888545Y785528D03*
X888514Y797602D03*
X891916Y808965D03*
X882609Y994245D03*
X897056Y1091391D03*
X891055Y1095407D03*
X897056Y1095984D03*
X884906Y1102760D03*
X884890Y1098724D03*
X893190Y1208069D03*
X894887Y1227209D03*
X891003Y1292765D03*
X890738Y1311132D03*
X891457Y1639797D03*
X898813Y146461D03*
X897715Y152367D03*
X898851Y231496D03*
Y238583D03*
Y245669D03*
X910977Y238583D03*
X898851Y259843D03*
X898576Y253056D03*
X910977Y252756D03*
Y257480D03*
X898851Y274016D03*
X910977Y266929D03*
X898851D03*
X912786Y306697D03*
X901848Y307782D03*
Y312738D03*
X909417Y323302D03*
X912085Y332335D03*
X898888Y437614D03*
X906996Y530707D03*
X902459Y530755D03*
X911630Y543998D03*
X910578Y550186D03*
X909362Y555614D03*
X898156Y554812D03*
X909024Y586768D03*
X908730Y619120D03*
X913686D03*
X899898Y619040D03*
X904854D03*
X910036Y702285D03*
X910753Y715864D03*
X912864Y864189D03*
Y870488D03*
Y867338D03*
X899693Y895207D03*
X904833Y915340D03*
X912628Y928101D03*
X911355Y944909D03*
X906710Y962433D03*
X906909Y951494D03*
X909296Y1020224D03*
X909300Y1014639D03*
X901739Y1091346D03*
X897815Y1078042D03*
X901366Y1078069D03*
X901694Y1095940D03*
X911071Y1123803D03*
X905771D03*
X903171D03*
X908371D03*
X910971Y1114103D03*
X908271D03*
X903071D03*
X905671D03*
X911699Y1129488D03*
X909041Y1126328D03*
X911641D03*
X903908Y1132870D03*
X904063Y1135946D03*
X901940Y1236799D03*
Y1229899D03*
Y1232399D03*
Y1246199D03*
Y1243699D03*
Y1239299D03*
X904703Y1297398D03*
X911457Y1639797D03*
X919175Y113394D03*
X921824Y110784D03*
X921418Y133298D03*
X929418D03*
X923565Y134579D03*
X920142Y308501D03*
X926801Y323302D03*
X923902Y332411D03*
X924600Y533706D03*
X920961Y550075D03*
X915949Y563363D03*
X915712Y613792D03*
X915194Y666671D03*
X928043Y677795D03*
X917286Y679625D03*
X924932Y701051D03*
X920628Y928101D03*
X928628D03*
X916628D03*
X924628D03*
X924487Y951244D03*
X918648Y964717D03*
X915490Y969886D03*
X916749Y1080659D03*
Y1088659D03*
X917110Y1101902D03*
X927598Y1120636D03*
X924898D03*
X914661Y1132612D03*
X914299Y1129488D03*
X914241Y1126328D03*
X924919Y1130336D03*
X927619D03*
X924919Y1139336D03*
X927419D03*
X925097Y1147708D03*
X927597D03*
X927146Y1328597D03*
Y1323641D03*
X929094Y1542353D03*
Y1545353D03*
X926041Y1554503D03*
Y1551503D03*
Y1548503D03*
Y1557503D03*
Y1560503D03*
X944961Y116497D03*
X934410Y109172D03*
X936417Y106495D03*
X937410Y109172D03*
X940161Y116497D03*
Y123584D03*
X944961D03*
X940161Y130670D03*
X944961D03*
X940161Y137757D03*
X944961D03*
X936151Y146012D03*
X938057Y141228D03*
X940945Y150847D03*
X932388Y330517D03*
X932622Y336817D03*
X944694Y352192D03*
X931627Y561578D03*
Y565578D03*
X943825Y581222D03*
Y591215D03*
X935281Y677795D03*
X945626Y789761D03*
X932000Y831000D03*
X942634Y886520D03*
X933700Y887508D03*
X944839Y902400D03*
X938188Y900853D03*
X944628Y928101D03*
X932628D03*
X936628D03*
X940497D03*
X941981Y1224406D03*
X947119Y1259935D03*
X933254Y1308273D03*
X940848Y1310181D03*
X930441Y1455039D03*
Y1458039D03*
Y1464039D03*
Y1461039D03*
Y1467039D03*
X938670Y1510528D03*
X941270D03*
Y1505328D03*
X938670D03*
X940170Y1507928D03*
X943870Y1510528D03*
Y1505328D03*
X945370Y1507928D03*
X942770D03*
X935094Y1542353D03*
X932094D03*
X935094Y1545353D03*
X932094D03*
X938094Y1542353D03*
Y1545353D03*
X941094Y1542353D03*
X944094D03*
X941094Y1545353D03*
X944094D03*
X931457Y1639797D03*
X960623Y82984D03*
Y77784D03*
Y80384D03*
Y75184D03*
Y85584D03*
X947461Y116497D03*
X952161Y116496D03*
Y109410D03*
Y102323D03*
X947461Y109410D03*
Y130670D03*
X952161D03*
Y123583D03*
X947461D03*
X952161Y137756D03*
X949443Y208206D03*
X949579Y330517D03*
X949813Y336817D03*
X956863Y451466D03*
X953816Y555194D03*
X951016D03*
X953816Y571194D03*
X951016D03*
X953816Y563194D03*
X951016D03*
X946625Y581222D03*
X949425D03*
Y591215D03*
X946625D03*
X948427Y611091D03*
X957551Y698251D03*
X954023Y725336D03*
X951195Y727165D03*
X952681Y735256D03*
X956323Y748412D03*
X957474Y764426D03*
X955086Y779798D03*
X956051Y793937D03*
X947735Y824921D03*
X948935Y835800D03*
X954700Y842700D03*
X947735Y854935D03*
X953091Y857440D03*
X953217Y861440D03*
X955967Y860376D03*
X946700Y849200D03*
X950251Y874268D03*
X950291Y870240D03*
Y866240D03*
X953145Y874240D03*
X952738Y886624D03*
X953587Y902814D03*
X961479Y927643D03*
X957671Y991564D03*
X946642Y991361D03*
X961033Y1091391D03*
X948883Y1102760D03*
X948867Y1098724D03*
X955032Y1095407D03*
X961033Y1095984D03*
X957167Y1208069D03*
X958864Y1227209D03*
X949970Y1321749D03*
X952070Y1367717D03*
X949070D03*
X956238Y1455139D03*
Y1458139D03*
Y1461139D03*
Y1464139D03*
X952676Y1461039D03*
Y1464039D03*
Y1458039D03*
Y1455039D03*
X956238Y1467139D03*
Y1469902D03*
X952676Y1467039D03*
X946470Y1510528D03*
Y1505328D03*
X947094Y1545353D03*
Y1542353D03*
X951457Y1639797D03*
X963177Y92849D03*
X970137Y103037D03*
X970271Y116496D03*
Y109410D03*
Y130670D03*
Y123583D03*
X966347Y137756D03*
X974952Y293796D03*
X972452D03*
X972147Y323681D03*
X975932Y437508D03*
X971932D03*
X962769Y458466D03*
X973695Y448874D03*
X969109Y449352D03*
X978723Y504699D03*
X976223D03*
X973723D03*
X978425Y516979D03*
X973425D03*
X975925D03*
X967302Y627948D03*
X969491Y629362D03*
X963187Y667620D03*
X973138Y667621D03*
X978059Y747438D03*
X976764Y786563D03*
X964070Y807686D03*
Y813006D03*
X977218Y802178D03*
X964036Y818961D03*
X968319Y826191D03*
X976635Y835018D03*
X976800Y838011D03*
X974282D03*
X976902Y847135D03*
X971808Y851242D03*
X975925Y854783D03*
X978201Y897500D03*
X969806Y993033D03*
X965716Y1091346D03*
X965671Y1095940D03*
X967148Y1123803D03*
X969748D03*
X969648Y1114103D03*
X967048D03*
X972348Y1123803D03*
X975048D03*
X972248Y1114103D03*
X974948D03*
X970485Y1132870D03*
X967885D03*
X968874Y1145169D03*
X966374D03*
X965917Y1236799D03*
Y1229899D03*
Y1232399D03*
Y1246199D03*
Y1243699D03*
Y1239299D03*
X978727Y1284908D03*
X971467Y1509515D03*
X974067D03*
X972567Y1512115D03*
X969967D03*
X976667Y1509515D03*
X977767Y1506915D03*
X975167D03*
X969967D03*
X972567D03*
X975167Y1512115D03*
X977767D03*
X971140Y1514693D03*
X968540D03*
X973740D03*
X976340D03*
X971457Y1639797D03*
X983554Y94017D03*
X987554D03*
X991554D03*
X987682Y115401D03*
X992674D03*
Y110445D03*
X987682D03*
X992674Y124618D03*
X987682D03*
Y129574D03*
X992674D03*
X985595Y151540D03*
X989245Y191941D03*
X989112Y188727D03*
X983069Y226141D03*
X985869D03*
X990939Y256535D03*
X985766Y288190D03*
X982966D03*
X985766Y285690D03*
X982966D03*
X980466Y288190D03*
Y285690D03*
X993992Y290755D03*
X989992D03*
X979932Y437508D03*
X982792Y447269D03*
X982670Y450201D03*
X989936Y519531D03*
X987436D03*
X982436D03*
X984936D03*
X983843Y633205D03*
Y636005D03*
Y638805D03*
X984307Y748432D03*
X985030Y781204D03*
X988329Y781445D03*
X991990Y773974D03*
X984963Y785387D03*
X979313Y814316D03*
X987903Y818645D03*
X993061Y833135D03*
X979203Y837159D03*
X988820Y858903D03*
X980529Y879097D03*
X988231Y878203D03*
X984892Y868720D03*
X987790Y896596D03*
X995133Y888503D03*
X982787Y899757D03*
X988461Y1013841D03*
X980726Y1080659D03*
Y1088659D03*
X981087Y1101902D03*
X988389Y1302558D03*
X980501Y1369685D03*
X983501D03*
X979538Y1464039D03*
Y1461039D03*
Y1458039D03*
Y1455039D03*
Y1467039D03*
Y1469802D03*
X979267Y1509515D03*
X984467D03*
X981867D03*
X985567Y1512115D03*
Y1506915D03*
X980367D03*
X982967D03*
Y1512115D03*
X980367D03*
X989667Y1509515D03*
X992267D03*
X987067D03*
X988167Y1512115D03*
X990767D03*
Y1506915D03*
X988167D03*
X984140Y1514693D03*
X981540D03*
X978940D03*
X986740D03*
X989340D03*
X991457Y1639797D03*
X1005256Y-25113D03*
X1002003Y-25027D03*
X1005241Y-27628D03*
X1001988Y-27542D03*
X1008281Y-26433D03*
X1000631Y84140D03*
Y76140D03*
Y80140D03*
X995563Y94017D03*
X1003076Y117557D03*
X998084D03*
X1003076Y122513D03*
Y131731D03*
X998084Y122513D03*
Y131731D03*
X1001175Y146461D03*
X1003076Y136687D03*
X998084D03*
X1000077Y152367D03*
X1001777Y180572D03*
X1006460Y180527D03*
X1010183Y192421D03*
X1001777Y185165D03*
X1006415Y185121D03*
X995745Y184619D03*
X997725Y206760D03*
X998939Y256535D03*
X999826Y278734D03*
X1004061Y280808D03*
X997992Y290755D03*
X1004544Y318050D03*
X1004933Y314535D03*
X997921Y333654D03*
X995913Y633450D03*
Y636250D03*
Y639050D03*
X1008342Y761735D03*
X1003539Y762632D03*
X1002834Y777394D03*
X1006053Y787745D03*
X999825Y819488D03*
X1002887Y834342D03*
X1000369D03*
X1005607Y874859D03*
Y877859D03*
X1002930Y906785D03*
X1010009Y998100D03*
X1005301Y1006560D03*
X999700Y1018400D03*
X1008312Y1363533D03*
X1008452Y1376752D03*
X1008483Y1372734D03*
X1006211Y1397662D03*
X1009338Y1391597D03*
Y1388597D03*
X1002538Y1463939D03*
Y1460939D03*
Y1457939D03*
Y1454939D03*
Y1466939D03*
Y1469702D03*
X1008549Y1509815D03*
X1007049Y1507215D03*
X1011149Y1509815D03*
X1009649Y1507215D03*
Y1512415D03*
X1007049D03*
X1008222Y1514993D03*
X1005622D03*
X1010822D03*
X1023373Y60922D03*
X1018209Y55513D03*
X1020254Y97068D03*
X1014006Y117261D03*
X1021537Y113394D03*
X1024186Y110784D03*
X1024289Y130898D03*
X1025927Y134579D03*
X1021713Y180665D03*
Y172665D03*
X1026915Y203393D03*
X1021745Y212864D03*
Y200864D03*
Y221864D03*
Y216864D03*
X1023502Y252371D03*
X1013354Y323362D03*
X1013327Y327453D03*
X1013318Y333190D03*
X1022845Y340944D03*
X1013313Y339909D03*
X1015195Y428305D03*
X1015804Y760454D03*
X1026090Y770943D03*
X1019375Y783056D03*
X1018044Y793592D03*
X1015800Y807535D03*
X1014587Y802788D03*
X1025859Y802275D03*
X1020703Y833659D03*
X1021221Y848712D03*
X1025219Y842155D03*
X1025239Y845070D03*
X1022009Y997860D03*
X1018009D03*
X1026009D03*
X1014009D03*
X1014767Y1035088D03*
X1022594Y1035114D03*
X1017297Y1102091D03*
X1026606Y1102591D03*
X1023106Y1102091D03*
X1017297Y1114691D03*
X1023106D03*
X1026606D03*
X1023106Y1127291D03*
X1026606D03*
X1017297Y1139891D03*
X1023106D03*
X1026606D03*
X1017297Y1127291D03*
X1026606Y1152491D03*
X1017297D03*
X1023106D03*
X1017297Y1165091D03*
X1023106D03*
X1026606D03*
X1017297Y1177691D03*
X1023106D03*
X1026606D03*
X1022420Y1203204D03*
X1026968Y1223749D03*
X1025434Y1320606D03*
X1011829Y1347471D03*
Y1342515D03*
X1015286Y1344924D03*
X1021623Y1373216D03*
X1012338Y1388597D03*
Y1391597D03*
X1015338D03*
Y1388597D03*
X1021338D03*
Y1391597D03*
X1018338D03*
Y1388597D03*
X1027338D03*
Y1391597D03*
X1024338D03*
Y1388597D03*
X1025138Y1463839D03*
Y1460839D03*
Y1457839D03*
Y1454839D03*
Y1466839D03*
Y1469602D03*
X1013749Y1509815D03*
X1016349D03*
X1021549D03*
X1018949D03*
X1024149D03*
X1022649Y1507215D03*
X1025249D03*
X1017449D03*
X1020049D03*
X1014849D03*
X1012249D03*
X1026749Y1509815D03*
X1012249Y1512415D03*
X1014849D03*
X1025249D03*
X1022649D03*
X1020049D03*
X1017449D03*
X1013422Y1514993D03*
X1023822D03*
X1021222D03*
X1018622D03*
X1016022D03*
X1026422D03*
X1011457Y1639797D03*
X1036772Y109172D03*
X1039772D03*
X1038779Y106495D03*
X1042523Y116497D03*
X1031780Y133298D03*
X1042523Y130670D03*
Y123584D03*
X1038513Y146012D03*
X1040419Y141228D03*
X1042523Y137757D03*
X1043307Y150847D03*
X1037984Y253198D03*
X1031354Y325901D03*
X1031382Y340947D03*
X1031310Y337888D03*
X1031377Y333671D03*
X1031362Y329268D03*
X1038796Y763272D03*
X1042880Y794924D03*
X1028155Y879413D03*
X1030300Y881400D03*
X1043252Y902501D03*
X1030009Y997860D03*
X1034009D03*
X1038252Y1009354D03*
X1034752D03*
X1028943D03*
X1042009Y997860D03*
X1038009D03*
X1034752Y1021954D03*
X1038252D03*
X1043553Y1035384D03*
X1040600Y1210600D03*
X1035384Y1215195D03*
X1034513Y1333665D03*
X1042586Y1345824D03*
X1030338Y1391597D03*
Y1388597D03*
X1029349Y1509815D03*
X1027849Y1507215D03*
Y1512415D03*
X1031457Y1639797D03*
X1049823Y109410D03*
X1054523Y116496D03*
Y109410D03*
Y102323D03*
X1049823Y116497D03*
X1047323D03*
X1049823Y130670D03*
X1047323D03*
Y123584D03*
X1049823Y123583D03*
X1054523Y130670D03*
Y123583D03*
Y137756D03*
X1047323Y137757D03*
X1045275Y247292D03*
X1050777Y450750D03*
X1054876Y536382D03*
X1059843Y597580D03*
X1059782Y594668D03*
X1062098Y615600D03*
X1044112Y778835D03*
X1045744Y800835D03*
X1048328Y808166D03*
X1057961Y931919D03*
X1046009Y997860D03*
X1054009D03*
X1050009D03*
X1058009D03*
X1059689Y1012354D03*
Y1024954D03*
X1048043Y1105091D03*
Y1117691D03*
Y1130291D03*
Y1155491D03*
Y1142891D03*
Y1168091D03*
Y1180691D03*
X1051249Y1290288D03*
X1052221Y1336984D03*
X1058891Y1345691D03*
Y1350683D03*
X1053935Y1345691D03*
Y1350683D03*
X1058891Y1362595D03*
X1053935D03*
X1058891Y1357603D03*
X1053935D03*
X1058891Y1381801D03*
Y1374881D03*
Y1369889D03*
X1053935Y1381801D03*
Y1374881D03*
Y1369889D03*
X1058891Y1386793D03*
X1053935D03*
X1051457Y1639797D03*
X1071988Y-66722D03*
X1075241Y-66808D03*
X1072003Y-64207D03*
X1075256Y-64293D03*
X1062985Y82984D03*
Y75184D03*
Y77784D03*
Y80384D03*
X1065539Y92849D03*
X1062985Y85584D03*
X1072499Y103037D03*
X1072633Y116496D03*
Y109410D03*
Y130670D03*
Y123583D03*
X1069224Y137756D03*
X1074814Y293796D03*
X1061325Y339509D03*
X1060679Y360151D03*
Y364276D03*
X1071548Y555234D03*
X1071263Y562003D03*
X1062066Y599588D03*
X1061328Y589556D03*
X1061267Y592354D03*
X1062069Y596095D03*
X1062066Y607588D03*
X1066559Y634946D03*
X1066009Y997860D03*
X1062009D03*
X1074009D03*
X1070778Y1012252D03*
X1066933Y1040567D03*
X1071641Y1058029D03*
X1060172Y1050481D03*
X1071348Y1050503D03*
X1066175Y1350683D03*
Y1345691D03*
X1071131Y1350683D03*
Y1345691D03*
X1066175Y1357603D03*
Y1362595D03*
X1071131Y1357603D03*
Y1362595D03*
X1066175Y1381801D03*
Y1369795D03*
Y1374881D03*
X1071131Y1381801D03*
Y1369795D03*
Y1374881D03*
X1066175Y1393993D03*
Y1399079D03*
Y1386793D03*
X1071131Y1399079D03*
Y1393993D03*
Y1386793D03*
X1066175Y1405999D03*
Y1410991D03*
X1071131Y1405999D03*
Y1410991D03*
X1071457Y1639797D03*
X1078281Y-65613D03*
X1089916Y94017D03*
X1085916D03*
X1090044Y110445D03*
Y115401D03*
Y124618D03*
Y129574D03*
X1087957Y151540D03*
X1091607Y191941D03*
X1091474Y188727D03*
X1085431Y226141D03*
X1088231D03*
X1088128Y285690D03*
Y288190D03*
X1085328D03*
X1082828Y285690D03*
X1085328D03*
X1082828Y288190D03*
X1077314Y293796D03*
X1092354Y290755D03*
X1077602Y314060D03*
X1091542Y389154D03*
Y410413D03*
Y396240D03*
Y403327D03*
Y417500D03*
Y424587D03*
Y431673D03*
Y438760D03*
Y445847D03*
Y467539D03*
Y474626D03*
Y488799D03*
Y481713D03*
Y495886D03*
Y511673D03*
Y518760D03*
Y525847D03*
Y532933D03*
Y540020D03*
Y547106D03*
X1090823Y602197D03*
X1091287Y595108D03*
X1079809Y1034386D03*
X1090655Y1350683D03*
Y1345691D03*
X1083371D03*
Y1350683D03*
X1078415Y1345691D03*
Y1350683D03*
X1090655Y1357603D03*
Y1362595D03*
X1083371Y1357603D03*
Y1362595D03*
X1078415D03*
Y1357603D03*
X1090655Y1381801D03*
Y1374881D03*
Y1369889D03*
X1083371D03*
Y1374881D03*
Y1381801D03*
X1078415Y1369889D03*
Y1374881D03*
Y1381801D03*
X1090655Y1394087D03*
Y1399079D03*
Y1386793D03*
X1083371D03*
Y1399079D03*
Y1394087D03*
X1078415Y1386793D03*
Y1394087D03*
Y1399079D03*
X1090655Y1405999D03*
Y1410991D03*
X1083371Y1405999D03*
Y1410991D03*
X1078415Y1405999D03*
Y1410991D03*
X1092000Y1644980D03*
X1102993Y84140D03*
Y76140D03*
Y80140D03*
X1097925Y94017D03*
X1093916D03*
X1100446Y117557D03*
X1095036Y115401D03*
Y110445D03*
X1105438Y117557D03*
X1095036Y129574D03*
Y124618D03*
X1105438Y131731D03*
Y122513D03*
X1100446Y131731D03*
Y122513D03*
X1103537Y146461D03*
X1100446Y136687D03*
X1105438D03*
X1102439Y152367D03*
X1104139Y180572D03*
X1108822Y180527D03*
X1104139Y185165D03*
X1108777Y185121D03*
X1098107Y184619D03*
X1100087Y206760D03*
X1101301Y256535D03*
X1093301D03*
X1102331Y279208D03*
X1106435Y281307D03*
X1096354Y290755D03*
X1100354D03*
X1100703Y340560D03*
X1101999Y353495D03*
X1093994Y374003D03*
X1106161Y389154D03*
X1104691Y396240D03*
X1108776Y422864D03*
X1108846Y429832D03*
X1108451Y436447D03*
X1108395Y472772D03*
X1105002Y516841D03*
X1108253Y510565D03*
X1099949Y550123D03*
X1099827Y552872D03*
X1101581Y572334D03*
X1099272Y562443D03*
X1101040Y560675D03*
X1099813Y574102D03*
X1104448Y653161D03*
X1108045Y677843D03*
X1107851Y1345691D03*
X1102895Y1350683D03*
Y1345691D03*
X1107851Y1350683D03*
X1095611D03*
Y1345691D03*
X1107851Y1357603D03*
X1102895Y1362595D03*
Y1357603D03*
X1107851Y1362595D03*
X1095611Y1357603D03*
Y1362595D03*
X1107851Y1369889D03*
Y1374881D03*
Y1381801D03*
X1102895Y1374881D03*
Y1369889D03*
Y1381801D03*
X1095611D03*
Y1374881D03*
Y1369889D03*
X1107851Y1386793D03*
Y1394087D03*
Y1399079D03*
X1102895Y1386793D03*
Y1394087D03*
Y1399079D03*
X1095611D03*
Y1394087D03*
Y1386793D03*
X1107851Y1405999D03*
Y1410991D03*
X1102895Y1405999D03*
Y1410991D03*
X1095611Y1405999D03*
Y1410991D03*
X1099900Y1535700D03*
X1107620Y1606752D03*
X1123052Y57511D03*
X1122613Y97042D03*
X1116368Y117261D03*
X1123899Y113394D03*
X1124075Y180665D03*
Y172665D03*
X1112545Y192421D03*
X1124107Y200864D03*
Y212864D03*
Y216864D03*
Y221864D03*
X1123500Y329000D03*
Y339000D03*
Y334000D03*
X1124753Y389153D03*
X1122253Y396240D03*
X1124753D03*
X1122253Y403327D03*
X1124753Y403326D03*
X1122253Y410413D03*
X1124753D03*
X1109468Y414823D03*
X1122253Y424586D03*
X1124753D03*
X1122253Y417500D03*
X1124753Y417499D03*
X1122253Y438760D03*
X1124753D03*
Y431673D03*
X1122253D03*
X1110486Y447953D03*
X1122253Y445847D03*
X1109653Y467539D03*
X1124753D03*
X1122253Y474626D03*
X1124753D03*
X1122253Y488799D03*
X1124753D03*
X1109129Y487711D03*
X1109242Y479104D03*
X1124753Y481712D03*
X1122253D03*
Y495886D03*
X1109653D03*
X1124753Y518760D03*
X1122253D03*
X1124753Y511673D03*
Y532933D03*
X1122253D03*
Y540020D03*
Y525846D03*
X1124753D03*
X1118863Y662981D03*
X1112839Y668885D03*
X1113244Y691851D03*
X1118855Y705043D03*
X1115135Y1345691D03*
Y1350683D03*
X1120091Y1345691D03*
Y1350683D03*
X1115135Y1357603D03*
Y1362595D03*
X1120091Y1357603D03*
Y1362595D03*
X1115135Y1374881D03*
Y1381801D03*
Y1369889D03*
X1120091D03*
Y1374881D03*
Y1381801D03*
X1115135Y1394087D03*
Y1399079D03*
Y1386793D03*
X1120091Y1399079D03*
Y1394087D03*
Y1386793D03*
X1115135Y1405999D03*
Y1410991D03*
X1120091Y1405999D03*
Y1410991D03*
X1112000Y1644980D03*
X1125735Y60922D03*
X1139134Y109172D03*
X1141141Y106495D03*
X1126548Y110784D03*
X1134142Y133298D03*
X1126142D03*
X1140875Y146012D03*
X1128289Y134579D03*
X1129277Y203393D03*
X1140346Y253198D03*
X1125864Y252371D03*
X1129553Y389153D03*
Y396240D03*
Y403326D03*
Y410413D03*
Y424586D03*
Y417499D03*
Y431673D03*
Y438760D03*
X1126931Y453564D03*
X1130355Y453483D03*
X1129553Y467539D03*
X1125178Y459792D03*
X1129553Y474626D03*
Y488799D03*
Y481712D03*
Y518760D03*
Y511673D03*
Y532933D03*
Y525846D03*
X1138098Y543925D03*
X1138673Y555000D03*
X1126633Y560500D03*
X1139615Y1350683D03*
Y1345691D03*
X1132331D03*
Y1350683D03*
X1127375D03*
Y1345691D03*
X1139615Y1357603D03*
Y1362595D03*
X1132331D03*
Y1357603D03*
X1127375D03*
Y1362595D03*
X1139615Y1374881D03*
Y1369889D03*
Y1381801D03*
X1132331Y1369889D03*
Y1381801D03*
Y1374881D03*
X1127375Y1369889D03*
Y1381801D03*
Y1374881D03*
X1139615Y1394087D03*
Y1399079D03*
Y1386793D03*
X1132331D03*
Y1394087D03*
Y1399079D03*
X1127375Y1386793D03*
Y1394087D03*
Y1399079D03*
X1139615Y1405999D03*
Y1410991D03*
X1132331Y1405999D03*
Y1410991D03*
X1127375Y1405999D03*
Y1410991D03*
X1129637Y1465913D03*
Y1461182D03*
Y1456451D03*
X1138298Y1465513D03*
Y1460782D03*
X1129637Y1476536D03*
Y1481267D03*
X1138298Y1476136D03*
Y1470244D03*
Y1480867D03*
X1129637Y1471805D03*
Y1496621D03*
X1138298Y1491490D03*
Y1485598D03*
Y1496221D03*
X1129637Y1491890D03*
Y1487159D03*
X1138298Y1500952D03*
Y1511576D03*
X1129637Y1507245D03*
Y1502514D03*
Y1511976D03*
X1138298Y1506845D03*
Y1516307D03*
X1129637Y1563544D03*
Y1558813D03*
X1138298Y1563144D03*
Y1572606D03*
X1129637Y1568275D03*
Y1578898D03*
Y1574167D03*
X1138298Y1567875D03*
Y1578498D03*
X1129637Y1583629D03*
Y1594253D03*
Y1589522D03*
X1138298Y1583229D03*
Y1593853D03*
Y1587960D03*
Y1598584D03*
Y1603315D03*
X1129637Y1609607D03*
Y1598984D03*
Y1604876D03*
X1138298Y1609207D03*
X1129637Y1614338D03*
X1138298Y1613938D03*
Y1618669D03*
X1132000Y1644980D03*
X1142134Y109172D03*
X1156885Y116496D03*
Y102323D03*
Y109410D03*
X1152185D03*
Y116497D03*
X1149685D03*
X1144885D03*
X1152185Y130670D03*
X1149685D03*
Y123584D03*
X1152185Y123583D03*
X1144885Y130670D03*
Y123584D03*
X1156885Y130670D03*
Y123583D03*
X1142781Y141228D03*
X1156885Y137756D03*
X1149685Y137757D03*
X1144885D03*
X1145669Y150847D03*
X1147637Y247292D03*
X1145761Y324148D03*
X1157251Y636842D03*
X1156023Y678462D03*
X1149345Y771517D03*
X1145910Y794217D03*
X1151277Y790996D03*
X1149627Y813323D03*
X1146985Y812642D03*
X1152510Y844642D03*
X1156811Y1350683D03*
Y1345691D03*
X1151855D03*
Y1350683D03*
X1144571D03*
Y1345691D03*
X1156811Y1357603D03*
Y1362595D03*
X1151855D03*
Y1357603D03*
X1144571D03*
Y1362595D03*
X1156811Y1374881D03*
Y1369889D03*
Y1381801D03*
X1151855Y1374881D03*
Y1369889D03*
Y1381801D03*
X1144571Y1369889D03*
Y1381801D03*
Y1374881D03*
X1156811Y1386793D03*
Y1399079D03*
Y1394087D03*
X1151855Y1386793D03*
Y1399079D03*
Y1394087D03*
X1144571D03*
Y1399079D03*
Y1386793D03*
X1156811Y1405999D03*
Y1410991D03*
X1151855Y1405999D03*
Y1410991D03*
X1144571Y1405999D03*
Y1410991D03*
X1146960Y1465913D03*
Y1461182D03*
X1155621Y1465513D03*
Y1460782D03*
X1146960Y1456451D03*
X1155621Y1480867D03*
X1146960Y1471805D03*
Y1476536D03*
Y1481267D03*
X1155621Y1476136D03*
Y1470244D03*
Y1491490D03*
Y1485598D03*
Y1496221D03*
X1146960Y1487159D03*
Y1491890D03*
Y1496621D03*
Y1507245D03*
Y1502514D03*
X1155621Y1506845D03*
Y1500952D03*
Y1511576D03*
X1146960Y1511976D03*
X1155621Y1516307D03*
X1146960Y1563544D03*
X1155621Y1563144D03*
X1146960Y1558813D03*
X1155621Y1572606D03*
X1146960Y1568275D03*
X1155621Y1567875D03*
X1146960Y1574167D03*
Y1578898D03*
X1155621Y1578498D03*
X1146960Y1594253D03*
X1155621Y1593853D03*
Y1587960D03*
X1146960Y1583629D03*
X1155621Y1583229D03*
X1146960Y1589522D03*
Y1609607D03*
Y1604876D03*
Y1598984D03*
X1155621Y1609207D03*
Y1598584D03*
Y1603315D03*
X1146960Y1614338D03*
X1155621Y1613938D03*
Y1618669D03*
X1152000Y1644980D03*
X1165347Y82984D03*
Y75184D03*
Y77784D03*
Y80384D03*
X1167756Y92734D03*
X1165347Y85584D03*
X1171586Y137756D03*
X1168902Y431029D03*
X1167931Y435029D03*
X1169173Y427017D03*
X1168851Y449873D03*
X1171255Y456287D03*
X1173278Y472579D03*
X1168478D03*
X1173278Y479666D03*
X1168478D03*
Y486752D03*
X1173278D03*
X1168478Y493839D03*
X1173278D03*
X1168478Y523800D03*
Y516713D03*
X1173278D03*
Y523800D03*
Y537973D03*
X1168478D03*
X1173278Y530886D03*
X1168478D03*
X1173278Y566752D03*
X1168478D03*
Y580926D03*
X1173278D03*
Y588013D03*
X1168478D03*
X1173278Y573839D03*
X1168478D03*
Y602186D03*
X1173278D03*
Y595099D03*
X1168478D03*
X1173278Y609272D03*
X1168478D03*
Y616359D03*
X1173278D03*
X1163157Y638125D03*
X1160756Y665140D03*
X1157985Y791142D03*
X1161291Y791662D03*
X1173697Y791911D03*
X1160516Y800900D03*
X1169051Y1345597D03*
Y1350683D03*
X1164095D03*
Y1345597D03*
X1169051Y1357603D03*
Y1362595D03*
X1164095Y1357603D03*
Y1362595D03*
X1169051Y1381801D03*
Y1374881D03*
Y1369889D03*
X1164095D03*
Y1381801D03*
Y1374881D03*
X1169051Y1393993D03*
Y1399079D03*
Y1386793D03*
X1164095Y1393993D03*
Y1399079D03*
Y1386793D03*
X1169051Y1410991D03*
Y1405999D03*
X1164095D03*
Y1410991D03*
X1164283Y1465913D03*
Y1456451D03*
Y1461182D03*
X1172944Y1465513D03*
Y1460782D03*
Y1470244D03*
Y1480867D03*
X1164283Y1471805D03*
Y1476536D03*
Y1481267D03*
X1172944Y1476136D03*
X1164283Y1487159D03*
Y1491890D03*
Y1496621D03*
X1172944Y1491490D03*
Y1485598D03*
Y1496221D03*
X1164283Y1507245D03*
Y1502514D03*
X1172944Y1506845D03*
Y1500952D03*
Y1511576D03*
X1164283Y1511976D03*
X1172944Y1516307D03*
X1164283Y1558813D03*
Y1563544D03*
X1172944Y1563144D03*
Y1567875D03*
X1164283Y1574167D03*
Y1578898D03*
X1172944Y1578498D03*
Y1572606D03*
X1164283Y1568275D03*
Y1583629D03*
X1172944Y1583229D03*
X1164283Y1589522D03*
Y1594253D03*
X1172944Y1593853D03*
Y1587960D03*
Y1598584D03*
Y1603315D03*
X1164283Y1609607D03*
Y1604876D03*
Y1598984D03*
X1172944Y1609207D03*
X1164283Y1614338D03*
X1172944Y1613938D03*
Y1618669D03*
X1172000Y1644980D03*
X1188278Y94017D03*
X1174861Y103037D03*
X1174995Y116496D03*
Y109410D03*
Y130670D03*
Y123583D03*
X1187793Y226141D03*
X1190593D03*
X1179676Y293796D03*
X1187690Y288190D03*
X1185190Y285690D03*
X1187690D03*
X1185190Y288190D03*
X1177176Y293796D03*
X1182911Y336516D03*
X1177036Y334148D03*
X1188598Y390500D03*
X1179184Y410394D03*
Y403307D03*
X1180578Y458406D03*
Y451319D03*
X1180402Y462264D03*
X1175778Y465492D03*
X1180578D03*
X1175778Y472579D03*
X1180578D03*
X1175778Y479666D03*
X1180578Y479665D03*
Y486752D03*
X1175778D03*
X1180578Y493839D03*
X1175778Y509626D03*
X1180578Y523799D03*
Y516713D03*
Y509626D03*
X1175778Y516713D03*
Y523800D03*
X1180578Y537973D03*
X1175778Y530886D03*
X1180578D03*
Y559665D03*
Y566752D03*
X1175778D03*
Y559665D03*
Y580926D03*
X1180578D03*
Y588012D03*
X1175778D03*
X1180578Y573839D03*
X1175778D03*
Y602185D03*
X1180578D03*
X1175778Y595099D03*
X1180578D03*
X1175778Y609272D03*
X1180578Y616358D03*
Y609272D03*
X1177745Y771744D03*
X1177566Y778539D03*
X1190062Y844378D03*
X1187703Y849734D03*
X1186742Y855466D03*
X1183431Y868340D03*
X1177775Y894053D03*
X1178480Y915220D03*
X1178000Y936500D03*
X1187200Y963400D03*
X1181291Y1350683D03*
Y1345691D03*
X1176335D03*
Y1350683D03*
X1181291Y1362595D03*
Y1357603D03*
X1176335Y1362595D03*
Y1357603D03*
X1181291Y1369889D03*
Y1381801D03*
Y1374881D03*
X1176335Y1369889D03*
Y1381801D03*
Y1374881D03*
X1181291Y1386793D03*
Y1399079D03*
Y1394087D03*
X1176335Y1386793D03*
Y1399079D03*
Y1394087D03*
X1181291Y1405999D03*
Y1410991D03*
X1176335Y1405999D03*
Y1410991D03*
X1181605Y1465913D03*
Y1456451D03*
Y1461182D03*
Y1471805D03*
Y1476536D03*
Y1481267D03*
Y1487159D03*
Y1491890D03*
Y1496621D03*
Y1507245D03*
Y1502514D03*
Y1511976D03*
Y1558813D03*
Y1563544D03*
Y1568275D03*
Y1574167D03*
Y1578898D03*
Y1583629D03*
Y1589522D03*
Y1594253D03*
Y1598984D03*
Y1609607D03*
Y1604876D03*
Y1614338D03*
X1205355Y84140D03*
Y76140D03*
Y80140D03*
X1196278Y94017D03*
X1200287D03*
X1192278D03*
X1202808Y117557D03*
X1197398Y110445D03*
Y115401D03*
X1192406Y110445D03*
Y115401D03*
X1197398Y129574D03*
Y124618D03*
X1192406D03*
Y129574D03*
X1202808Y122513D03*
Y131731D03*
X1205899Y146461D03*
X1202808Y136687D03*
X1204801Y152367D03*
X1190319Y151540D03*
X1200469Y184619D03*
X1193969Y191941D03*
X1193836Y188727D03*
X1202449Y206760D03*
X1203663Y256535D03*
X1195663D03*
X1204693Y279208D03*
X1194716Y290755D03*
X1202716D03*
X1190490Y285690D03*
Y288190D03*
X1198716Y290755D03*
X1198248Y381500D03*
X1198689Y465492D03*
X1198655Y460250D03*
X1196420Y470136D03*
X1198689Y472579D03*
Y486752D03*
Y479665D03*
Y493839D03*
Y509626D03*
Y516713D03*
X1195149Y537973D03*
X1197629Y525483D03*
X1197550Y532756D03*
X1198689Y559665D03*
Y566752D03*
X1198539Y579978D03*
X1198689Y573839D03*
X1198753Y608117D03*
X1198997Y790610D03*
X1198845Y998504D03*
X1204919Y1021860D03*
X1202268Y1013551D03*
X1190267Y1465513D03*
Y1460782D03*
X1198928Y1465914D03*
Y1456452D03*
Y1461183D03*
Y1481268D03*
X1190267Y1476136D03*
Y1470244D03*
Y1480867D03*
X1198928Y1476537D03*
Y1471806D03*
X1190267Y1485598D03*
Y1496221D03*
X1198928Y1491891D03*
Y1487160D03*
Y1496622D03*
X1190267Y1491490D03*
Y1506845D03*
Y1500952D03*
Y1511576D03*
X1198928Y1507246D03*
Y1502515D03*
Y1511977D03*
X1190267Y1516307D03*
X1198928Y1558813D03*
X1190267Y1563144D03*
X1198928Y1563544D03*
X1190267Y1567875D03*
X1198928Y1568275D03*
X1190267Y1578498D03*
Y1572606D03*
X1198928Y1578898D03*
Y1574167D03*
X1190267Y1583229D03*
X1198928Y1583629D03*
X1190267Y1593853D03*
Y1587960D03*
X1198928Y1594253D03*
Y1589522D03*
X1190267Y1609207D03*
Y1598584D03*
Y1603315D03*
X1198928Y1609607D03*
Y1598984D03*
Y1604876D03*
X1190267Y1613938D03*
Y1618669D03*
X1198928Y1614338D03*
X1192000Y1644980D03*
X1218730Y117261D03*
X1207800Y117557D03*
Y122513D03*
Y131731D03*
Y136687D03*
X1206501Y180572D03*
X1211184Y180527D03*
X1214907Y192421D03*
X1206501Y185165D03*
X1211139Y185121D03*
X1208797Y281307D03*
X1220985Y342319D03*
X1212680Y445908D03*
X1216630Y445787D03*
X1212000Y1644980D03*
X1222933Y55513D03*
X1228097Y60922D03*
X1225041Y97080D03*
X1228910Y110784D03*
X1226261Y113394D03*
X1229195Y130898D03*
X1236504Y133298D03*
X1230651Y134579D03*
X1226437Y180665D03*
Y172665D03*
X1226469Y200864D03*
Y212864D03*
Y216864D03*
Y221864D03*
X1228226Y252371D03*
X1238055Y303839D03*
X1230077Y336324D03*
X1234656Y353506D03*
X1223431Y393924D03*
Y389912D03*
Y385912D03*
Y409924D03*
Y405924D03*
Y401924D03*
X1229548Y1350683D03*
Y1345691D03*
X1234504D03*
Y1350683D03*
X1229548Y1362595D03*
Y1357603D03*
X1234504D03*
Y1362595D03*
X1229548Y1369889D03*
Y1374881D03*
Y1381801D03*
X1234504Y1369889D03*
Y1374881D03*
Y1381801D03*
X1229548Y1386793D03*
X1234504D03*
X1232000Y1644980D03*
X1243503Y106495D03*
X1244496Y109172D03*
X1241496D03*
X1247247Y116497D03*
X1254547Y109410D03*
Y116497D03*
X1252047D03*
X1247247Y123584D03*
Y130670D03*
X1252047Y123584D03*
X1254547Y123583D03*
Y130670D03*
X1252047D03*
X1243237Y146012D03*
X1245143Y141228D03*
X1247247Y137757D03*
X1252047D03*
X1250307Y140296D03*
X1248031Y150847D03*
X1249999Y247292D03*
X1242708Y253198D03*
X1248064Y567813D03*
Y572769D03*
Y581987D03*
Y586943D03*
Y601116D03*
Y596160D03*
Y615289D03*
Y610333D03*
X1246800Y1001600D03*
X1249200Y1014000D03*
X1248721Y1025864D03*
X1251802Y1186071D03*
X1254028Y1350683D03*
Y1345691D03*
X1241788D03*
Y1350683D03*
X1246744Y1345691D03*
Y1350683D03*
X1254028Y1357603D03*
Y1362595D03*
X1241788D03*
Y1357603D03*
X1246744Y1362595D03*
Y1357603D03*
X1254028Y1381801D03*
Y1374881D03*
Y1369889D03*
X1241788Y1374881D03*
Y1369795D03*
Y1381801D03*
X1246744Y1374881D03*
Y1369795D03*
Y1381801D03*
X1254028Y1386793D03*
Y1399079D03*
Y1394087D03*
X1241788Y1399079D03*
Y1393993D03*
Y1386793D03*
X1246744Y1393993D03*
Y1399079D03*
Y1386793D03*
X1254028Y1410991D03*
Y1405999D03*
X1241788Y1410991D03*
Y1405999D03*
X1246744Y1410991D03*
Y1405999D03*
X1245900Y1528000D03*
X1267709Y82984D03*
Y75184D03*
Y77784D03*
Y80384D03*
X1270263Y92849D03*
X1267709Y85584D03*
X1259247Y116496D03*
Y102323D03*
Y109410D03*
Y130670D03*
Y123583D03*
Y137756D03*
X1258925Y324075D03*
X1270951Y491870D03*
X1270515Y908277D03*
X1269876Y1132319D03*
X1263873Y1148000D03*
X1266709Y1160168D03*
X1258736Y1188223D03*
X1268573Y1193019D03*
X1264573D03*
X1266268Y1345691D03*
Y1350683D03*
X1258984D03*
Y1345691D03*
X1266268Y1362595D03*
Y1357603D03*
X1258984Y1362595D03*
Y1357603D03*
X1266268Y1369889D03*
Y1374881D03*
Y1381801D03*
X1258984D03*
Y1369889D03*
Y1374881D03*
X1266268Y1399079D03*
Y1394087D03*
Y1386793D03*
X1258984Y1394087D03*
Y1386793D03*
Y1399079D03*
X1266268Y1410991D03*
Y1405999D03*
X1258984D03*
Y1410991D03*
X1263242Y1523458D03*
X1262985Y1519459D03*
X1260260Y1546500D03*
X1277223Y103037D03*
X1277357Y116496D03*
Y109410D03*
Y130670D03*
Y123583D03*
X1273555Y137756D03*
X1279538Y293796D03*
X1282038D03*
X1283494Y339495D03*
X1287437Y370010D03*
X1280616Y472189D03*
X1273451Y491870D03*
X1279539Y772576D03*
Y776576D03*
X1274417Y861964D03*
X1282317Y880193D03*
X1285493Y892175D03*
X1277039Y916484D03*
X1284021Y940008D03*
X1273865Y1132497D03*
X1282830Y1146937D03*
X1272120Y1159455D03*
X1280306Y1162817D03*
X1276573Y1193019D03*
X1280573D03*
X1272573D03*
X1277108Y1211664D03*
X1279402Y1213958D03*
X1275032Y1209589D03*
X1284198Y1218754D03*
X1283464Y1345691D03*
Y1350683D03*
X1278508Y1345691D03*
Y1350683D03*
X1271224Y1345691D03*
Y1350683D03*
X1283464Y1362595D03*
Y1357603D03*
X1278508D03*
Y1362595D03*
X1271224D03*
Y1357603D03*
X1283464Y1381801D03*
Y1369889D03*
Y1374881D03*
X1278508Y1381801D03*
Y1369889D03*
Y1374881D03*
X1271224Y1369889D03*
Y1374881D03*
Y1381801D03*
X1283464Y1386793D03*
Y1399079D03*
Y1394087D03*
X1278508Y1386793D03*
Y1399079D03*
Y1394087D03*
X1271224D03*
Y1399079D03*
Y1386793D03*
X1283464Y1410991D03*
Y1405999D03*
X1278508Y1410991D03*
Y1405999D03*
X1271224Y1410991D03*
Y1405999D03*
X1291756Y-25143D03*
X1288503Y-25157D03*
X1291741Y-27658D03*
X1288488Y-27672D03*
X1294781Y-26463D03*
X1302649Y94017D03*
X1298640D03*
X1290640D03*
X1294640D03*
X1299760Y110445D03*
Y115401D03*
X1294768Y110445D03*
Y115401D03*
Y129574D03*
X1299760D03*
Y124618D03*
X1294768D03*
X1296331Y191941D03*
X1302831Y184619D03*
X1296198Y188727D03*
X1292955Y226141D03*
X1290155D03*
X1298025Y256535D03*
X1290052Y288190D03*
X1292852D03*
Y285690D03*
X1305078Y290755D03*
X1297078D03*
X1301078D03*
X1287552Y288190D03*
X1290052Y285690D03*
X1287552D03*
X1294425Y321425D03*
X1299959Y351454D03*
X1296783Y511956D03*
X1303520Y748403D03*
X1300516Y832047D03*
X1300504Y835985D03*
X1300204Y859088D03*
X1300097Y851193D03*
X1300091Y854824D03*
X1291955Y901295D03*
X1289547Y928047D03*
X1298090Y940852D03*
X1295453Y940953D03*
X1302988Y1345691D03*
Y1350683D03*
X1290748D03*
Y1345691D03*
X1295704Y1350683D03*
Y1345691D03*
X1302988Y1362595D03*
Y1357603D03*
X1290748Y1362595D03*
Y1357603D03*
X1295704Y1362595D03*
Y1357603D03*
X1302988Y1374881D03*
Y1381801D03*
Y1369889D03*
X1290748D03*
Y1381801D03*
Y1374881D03*
X1295704Y1381801D03*
Y1374881D03*
Y1369889D03*
X1302988Y1386793D03*
Y1399079D03*
Y1394087D03*
X1290748Y1399079D03*
Y1394087D03*
Y1386793D03*
X1295704Y1394087D03*
Y1399079D03*
Y1386793D03*
X1302988Y1410991D03*
Y1405999D03*
X1290748Y1410991D03*
Y1405999D03*
X1295704Y1410991D03*
Y1405999D03*
X1302866Y1461182D03*
Y1456451D03*
Y1465913D03*
Y1476536D03*
Y1471805D03*
Y1481267D03*
Y1491890D03*
Y1487159D03*
Y1496621D03*
Y1507245D03*
Y1502514D03*
Y1511976D03*
Y1558813D03*
Y1563544D03*
Y1578898D03*
Y1574167D03*
Y1568275D03*
Y1594253D03*
Y1589522D03*
Y1583629D03*
Y1609607D03*
Y1598984D03*
Y1604876D03*
Y1614338D03*
X1292000Y1644980D03*
X1307717Y84140D03*
Y76140D03*
Y80140D03*
X1310162Y117557D03*
X1305170D03*
X1310162Y122513D03*
Y131731D03*
X1305170Y122513D03*
Y131731D03*
X1310162Y136687D03*
X1305170D03*
X1313546Y180527D03*
X1308863Y180572D03*
Y185165D03*
X1317269Y192421D03*
X1313501Y185121D03*
X1304811Y206760D03*
X1306025Y256535D03*
X1307055Y279208D03*
X1311159Y281307D03*
X1314569Y318013D03*
X1312069D03*
X1317584Y313058D03*
X1316017Y349889D03*
X1308410Y370899D03*
X1313691Y402642D03*
X1316191D03*
X1309117Y398949D03*
X1306617Y401949D03*
X1308066Y413611D03*
X1310866D03*
X1313366D03*
X1315866D03*
X1315806Y423944D03*
X1313306D03*
X1310806D03*
X1308006D03*
X1307919Y478382D03*
X1307825Y482382D03*
X1305134Y812065D03*
X1313756Y829871D03*
X1308857Y836076D03*
X1316906Y842470D03*
Y867665D03*
Y883413D03*
Y892862D03*
X1316893Y925603D03*
X1318375Y943951D03*
X1303907Y960093D03*
X1307580Y990314D03*
X1304664Y1023462D03*
X1309937Y1037038D03*
X1319326Y1040723D03*
X1317437Y1152684D03*
X1307167Y1245696D03*
X1308276Y1276446D03*
X1315228Y1345691D03*
Y1350683D03*
X1307944D03*
Y1345691D03*
X1315228Y1362595D03*
Y1357603D03*
X1307944D03*
Y1362595D03*
X1315228Y1381801D03*
Y1369889D03*
Y1374881D03*
X1307944D03*
Y1381801D03*
Y1369889D03*
X1315228Y1399079D03*
Y1394087D03*
Y1386793D03*
X1307944D03*
Y1399079D03*
Y1394087D03*
X1315228Y1410991D03*
Y1405999D03*
X1307944Y1410991D03*
Y1405999D03*
X1311527Y1465513D03*
Y1460782D03*
Y1480867D03*
Y1476136D03*
Y1470244D03*
Y1491490D03*
Y1485598D03*
Y1496221D03*
Y1506845D03*
Y1500952D03*
Y1511576D03*
Y1516307D03*
Y1563144D03*
Y1567875D03*
Y1578498D03*
Y1572606D03*
Y1583229D03*
Y1593853D03*
Y1587960D03*
Y1609207D03*
Y1598584D03*
Y1603315D03*
Y1613938D03*
Y1618669D03*
X1312000Y1644980D03*
X1331756Y-64193D03*
X1328503Y-64207D03*
X1331741Y-66708D03*
X1328488Y-66722D03*
X1334781Y-65513D03*
X1321092Y117261D03*
X1328799Y172665D03*
Y180665D03*
X1328831Y212864D03*
Y200864D03*
Y221864D03*
Y216864D03*
X1330414Y310058D03*
X1325458D03*
X1322540Y313058D03*
X1333332D03*
X1331085Y334347D03*
X1323816D03*
Y341615D03*
X1331085Y348868D03*
X1323816D03*
X1332927Y468607D03*
X1326912Y493153D03*
X1325630Y513238D03*
X1335000Y590500D03*
Y586500D03*
Y633000D03*
Y637000D03*
Y677500D03*
Y681500D03*
Y724500D03*
Y728500D03*
X1324217Y780595D03*
X1332654Y836170D03*
X1323205Y861367D03*
X1335803Y851918D03*
Y877114D03*
X1326355Y886562D03*
X1328457Y959986D03*
X1321104Y964398D03*
X1323554Y967623D03*
X1331890Y1051919D03*
X1331359Y1098898D03*
X1334161Y1098518D03*
X1333905Y1123101D03*
X1331405D03*
X1323405D03*
X1320279Y1131935D03*
Y1134435D03*
Y1136935D03*
Y1139435D03*
X1334305Y1129301D03*
X1331805D03*
X1329305D03*
X1326805D03*
X1324305D03*
X1321805D03*
X1334305Y1125801D03*
X1331805D03*
X1323405D03*
X1320279Y1141935D03*
Y1146935D03*
Y1144435D03*
X1326269Y1152713D03*
Y1155213D03*
X1320493Y1204405D03*
X1334793Y1204617D03*
X1320493Y1206905D03*
Y1211905D03*
Y1209405D03*
X1334793Y1207117D03*
Y1209617D03*
Y1212117D03*
X1330070Y1297498D03*
X1335470D03*
X1332424Y1345691D03*
Y1350683D03*
X1327468D03*
Y1345691D03*
X1320184Y1350683D03*
Y1345691D03*
X1332424Y1362595D03*
Y1357603D03*
X1327468D03*
Y1362595D03*
X1320184D03*
Y1357603D03*
X1332424Y1381801D03*
Y1369889D03*
Y1374881D03*
X1327468Y1381801D03*
Y1369889D03*
Y1374881D03*
X1320184Y1381801D03*
Y1374881D03*
Y1369889D03*
X1332424Y1386793D03*
Y1394087D03*
Y1399079D03*
X1327468Y1386793D03*
Y1394087D03*
Y1399079D03*
X1320184D03*
Y1394087D03*
Y1386793D03*
X1332424Y1410991D03*
Y1405999D03*
X1327468Y1410991D03*
Y1405999D03*
X1320184Y1410991D03*
Y1405999D03*
X1328850Y1465513D03*
Y1460782D03*
X1320189Y1465913D03*
Y1456451D03*
Y1461182D03*
X1328850Y1476136D03*
Y1470244D03*
X1320189Y1481267D03*
X1328850Y1480867D03*
X1320189Y1471805D03*
Y1476536D03*
X1328850Y1491490D03*
Y1485598D03*
X1320189Y1496621D03*
X1328850Y1496221D03*
X1320189Y1487159D03*
Y1491890D03*
Y1502514D03*
X1328850Y1506845D03*
Y1500952D03*
Y1511576D03*
X1320189Y1511976D03*
Y1507245D03*
X1328850Y1516307D03*
X1320189Y1558813D03*
Y1563544D03*
X1328850Y1563144D03*
Y1567875D03*
X1320189Y1574167D03*
Y1578898D03*
X1328850Y1578498D03*
Y1572606D03*
X1320189Y1568275D03*
X1328850Y1583229D03*
X1320189Y1589522D03*
Y1594253D03*
X1328850Y1593853D03*
Y1587960D03*
X1320189Y1583629D03*
X1328850Y1603315D03*
X1320189Y1609607D03*
Y1604876D03*
Y1598984D03*
X1328850Y1609207D03*
Y1598584D03*
Y1613938D03*
Y1618669D03*
X1320189Y1614338D03*
X1332000Y1644980D03*
X1340320Y151540D03*
X1338288Y313058D03*
X1338378Y334347D03*
X1338275Y341603D03*
X1338378Y348830D03*
X1345451Y699032D03*
X1347136Y780040D03*
X1351550Y839320D03*
Y855068D03*
X1345252D03*
X1342103D03*
Y861367D03*
X1338953D03*
Y858218D03*
X1338952Y855067D03*
X1338953Y870814D03*
X1342103Y867665D03*
X1338953D03*
X1351550Y873964D03*
X1345252D03*
X1342103D03*
X1338952Y873965D03*
X1345252Y892862D03*
X1341820Y947407D03*
X1347380Y1057998D03*
Y1055498D03*
X1344880D03*
Y1057998D03*
X1347380Y1060498D03*
Y1062998D03*
X1344880D03*
Y1060498D03*
X1339349Y1098767D03*
X1339305Y1129301D03*
X1336805D03*
X1339305Y1125801D03*
X1336805D03*
X1343505Y1136935D03*
Y1134435D03*
Y1139435D03*
Y1131935D03*
X1349907D03*
Y1134435D03*
Y1136935D03*
Y1139435D03*
X1352407Y1131935D03*
Y1134435D03*
Y1136935D03*
Y1139435D03*
X1343505Y1146935D03*
Y1144435D03*
Y1141935D03*
X1349907D03*
Y1146935D03*
Y1144435D03*
X1352407Y1141935D03*
Y1146935D03*
Y1144435D03*
X1336669Y1152713D03*
Y1155213D03*
X1351405Y1154902D03*
Y1152402D03*
X1347423Y1204405D03*
X1337108Y1200821D03*
Y1198321D03*
X1347423Y1209405D03*
Y1211905D03*
Y1206905D03*
X1340870Y1297498D03*
X1346270D03*
X1351670D03*
X1351948Y1350683D03*
Y1345691D03*
X1339708Y1345597D03*
Y1350683D03*
X1344664Y1345597D03*
Y1350683D03*
X1351948Y1357603D03*
Y1362595D03*
X1339708D03*
Y1357603D03*
X1344664Y1362595D03*
Y1357603D03*
X1351948Y1374881D03*
Y1381801D03*
Y1369889D03*
X1339708Y1374881D03*
Y1381801D03*
Y1369889D03*
X1344664D03*
Y1374881D03*
Y1381801D03*
X1351948Y1386793D03*
Y1394087D03*
Y1399079D03*
X1339708D03*
Y1393993D03*
Y1386793D03*
X1344664Y1393993D03*
Y1399079D03*
Y1386793D03*
X1351948Y1410991D03*
Y1405999D03*
X1339708Y1410991D03*
Y1405999D03*
X1344664Y1410991D03*
Y1405999D03*
X1337512Y1461182D03*
X1346173Y1465513D03*
Y1460782D03*
X1337512Y1465913D03*
Y1456451D03*
X1346173Y1476136D03*
Y1470244D03*
X1337512Y1481267D03*
X1346173Y1480867D03*
X1337512Y1471805D03*
Y1476536D03*
X1346173Y1485598D03*
Y1491490D03*
X1337512Y1487159D03*
Y1491890D03*
Y1496621D03*
X1346173Y1496221D03*
X1337512Y1507245D03*
Y1502514D03*
X1346173Y1506845D03*
Y1500952D03*
Y1511576D03*
X1337512Y1511976D03*
X1346173Y1516307D03*
X1337512Y1558813D03*
Y1563544D03*
X1346173Y1563144D03*
X1337512Y1574167D03*
Y1578898D03*
X1346173Y1578498D03*
Y1572606D03*
X1337512Y1568275D03*
X1346173Y1567875D03*
X1337512Y1583629D03*
X1346173Y1583229D03*
X1337512Y1589522D03*
Y1594253D03*
X1346173Y1593853D03*
Y1587960D03*
X1337512Y1609607D03*
Y1604876D03*
Y1598984D03*
X1346173Y1609207D03*
Y1598584D03*
Y1603315D03*
X1337512Y1614338D03*
X1346173Y1613938D03*
Y1618669D03*
X1352000Y1644980D03*
X1355900Y146461D03*
X1354802Y152367D03*
X1355255Y561032D03*
Y607532D03*
Y652032D03*
X1364148Y836170D03*
X1354699Y855068D03*
X1357849Y861367D03*
X1354699D03*
X1357849Y858218D03*
X1357850Y855067D03*
X1360999Y851918D03*
Y877114D03*
X1357850Y873965D03*
X1354699Y873964D03*
X1357849Y870814D03*
Y867665D03*
X1354699D03*
X1363173Y994483D03*
X1363905Y1000855D03*
X1366493Y1000828D03*
X1367884Y1018825D03*
X1357265Y1022766D03*
X1364237Y1043140D03*
X1357265Y1030266D03*
X1363941Y1047047D03*
X1366289Y1098518D03*
X1361037Y1098428D03*
X1355533Y1123101D03*
X1363533D03*
X1366033D03*
X1366433Y1129301D03*
X1355533Y1125801D03*
X1363933D03*
X1366433D03*
X1353933Y1129301D03*
X1356433D03*
X1358933D03*
X1361433D03*
X1363933D03*
X1357397Y1155213D03*
Y1152713D03*
X1366797D03*
Y1155213D03*
X1361723Y1204617D03*
X1364038Y1198321D03*
Y1200821D03*
X1361723Y1212117D03*
Y1209617D03*
Y1207117D03*
X1357070Y1297498D03*
X1356904Y1345691D03*
Y1350683D03*
Y1357603D03*
Y1362595D03*
Y1381801D03*
Y1369889D03*
Y1374881D03*
Y1386793D03*
Y1394087D03*
Y1399079D03*
Y1410991D03*
Y1405999D03*
X1354834Y1465913D03*
Y1456451D03*
Y1461182D03*
X1363496Y1465513D03*
Y1460782D03*
X1354834Y1481267D03*
X1363496Y1476136D03*
Y1470244D03*
Y1480867D03*
X1354834Y1471805D03*
Y1476536D03*
Y1487159D03*
Y1496621D03*
X1363496Y1485598D03*
Y1491490D03*
Y1496221D03*
X1354834Y1491890D03*
Y1502514D03*
Y1511976D03*
X1363496Y1511576D03*
Y1506845D03*
Y1500952D03*
X1354834Y1507245D03*
X1363496Y1516307D03*
X1354834Y1558813D03*
Y1563544D03*
X1363496Y1563144D03*
Y1572606D03*
X1354834Y1568275D03*
Y1574167D03*
Y1578898D03*
X1363496Y1567875D03*
Y1578498D03*
X1354834Y1583629D03*
Y1589522D03*
Y1594253D03*
X1363496Y1583229D03*
Y1593853D03*
Y1587960D03*
X1354834Y1609607D03*
Y1604876D03*
Y1598984D03*
X1363496Y1609207D03*
Y1598584D03*
Y1603315D03*
X1354834Y1614338D03*
X1363496Y1613938D03*
Y1618669D03*
X1376262Y113394D03*
X1378911Y110784D03*
X1378505Y133298D03*
X1380652Y134579D03*
X1378227Y252371D03*
X1383556Y558338D03*
X1383184Y587653D03*
X1383425Y593575D03*
X1383556Y604838D03*
X1381118Y634033D03*
X1383425Y640075D03*
X1381244Y673623D03*
X1383425Y684140D03*
X1381932Y722547D03*
X1383425Y731575D03*
X1383046Y829871D03*
X1379896Y842470D03*
Y858218D03*
X1370447Y867665D03*
Y886562D03*
X1371379Y986717D03*
X1370384Y1004680D03*
X1376601Y1030218D03*
X1374451Y1090568D03*
Y1093068D03*
X1371477Y1098767D03*
X1375633Y1136935D03*
Y1134435D03*
Y1139435D03*
Y1131935D03*
X1383366D03*
Y1134435D03*
Y1136935D03*
Y1139435D03*
X1368933Y1125801D03*
X1371433D03*
X1368933Y1129301D03*
X1371433D03*
X1383024Y1152684D03*
X1376861D03*
X1375633Y1146935D03*
Y1144435D03*
Y1141935D03*
X1383366D03*
Y1146935D03*
Y1144435D03*
X1377390Y1244055D03*
Y1250760D03*
Y1254164D03*
X1372300Y1422900D03*
X1372157Y1461183D03*
Y1456452D03*
Y1465914D03*
Y1471806D03*
Y1476537D03*
Y1481268D03*
Y1487160D03*
Y1491891D03*
Y1496622D03*
Y1502515D03*
Y1507246D03*
Y1511977D03*
Y1558813D03*
Y1563544D03*
Y1568275D03*
Y1574167D03*
Y1578898D03*
Y1583629D03*
Y1589522D03*
Y1594253D03*
Y1604876D03*
Y1598984D03*
Y1609607D03*
Y1614338D03*
X1372000Y1644980D03*
X1391497Y109172D03*
X1394497D03*
X1393504Y106495D03*
X1397248Y116497D03*
X1386505Y133298D03*
X1397248Y130670D03*
Y123584D03*
X1393238Y146012D03*
X1395144Y141228D03*
X1397248Y137757D03*
X1398032Y150847D03*
X1400000Y247292D03*
X1392709Y253198D03*
X1391086Y577192D03*
X1400912Y581222D03*
Y591215D03*
X1391587Y627817D03*
X1388414Y675000D03*
X1388241Y722000D03*
X1396916Y862829D03*
X1395561Y876204D03*
X1396163Y868597D03*
X1398247Y926261D03*
X1390322Y1057998D03*
Y1055498D03*
X1392822D03*
Y1057998D03*
X1390322Y1060498D03*
Y1062998D03*
X1392822D03*
Y1060498D03*
X1399748Y1098518D03*
X1394496Y1098428D03*
X1388992Y1123101D03*
X1396992D03*
X1399492D03*
X1385866Y1131935D03*
Y1134435D03*
Y1136935D03*
Y1139435D03*
X1388992Y1125801D03*
X1397392D03*
X1399892D03*
X1387392Y1129301D03*
X1389892D03*
X1392392D03*
X1394892D03*
X1397392D03*
X1399892D03*
X1391856Y1155213D03*
Y1152713D03*
X1385866Y1141935D03*
Y1146935D03*
Y1144435D03*
X1393695Y1204405D03*
Y1206905D03*
Y1211905D03*
Y1209405D03*
X1385992Y1285466D03*
X1390492D03*
X1392000Y1644980D03*
X1409248Y109410D03*
Y102323D03*
X1404548Y116497D03*
X1402048D03*
X1404548Y109410D03*
X1409248Y116496D03*
X1402048Y130670D03*
Y123584D03*
X1404548Y123583D03*
X1409248Y130670D03*
Y123583D03*
X1404548Y130670D03*
X1409248Y137756D03*
X1402048Y137757D03*
X1408666Y324733D03*
X1411950Y448466D03*
X1408103Y555194D03*
X1410903D03*
X1408103Y563194D03*
X1410903D03*
X1408103Y571194D03*
X1410903D03*
X1406512Y581222D03*
X1403712D03*
Y591215D03*
X1406512D03*
X1405514Y611091D03*
X1405000Y656000D03*
Y699000D03*
X1404689Y910897D03*
X1413575Y915186D03*
X1413322Y958908D03*
X1404317Y989436D03*
X1411038Y985379D03*
X1404936Y1098767D03*
X1415494Y1139435D03*
Y1136935D03*
Y1134435D03*
Y1131935D03*
X1409092Y1136935D03*
Y1134435D03*
Y1139435D03*
Y1131935D03*
X1402392Y1125801D03*
X1404892D03*
X1402392Y1129301D03*
X1404892D03*
X1409092Y1141935D03*
X1416736Y1152713D03*
Y1155213D03*
X1402256D03*
Y1152713D03*
X1415494Y1144435D03*
Y1146935D03*
Y1141935D03*
X1409092Y1146935D03*
Y1144435D03*
X1407995Y1204617D03*
X1410310Y1200821D03*
Y1198321D03*
X1407995Y1207117D03*
Y1209617D03*
Y1212117D03*
X1415903Y1282590D03*
X1404019Y1285290D03*
X1414346Y1303020D03*
X1412000Y1644980D03*
X1417710Y82984D03*
Y75184D03*
Y77784D03*
Y80384D03*
X1420264Y92849D03*
X1417710Y85584D03*
X1427224Y103037D03*
X1427358Y116496D03*
Y109410D03*
Y130670D03*
Y123583D03*
X1423515Y137756D03*
X1429539Y293796D03*
X1432039D03*
X1431019Y434508D03*
X1427019D03*
X1424196Y446352D03*
X1428782Y445874D03*
X1417856Y455466D03*
X1433310Y504699D03*
X1430810D03*
X1433012Y516979D03*
X1430512D03*
X1427233Y628183D03*
X1424389Y627948D03*
X1426000Y709000D03*
Y713000D03*
Y757000D03*
Y753000D03*
X1422813Y910065D03*
X1424126Y900295D03*
X1427553Y939200D03*
X1427473Y965621D03*
X1420740Y1004766D03*
Y1000766D03*
Y1016266D03*
Y1030766D03*
X1420107Y1052514D03*
X1431876Y1098518D03*
X1426624Y1098428D03*
X1421120Y1123101D03*
X1429120D03*
X1431620D03*
X1422020Y1129301D03*
X1424520D03*
X1427020D03*
X1429520D03*
X1432020D03*
X1417994Y1139435D03*
Y1136935D03*
Y1134435D03*
Y1131935D03*
X1421120Y1125801D03*
X1429520D03*
X1432020D03*
X1419520Y1129301D03*
X1432384Y1155213D03*
Y1152713D03*
X1422984D03*
Y1155213D03*
X1417994Y1144435D03*
Y1146935D03*
Y1141935D03*
X1420625Y1204405D03*
Y1206905D03*
Y1209405D03*
X1425652Y1297411D03*
X1433386Y1343309D03*
X1428840Y1407740D03*
X1423065Y1508327D03*
X1432499Y1512175D03*
X1424245Y1543338D03*
X1425558Y1537432D03*
X1425260Y1558072D03*
X1433558Y1555366D03*
X1423701Y1563978D03*
X1432000Y1644980D03*
X1444641Y94017D03*
X1448641D03*
X1440641D03*
X1449761Y115401D03*
Y110445D03*
X1444769D03*
Y115401D03*
X1449761Y124618D03*
X1444769D03*
Y129574D03*
X1449761D03*
X1442682Y151540D03*
X1446332Y191941D03*
X1446199Y188727D03*
X1442956Y226141D03*
X1440156D03*
X1448026Y256535D03*
X1440053Y285690D03*
X1437553D03*
X1440053Y288190D03*
X1442853D03*
Y285690D03*
X1447079Y290755D03*
X1437553Y288190D03*
X1437758Y362584D03*
X1435019Y434508D03*
X1437757Y447201D03*
X1437879Y444269D03*
X1435810Y504699D03*
X1447036Y519518D03*
X1435512Y516979D03*
X1444536Y519518D03*
X1439536D03*
X1442036D03*
X1435241Y593796D03*
X1440930Y636005D03*
Y633205D03*
Y638805D03*
X1437784Y683532D03*
X1436567Y727532D03*
X1443000Y798500D03*
Y794500D03*
Y842500D03*
Y838500D03*
X1438188Y867633D03*
X1437703Y880067D03*
X1449072Y892581D03*
X1435288Y897500D03*
X1444453Y938806D03*
X1439449Y979009D03*
X1440610Y1021567D03*
X1435266Y1031522D03*
X1437064Y1098767D03*
X1441220Y1131935D03*
Y1139435D03*
Y1134435D03*
Y1136935D03*
X1434520Y1125801D03*
X1437020D03*
X1434520Y1129301D03*
X1437020D03*
X1441220Y1141935D03*
Y1144435D03*
Y1146935D03*
X1442448Y1152684D03*
X1434925Y1204617D03*
X1437240Y1200821D03*
Y1198321D03*
X1434925Y1207117D03*
Y1209617D03*
Y1212117D03*
X1436408Y1303462D03*
X1444438Y1308312D03*
X1439482D03*
X1441286Y1335776D03*
X1457718Y84140D03*
Y76140D03*
Y80140D03*
X1452650Y94017D03*
X1460163Y117557D03*
X1455171D03*
Y122513D03*
X1460163Y131731D03*
Y122513D03*
X1455171Y131731D03*
X1458262Y146461D03*
X1460163Y136687D03*
X1455171D03*
X1457164Y152367D03*
X1463547Y180527D03*
X1458864Y180572D03*
Y185165D03*
X1463502Y185121D03*
X1452832Y184619D03*
X1454812Y206760D03*
X1456026Y256535D03*
X1457056Y279208D03*
X1461160Y281307D03*
X1455079Y290755D03*
X1451079D03*
X1458982Y356861D03*
X1453000Y633450D03*
Y636250D03*
Y639050D03*
X1453032Y769032D03*
X1453775Y813032D03*
X1461241Y867475D03*
X1462694Y874859D03*
Y877859D03*
X1460472Y885985D03*
X1459420Y899226D03*
X1451005Y931848D03*
X1462819Y949996D03*
X1462000Y960378D03*
X1460655Y964253D03*
X1466076Y979746D03*
X1462388Y1006560D03*
X1455939Y1018368D03*
X1465503Y1030233D03*
X1460592Y1345691D03*
Y1350683D03*
X1465548Y1345691D03*
Y1350683D03*
X1460592Y1357603D03*
Y1362595D03*
X1465548Y1357603D03*
Y1362595D03*
X1460592Y1381801D03*
Y1374881D03*
Y1369889D03*
X1465548Y1381801D03*
Y1374881D03*
Y1369889D03*
X1460592Y1386793D03*
X1465548D03*
X1452000Y1644980D03*
X1480460Y60922D03*
X1475296Y55513D03*
X1471093Y117261D03*
X1478624Y113394D03*
X1481273Y110784D03*
X1481368Y130898D03*
X1478800Y180665D03*
Y172665D03*
X1467270Y192421D03*
X1478832Y200864D03*
Y212864D03*
Y216864D03*
Y221864D03*
X1480589Y252371D03*
X1473900Y433100D03*
X1478710Y685630D03*
X1473525Y710052D03*
X1474425Y716075D03*
X1479962Y727500D03*
X1471415Y748629D03*
X1474425Y760075D03*
X1473634Y864337D03*
X1481454Y911570D03*
X1474075Y920575D03*
X1474349Y949394D03*
X1468500Y974181D03*
X1479096Y997860D03*
X1471096D03*
X1475096D03*
X1467096D03*
X1471854Y1035088D03*
X1479624Y1035102D03*
X1468371Y1030701D03*
X1480193Y1102091D03*
X1474384D03*
X1480193Y1114691D03*
X1474384D03*
X1480193Y1127291D03*
X1474384D03*
X1480193Y1139891D03*
X1474384D03*
X1480193Y1152491D03*
X1474384D03*
X1480193Y1165091D03*
X1474384D03*
X1480193Y1177691D03*
X1474384D03*
X1480675Y1202103D03*
X1477788Y1350683D03*
Y1345691D03*
X1472832Y1350683D03*
Y1345691D03*
X1477788Y1357603D03*
Y1362595D03*
X1472832Y1357603D03*
Y1362595D03*
X1477788Y1381801D03*
Y1369795D03*
Y1374881D03*
X1472832Y1381801D03*
Y1369795D03*
Y1374881D03*
X1477788Y1386793D03*
Y1399079D03*
Y1393993D03*
X1472832Y1386793D03*
Y1393993D03*
Y1399079D03*
X1477788Y1405999D03*
Y1410991D03*
X1472832Y1405999D03*
Y1410991D03*
X1476094Y1465913D03*
Y1461182D03*
Y1456451D03*
Y1471805D03*
Y1481267D03*
Y1476536D03*
Y1491890D03*
Y1487159D03*
Y1496621D03*
Y1502514D03*
Y1511976D03*
Y1507245D03*
Y1563544D03*
Y1558813D03*
Y1568275D03*
Y1578898D03*
Y1574167D03*
Y1583629D03*
Y1594253D03*
Y1589522D03*
Y1609607D03*
Y1598984D03*
Y1604876D03*
Y1614338D03*
X1472000Y1644980D03*
X1493859Y109172D03*
X1496859D03*
X1495866Y106495D03*
X1488867Y133298D03*
X1495600Y146012D03*
X1497506Y141228D03*
X1483014Y134579D03*
X1495071Y253198D03*
X1486360Y358700D03*
Y354200D03*
X1496473Y769000D03*
X1491062Y793003D03*
X1491425Y801575D03*
X1496845Y813000D03*
X1491425Y845575D03*
X1489650Y836985D03*
X1489805Y866386D03*
X1497488Y873839D03*
X1491414Y875383D03*
X1494000Y884000D03*
X1498084Y894825D03*
X1492101Y894860D03*
X1496383Y898023D03*
X1496500Y919000D03*
X1496000Y922000D03*
X1487075Y920925D03*
X1485100Y943900D03*
X1496425Y943075D03*
X1496072Y950044D03*
X1482591Y961909D03*
X1486500Y947000D03*
X1485226Y973886D03*
X1492560Y974654D03*
X1495339Y1009354D03*
X1491839D03*
X1486030D03*
X1491096Y997860D03*
X1483096D03*
X1495096D03*
X1487096D03*
X1495339Y1021954D03*
X1491839D03*
X1486030D03*
X1483693Y1102091D03*
Y1114691D03*
Y1127291D03*
Y1139891D03*
Y1152491D03*
Y1165091D03*
Y1177691D03*
X1498197Y1209607D03*
X1492471Y1215195D03*
X1484055Y1223749D03*
X1497312Y1350683D03*
Y1345691D03*
X1485072D03*
Y1350683D03*
X1490028Y1345691D03*
Y1350683D03*
X1497312Y1357603D03*
Y1362595D03*
X1485072D03*
Y1357603D03*
X1490028D03*
Y1362595D03*
X1485072Y1369889D03*
Y1374881D03*
Y1381801D03*
X1490028Y1369889D03*
Y1374881D03*
Y1381801D03*
X1497312D03*
Y1374881D03*
Y1369889D03*
Y1386793D03*
Y1394087D03*
Y1399079D03*
X1485072Y1394087D03*
Y1399079D03*
Y1386793D03*
X1490028Y1399079D03*
Y1394087D03*
Y1386793D03*
X1497312Y1405999D03*
Y1410991D03*
X1485072Y1405999D03*
Y1410991D03*
X1490028Y1405999D03*
Y1410991D03*
X1484755Y1465513D03*
Y1460782D03*
X1493417Y1465913D03*
Y1456451D03*
Y1461182D03*
Y1471805D03*
Y1476536D03*
Y1481267D03*
X1484755Y1476136D03*
Y1470244D03*
Y1480867D03*
Y1496221D03*
X1493417Y1487159D03*
Y1491890D03*
Y1496621D03*
X1484755Y1491490D03*
Y1485598D03*
Y1506845D03*
Y1500952D03*
Y1511576D03*
X1493417Y1507245D03*
Y1502514D03*
Y1511976D03*
X1484755Y1516307D03*
Y1563144D03*
X1493417Y1558813D03*
Y1563544D03*
Y1578898D03*
X1484755Y1567875D03*
Y1578498D03*
Y1572606D03*
X1493417Y1568275D03*
Y1574167D03*
X1484755Y1583229D03*
Y1593853D03*
Y1587960D03*
X1493417Y1583629D03*
Y1589522D03*
Y1594253D03*
X1484755Y1609207D03*
Y1598584D03*
Y1603315D03*
X1493417Y1609607D03*
Y1604876D03*
Y1598984D03*
X1484755Y1613938D03*
Y1618669D03*
X1493417Y1614338D03*
X1492000Y1644980D03*
X1511610Y116496D03*
Y109410D03*
Y102323D03*
X1499610Y116497D03*
X1506910D03*
X1504410D03*
X1506910Y109410D03*
X1511610Y123583D03*
X1499610Y130670D03*
Y123584D03*
X1506910Y130670D03*
X1504410D03*
Y123584D03*
X1506910Y123583D03*
X1511610Y130670D03*
Y137756D03*
X1499610Y137757D03*
X1504410D03*
X1500394Y150847D03*
X1502362Y247292D03*
X1501807Y323766D03*
X1507864Y450750D03*
X1511963Y536382D03*
X1510280Y899732D03*
X1514354Y938811D03*
X1510500Y931500D03*
X1513955Y950396D03*
X1505888Y965964D03*
X1514000Y968739D03*
X1510740Y973740D03*
X1507096Y997860D03*
X1503096D03*
X1511096D03*
X1499096D03*
X1505130Y1105091D03*
Y1117691D03*
Y1130291D03*
Y1142891D03*
Y1155491D03*
Y1168091D03*
Y1180691D03*
X1509552Y1350683D03*
Y1345691D03*
X1514508Y1350683D03*
Y1345691D03*
X1502268Y1350683D03*
Y1345691D03*
X1509552Y1362595D03*
Y1357603D03*
X1514508D03*
Y1362595D03*
X1502268Y1357603D03*
Y1362595D03*
X1509552Y1374881D03*
Y1369889D03*
Y1381801D03*
X1514508Y1374881D03*
Y1369889D03*
Y1381801D03*
X1502268D03*
Y1374881D03*
Y1369889D03*
X1509552Y1394087D03*
Y1399079D03*
Y1386793D03*
X1514508Y1394087D03*
Y1399079D03*
Y1386793D03*
X1502268D03*
Y1399079D03*
Y1394087D03*
X1509552Y1405999D03*
Y1410991D03*
X1514508Y1405999D03*
Y1410991D03*
X1502268Y1405999D03*
Y1410991D03*
X1502078Y1465513D03*
Y1460782D03*
X1510740Y1465913D03*
Y1456451D03*
Y1461182D03*
X1502078Y1470244D03*
Y1480867D03*
X1510740Y1471805D03*
Y1476536D03*
Y1481267D03*
X1502078Y1476136D03*
Y1491490D03*
Y1485598D03*
Y1496221D03*
X1510740Y1487159D03*
Y1491890D03*
Y1496621D03*
Y1507245D03*
Y1502514D03*
Y1511976D03*
X1502078Y1506845D03*
Y1500952D03*
Y1511576D03*
Y1516307D03*
X1510740Y1563544D03*
X1502078Y1563144D03*
X1510740Y1558813D03*
Y1578898D03*
X1502078Y1567875D03*
Y1578498D03*
Y1572606D03*
X1510740Y1568275D03*
Y1574167D03*
X1502078Y1583229D03*
Y1593853D03*
Y1587960D03*
X1510740Y1583629D03*
Y1589522D03*
Y1594253D03*
X1502078Y1609207D03*
Y1598584D03*
Y1603315D03*
X1510740Y1609607D03*
Y1604876D03*
Y1598984D03*
X1502078Y1613938D03*
Y1618669D03*
X1510740Y1614338D03*
X1512000Y1644980D03*
X1520072Y82984D03*
Y75184D03*
Y77784D03*
Y80384D03*
X1522626Y92849D03*
X1520072Y85584D03*
X1529586Y103037D03*
X1529720Y116496D03*
Y109410D03*
Y130670D03*
Y123583D03*
X1526311Y137756D03*
X1528635Y555234D03*
X1528350Y562003D03*
X1519156Y596095D03*
X1516869Y594668D03*
X1518354Y592354D03*
X1518415Y589556D03*
X1519153Y599588D03*
X1516930Y597580D03*
X1519185Y615600D03*
X1519153Y607588D03*
X1523646Y634946D03*
X1519063Y876339D03*
X1517344Y896999D03*
X1515743Y888133D03*
X1517344Y903179D03*
X1517153Y908367D03*
X1523000Y923740D03*
X1526611Y921442D03*
X1525740Y928740D03*
X1528087Y936394D03*
X1524500Y949500D03*
X1530174Y956986D03*
X1525522Y971075D03*
X1523966Y980281D03*
X1515096Y997860D03*
X1531096D03*
X1519096D03*
X1523096D03*
X1516776Y1024954D03*
Y1012354D03*
X1526748Y1345691D03*
Y1350683D03*
X1521792Y1345691D03*
Y1350683D03*
X1526748Y1357603D03*
Y1362595D03*
X1521792Y1357603D03*
Y1362595D03*
X1526748Y1369889D03*
Y1374881D03*
Y1381801D03*
X1521792Y1374881D03*
Y1381801D03*
Y1369889D03*
X1526748Y1386793D03*
Y1399079D03*
Y1394087D03*
X1521792Y1386793D03*
Y1394087D03*
Y1399079D03*
X1526748Y1405999D03*
Y1410991D03*
X1521792Y1405999D03*
Y1410991D03*
X1519401Y1465513D03*
Y1460782D03*
X1528062Y1465913D03*
Y1456451D03*
Y1461182D03*
Y1481267D03*
X1519401Y1476136D03*
Y1470244D03*
Y1480867D03*
X1528062Y1471805D03*
Y1476536D03*
X1519401Y1491490D03*
Y1485598D03*
Y1496221D03*
X1528062Y1487159D03*
Y1491890D03*
Y1496621D03*
X1519401Y1506845D03*
Y1500952D03*
Y1511576D03*
X1528062Y1507245D03*
Y1502514D03*
Y1511976D03*
X1519401Y1516307D03*
Y1563144D03*
X1528062Y1558813D03*
Y1563544D03*
Y1578898D03*
X1519401Y1567875D03*
Y1578498D03*
Y1572606D03*
X1528062Y1568275D03*
Y1574167D03*
X1519401Y1587960D03*
X1528062Y1583629D03*
Y1589522D03*
Y1594253D03*
X1519401Y1583229D03*
Y1593853D03*
Y1609207D03*
Y1598584D03*
Y1603315D03*
X1528062Y1609607D03*
Y1604876D03*
Y1598984D03*
X1519401Y1613938D03*
Y1618669D03*
X1528062Y1614338D03*
X1547003Y94017D03*
X1543003D03*
X1547131Y110445D03*
Y115401D03*
Y129574D03*
Y124618D03*
X1545044Y151540D03*
X1548561Y188727D03*
X1542518Y226141D03*
X1545318D03*
X1531901Y293796D03*
X1539915Y288190D03*
X1542415Y285690D03*
X1539915D03*
X1542415Y288190D03*
X1545215D03*
Y285690D03*
X1534401Y293796D03*
X1541283Y354553D03*
X1546272Y1350683D03*
Y1345691D03*
X1534032Y1350683D03*
Y1345691D03*
X1538988D03*
Y1350683D03*
X1546272Y1357603D03*
Y1362595D03*
X1534032Y1357603D03*
Y1362595D03*
X1538988D03*
Y1357603D03*
X1546272Y1374881D03*
Y1369889D03*
Y1381801D03*
X1534032Y1369889D03*
Y1381801D03*
Y1374881D03*
X1538988Y1369889D03*
Y1381801D03*
Y1374881D03*
X1546272Y1386793D03*
Y1394087D03*
Y1399079D03*
X1534032Y1394087D03*
Y1399079D03*
Y1386793D03*
X1538988Y1394087D03*
Y1399079D03*
Y1386793D03*
X1546272Y1405999D03*
Y1410991D03*
X1534032Y1405999D03*
Y1410991D03*
X1538988Y1405999D03*
Y1410991D03*
X1545385Y1461183D03*
X1536724Y1465513D03*
Y1460782D03*
X1545385Y1465914D03*
Y1456452D03*
X1536724Y1476136D03*
Y1470244D03*
Y1480867D03*
X1545385Y1476537D03*
Y1471806D03*
Y1481268D03*
X1536724Y1491490D03*
Y1485598D03*
Y1496221D03*
X1545385Y1491891D03*
Y1487160D03*
Y1496622D03*
X1536724Y1506845D03*
Y1500952D03*
Y1511576D03*
X1545385Y1507246D03*
Y1502515D03*
Y1511977D03*
X1536724Y1516307D03*
X1545385Y1563544D03*
Y1558813D03*
X1536724Y1563144D03*
Y1567875D03*
X1545385Y1568275D03*
X1536724Y1578498D03*
Y1572606D03*
X1545385Y1578898D03*
Y1574167D03*
Y1594253D03*
Y1589522D03*
X1536724Y1583229D03*
X1545385Y1583629D03*
X1536724Y1593853D03*
Y1587960D03*
Y1609207D03*
Y1598584D03*
Y1603315D03*
X1545385Y1609607D03*
Y1598984D03*
Y1604876D03*
Y1614338D03*
X1536724Y1613938D03*
Y1618669D03*
X1532000Y1644980D03*
X1560080Y84140D03*
Y76140D03*
Y80140D03*
X1555012Y94017D03*
X1551003D03*
X1562525Y117557D03*
X1557533D03*
X1552123Y115401D03*
Y110445D03*
X1562525Y122513D03*
X1552123Y129574D03*
Y124618D03*
X1557533Y131731D03*
Y122513D03*
X1562525Y131731D03*
X1560624Y146461D03*
X1557533Y136687D03*
X1562525D03*
X1559526Y152367D03*
X1561226Y180572D03*
X1548694Y191941D03*
X1555194Y184619D03*
X1561226Y185165D03*
X1557174Y206760D03*
X1550388Y256535D03*
X1558388D03*
X1559418Y279208D03*
X1563522Y281307D03*
X1549441Y290755D03*
X1553441D03*
X1557441D03*
X1554403Y352363D03*
X1563248Y389154D03*
X1548629D03*
Y403327D03*
Y410413D03*
X1561778Y396240D03*
X1548629D03*
Y417500D03*
Y424587D03*
Y438760D03*
Y431673D03*
Y445847D03*
Y467539D03*
Y474626D03*
Y488799D03*
Y481713D03*
Y495886D03*
Y511673D03*
Y518760D03*
X1562089Y516841D03*
X1548629Y540020D03*
Y525847D03*
Y532933D03*
Y547106D03*
X1556914Y552872D03*
X1557036Y550123D03*
X1556359Y562443D03*
X1558668Y572334D03*
X1558127Y560675D03*
X1556900Y574102D03*
X1547910Y602197D03*
X1548374Y595108D03*
X1561535Y653161D03*
X1565132Y677843D03*
X1547813Y906581D03*
X1551099Y959096D03*
X1558512Y1345691D03*
Y1350683D03*
X1563468D03*
Y1345691D03*
X1551228Y1350683D03*
Y1345691D03*
X1563468Y1362595D03*
X1551228Y1357603D03*
Y1362595D03*
X1558512D03*
Y1357603D03*
X1563468D03*
X1558512Y1374881D03*
Y1369889D03*
Y1381801D03*
X1563468Y1374881D03*
Y1369889D03*
Y1381801D03*
X1551228Y1369889D03*
Y1381801D03*
Y1374881D03*
X1558512Y1399079D03*
Y1394087D03*
Y1386793D03*
X1563468Y1399079D03*
Y1394087D03*
Y1386793D03*
X1551228D03*
Y1394087D03*
Y1399079D03*
X1558512Y1405999D03*
Y1410991D03*
X1563468Y1405999D03*
Y1410991D03*
X1551228Y1405999D03*
Y1410991D03*
X1552000Y1644980D03*
X1576256Y-25273D03*
X1573003Y-25287D03*
X1576241Y-27788D03*
X1572988Y-27802D03*
X1579281Y-26693D03*
X1573455Y117261D03*
X1565909Y180527D03*
X1569632Y192421D03*
X1565864Y185121D03*
X1571625Y333549D03*
X1579340Y396240D03*
Y403327D03*
Y410413D03*
X1566555Y414823D03*
X1565863Y422864D03*
X1579340Y417500D03*
Y424586D03*
X1565933Y429832D03*
X1565538Y436447D03*
X1579340Y431673D03*
Y438760D03*
X1567573Y447953D03*
X1579340Y445847D03*
X1566740Y467539D03*
X1565482Y472772D03*
X1579340Y474626D03*
Y488799D03*
X1566216Y487711D03*
X1566329Y479104D03*
X1579340Y481712D03*
Y495886D03*
X1566740D03*
X1579340Y518760D03*
X1565050Y511673D03*
X1579340Y540020D03*
Y532933D03*
Y525846D03*
X1574222Y629872D03*
X1569926Y668885D03*
X1575950Y662981D03*
X1570331Y691851D03*
X1575942Y705043D03*
X1575708Y1345597D03*
X1570752Y1350683D03*
Y1345597D03*
X1575708Y1350683D03*
X1570752Y1357603D03*
Y1362595D03*
X1575708D03*
Y1357603D03*
Y1381801D03*
Y1374881D03*
Y1369889D03*
X1570752D03*
Y1381801D03*
Y1374881D03*
X1575708Y1386793D03*
Y1399079D03*
Y1393993D03*
X1570752Y1386793D03*
Y1393993D03*
Y1399079D03*
X1575708Y1405999D03*
Y1410991D03*
X1570752Y1405999D03*
Y1410991D03*
X1572000Y1644980D03*
X1586256Y-64207D03*
X1583003D03*
X1586241Y-66722D03*
X1582988D03*
X1589281Y-65613D03*
X1582822Y60922D03*
X1580327Y57448D03*
X1580986Y113394D03*
X1583635Y110784D03*
X1591229Y133298D03*
X1583229D03*
X1585376Y134579D03*
X1581162Y180665D03*
Y172665D03*
X1581194Y212864D03*
Y200864D03*
Y221864D03*
Y216864D03*
X1582951Y252371D03*
X1586640Y389153D03*
X1581840D03*
Y403326D03*
Y410413D03*
X1586640D03*
X1581840Y396240D03*
X1586640D03*
Y403326D03*
Y417499D03*
X1581840D03*
Y424586D03*
X1586640D03*
X1581840Y438760D03*
X1586640D03*
Y431673D03*
X1581840D03*
X1586640Y467539D03*
X1581840D03*
Y474626D03*
X1586640D03*
X1581840Y488799D03*
X1586640D03*
X1581840Y481712D03*
X1586640D03*
X1581840Y518760D03*
Y511673D03*
X1586640D03*
Y518760D03*
Y525846D03*
Y532933D03*
X1581840D03*
Y525846D03*
X1595185Y543925D03*
X1595760Y555000D03*
X1583720Y560500D03*
X1587948Y1350683D03*
Y1345691D03*
X1582992D03*
Y1350683D03*
X1587948Y1362595D03*
Y1357603D03*
X1582992Y1362595D03*
Y1357603D03*
Y1369889D03*
Y1381801D03*
Y1374881D03*
X1587948Y1369889D03*
Y1381801D03*
Y1374881D03*
X1582992Y1399079D03*
Y1394087D03*
Y1386793D03*
X1587948Y1399079D03*
Y1394087D03*
Y1386793D03*
X1582992Y1405999D03*
Y1410991D03*
X1587948Y1405999D03*
Y1410991D03*
X1592020Y1433061D03*
X1591610Y1469940D03*
X1591586Y1505130D03*
X1609272Y109410D03*
X1601972Y116497D03*
X1609272D03*
X1606772D03*
X1596221Y109172D03*
X1599221D03*
X1598228Y106495D03*
X1601972Y123584D03*
Y130670D03*
X1606772Y123584D03*
X1609272Y123583D03*
Y130670D03*
X1606772D03*
Y137757D03*
X1597962Y146012D03*
X1599868Y141228D03*
X1601972Y137757D03*
X1602756Y150847D03*
X1604724Y247292D03*
X1597433Y253198D03*
X1608240Y329000D03*
X1603664Y342596D03*
X1598223Y351003D03*
X1599127Y375587D03*
X1596714Y383003D03*
X1614338Y636842D03*
X1610620Y1345691D03*
Y1350683D03*
Y1357603D03*
Y1362595D03*
Y1381801D03*
Y1374881D03*
Y1369889D03*
Y1386793D03*
X1597225Y1437014D03*
X1603363Y1460570D03*
X1597457Y1452556D03*
X1598500Y1472500D03*
X1606745Y1474242D03*
X1602580Y1483108D03*
X1598000Y1486000D03*
X1604000Y1516000D03*
X1600700Y1534300D03*
X1622434Y82984D03*
Y80384D03*
Y75184D03*
Y77784D03*
X1624988Y92849D03*
X1622434Y85584D03*
X1613972Y116496D03*
Y102323D03*
Y109410D03*
Y130670D03*
Y123583D03*
Y137756D03*
X1625952Y431029D03*
X1626260Y427017D03*
X1625018Y435029D03*
X1625938Y449873D03*
X1625565Y472579D03*
Y479666D03*
Y486752D03*
Y493839D03*
Y523800D03*
Y516713D03*
Y537973D03*
Y530886D03*
Y566752D03*
Y588013D03*
Y573839D03*
Y580926D03*
Y602186D03*
Y595099D03*
Y609272D03*
Y616359D03*
X1620244Y638125D03*
X1617843Y665140D03*
X1613110Y678462D03*
X1624148Y708258D03*
X1627455Y759489D03*
X1619612Y783152D03*
X1620359Y774830D03*
X1619569Y796035D03*
X1620755Y787530D03*
X1613235Y808466D03*
X1620479Y815730D03*
X1620072Y801630D03*
X1616255Y824405D03*
X1619859Y839519D03*
X1615576Y1345691D03*
Y1350683D03*
X1622860D03*
Y1345691D03*
X1627816Y1350683D03*
Y1345691D03*
X1615576Y1357603D03*
Y1362595D03*
X1622860Y1357603D03*
Y1362595D03*
X1627816Y1357603D03*
Y1362595D03*
X1622860Y1381801D03*
Y1369795D03*
Y1374881D03*
X1627816Y1381801D03*
Y1369795D03*
Y1374881D03*
X1615576Y1381801D03*
Y1374881D03*
Y1369889D03*
Y1386793D03*
X1622860D03*
Y1393993D03*
Y1399079D03*
X1627816Y1386793D03*
Y1399079D03*
Y1393993D03*
X1622860Y1405999D03*
Y1410991D03*
X1627816Y1405999D03*
Y1410991D03*
X1618800Y1528558D03*
X1614200Y1519500D03*
X1614360Y1542860D03*
X1618600Y1532000D03*
X1631948Y103037D03*
X1632082Y116496D03*
Y109410D03*
Y130670D03*
Y123583D03*
X1628673Y137756D03*
X1644880Y226141D03*
X1644777Y288190D03*
X1642277Y285690D03*
X1644777D03*
X1642277Y288190D03*
X1636763Y293796D03*
X1634263D03*
X1635987Y335616D03*
X1630703Y350655D03*
X1636468Y345595D03*
X1636271Y410394D03*
Y403307D03*
X1637665Y458406D03*
Y451319D03*
X1637489Y462264D03*
X1632865Y465492D03*
X1637665D03*
Y472579D03*
X1632865D03*
X1630365D03*
Y479666D03*
X1632865D03*
X1637665Y479665D03*
Y486752D03*
X1630365D03*
X1632865D03*
X1630365Y493839D03*
X1637665D03*
X1632865Y509626D03*
Y516713D03*
X1630365D03*
Y523800D03*
X1632865D03*
X1637665Y523799D03*
Y516713D03*
Y509626D03*
X1630365Y530886D03*
X1637665D03*
X1632865D03*
X1637665Y537973D03*
X1630365D03*
X1637665Y559665D03*
Y566752D03*
X1630365D03*
X1632865D03*
Y559665D03*
Y573839D03*
X1630365Y580926D03*
X1632865D03*
X1637665D03*
Y588012D03*
X1630365Y588013D03*
X1632865Y588012D03*
X1637665Y573839D03*
X1630365D03*
X1632865Y602185D03*
X1630365Y602186D03*
X1637665Y602185D03*
Y595099D03*
X1632865D03*
X1630365D03*
Y616359D03*
X1632865Y609272D03*
X1630365D03*
X1637665Y616358D03*
Y609272D03*
X1637526Y699930D03*
X1637472Y717830D03*
X1631031Y732430D03*
X1628813Y727045D03*
X1631187Y750630D03*
X1629969Y740826D03*
X1644304Y891353D03*
X1640056Y1345691D03*
Y1350683D03*
X1635100Y1345691D03*
Y1350683D03*
X1640056Y1357603D03*
Y1362595D03*
X1635100D03*
Y1357603D03*
X1640056Y1369889D03*
Y1374881D03*
Y1381801D03*
X1635100Y1369889D03*
Y1374881D03*
Y1381801D03*
X1640056Y1399079D03*
Y1394087D03*
Y1386793D03*
X1635100Y1394087D03*
Y1399079D03*
Y1386793D03*
Y1405999D03*
Y1410991D03*
X1640056Y1405999D03*
Y1410991D03*
X1649365Y94017D03*
X1657374D03*
X1653365D03*
X1645365D03*
X1659895Y117557D03*
X1654485Y110445D03*
Y115401D03*
X1649493Y110445D03*
Y115401D03*
X1659895Y122513D03*
Y131731D03*
X1654485Y124618D03*
Y129574D03*
X1649493Y124618D03*
Y129574D03*
X1659895Y136687D03*
X1647406Y151540D03*
X1651056Y191941D03*
X1657556Y184619D03*
X1650923Y188727D03*
X1659536Y206760D03*
X1647680Y226141D03*
X1660750Y256535D03*
X1652750D03*
X1647577Y285690D03*
Y288190D03*
X1655803Y290755D03*
X1651803D03*
X1659803D03*
X1645685Y390500D03*
X1655335Y381500D03*
X1653507Y470136D03*
X1655776Y465492D03*
X1655742Y460250D03*
X1655776Y472579D03*
Y486752D03*
Y479665D03*
Y493839D03*
Y509626D03*
Y516713D03*
X1652236Y537973D03*
X1654716Y525483D03*
X1654637Y532756D03*
X1655776Y559665D03*
Y566752D03*
X1655626Y579978D03*
X1655776Y573839D03*
X1655840Y608117D03*
X1654572Y771702D03*
X1645128Y929263D03*
X1645342Y962120D03*
X1657091Y990823D03*
X1649571Y983857D03*
X1647340Y1350683D03*
Y1345691D03*
X1652296Y1350683D03*
Y1345691D03*
X1659580Y1350683D03*
Y1345691D03*
X1647340Y1357603D03*
Y1362595D03*
X1652296Y1357603D03*
Y1362595D03*
X1659580D03*
Y1357603D03*
X1647340Y1381801D03*
Y1374881D03*
Y1369889D03*
X1652296Y1381801D03*
Y1374881D03*
Y1369889D03*
X1659580Y1374881D03*
Y1369889D03*
Y1381801D03*
X1647340Y1386793D03*
Y1394087D03*
Y1399079D03*
X1652296Y1386793D03*
Y1399079D03*
Y1394087D03*
X1659580D03*
Y1399079D03*
Y1386793D03*
X1647340Y1405999D03*
Y1410991D03*
X1652296Y1405999D03*
Y1410991D03*
X1659580Y1405999D03*
Y1410991D03*
X1657983Y1460782D03*
X1649322Y1456451D03*
Y1465913D03*
X1657983Y1465513D03*
X1649322Y1461182D03*
Y1476536D03*
X1657983Y1476136D03*
Y1470244D03*
X1649322Y1471805D03*
Y1481267D03*
X1657983Y1480867D03*
X1649322Y1487159D03*
Y1496621D03*
X1657983Y1496221D03*
X1649322Y1491890D03*
X1657983Y1491490D03*
Y1485598D03*
Y1500952D03*
X1649322Y1502514D03*
X1657983Y1511576D03*
X1649322Y1511976D03*
Y1507245D03*
X1657983Y1506845D03*
Y1516307D03*
X1649322Y1558813D03*
Y1563544D03*
X1657983Y1563144D03*
Y1572606D03*
X1649322Y1574167D03*
Y1568275D03*
X1657983Y1567875D03*
X1649322Y1578898D03*
X1657983Y1578498D03*
X1649322Y1583629D03*
X1657983Y1583229D03*
X1649322Y1594253D03*
X1657983Y1593853D03*
Y1587960D03*
X1649322Y1589522D03*
Y1609607D03*
X1657983Y1609207D03*
X1649322Y1598984D03*
X1657983Y1598584D03*
Y1603315D03*
X1649322Y1604876D03*
Y1614338D03*
X1657983Y1613938D03*
Y1618669D03*
X1652000Y1644980D03*
X1662442Y84140D03*
Y76140D03*
Y80140D03*
X1675817Y117261D03*
X1664887Y117557D03*
Y122513D03*
Y131731D03*
X1662986Y146461D03*
X1664887Y136687D03*
X1661888Y152367D03*
X1663588Y180572D03*
X1668271Y180527D03*
X1671994Y192421D03*
X1663588Y185165D03*
X1668226Y185121D03*
X1661780Y279208D03*
X1665884Y281307D03*
X1669767Y445908D03*
X1673717Y445787D03*
X1664536Y1350683D03*
Y1345691D03*
X1671820D03*
Y1350683D03*
X1676776Y1345691D03*
Y1350683D03*
X1664536Y1357603D03*
Y1362595D03*
X1671820Y1357603D03*
Y1362595D03*
X1676776Y1357603D03*
Y1362595D03*
X1664536Y1374881D03*
Y1369889D03*
Y1381801D03*
X1671820Y1374881D03*
Y1381801D03*
Y1369889D03*
X1676776D03*
Y1374881D03*
Y1381801D03*
X1664536Y1394087D03*
Y1399079D03*
Y1386793D03*
X1671820D03*
Y1394087D03*
Y1399079D03*
X1676776Y1386793D03*
Y1399079D03*
Y1394087D03*
X1664536Y1405999D03*
Y1410991D03*
X1671820Y1405999D03*
Y1410991D03*
X1676776Y1405999D03*
Y1410991D03*
X1666645Y1465913D03*
Y1456451D03*
Y1461182D03*
X1675306Y1465513D03*
Y1460782D03*
X1666645Y1471805D03*
Y1476536D03*
Y1481267D03*
X1675306Y1476136D03*
Y1470244D03*
Y1480867D03*
X1666645Y1487159D03*
Y1491890D03*
Y1496621D03*
X1675306Y1491490D03*
Y1485598D03*
Y1496221D03*
Y1511576D03*
X1666645Y1511976D03*
Y1507245D03*
Y1502514D03*
X1675306Y1506845D03*
Y1500952D03*
Y1516307D03*
X1666645Y1558813D03*
Y1563544D03*
X1675306Y1563144D03*
Y1578498D03*
Y1572606D03*
X1666645Y1568275D03*
X1675306Y1567875D03*
X1666645Y1574167D03*
Y1578898D03*
Y1583629D03*
X1675306Y1583229D03*
X1666645Y1589522D03*
Y1594253D03*
X1675306Y1593853D03*
Y1587960D03*
X1666645Y1604876D03*
Y1598984D03*
X1675306Y1609207D03*
Y1598584D03*
Y1603315D03*
X1666645Y1609607D03*
Y1614338D03*
X1675306Y1613938D03*
Y1618669D03*
X1672000Y1644980D03*
X1685184Y60922D03*
X1680020Y55513D03*
X1683348Y113394D03*
X1685997Y110784D03*
X1686171Y130898D03*
X1693591Y133298D03*
X1687738Y134579D03*
X1683524Y172665D03*
Y180665D03*
X1683556Y200864D03*
Y212864D03*
Y221864D03*
Y216864D03*
X1685313Y252371D03*
X1687164Y336324D03*
X1678072Y342319D03*
X1691743Y353506D03*
X1680518Y385912D03*
Y393924D03*
Y389912D03*
Y409924D03*
Y405924D03*
Y401924D03*
X1677933Y418838D03*
X1689016Y1345691D03*
Y1350683D03*
X1684060D03*
Y1345691D03*
X1689016Y1362595D03*
Y1357603D03*
X1684060D03*
Y1362595D03*
X1689016Y1369889D03*
Y1381801D03*
Y1374881D03*
X1684060Y1369889D03*
Y1381801D03*
Y1374881D03*
X1689016Y1394087D03*
Y1399079D03*
Y1386793D03*
X1684060Y1394087D03*
Y1399079D03*
Y1386793D03*
X1689016Y1405999D03*
Y1410991D03*
X1684060Y1405999D03*
Y1410991D03*
X1683968Y1465913D03*
Y1456451D03*
Y1461182D03*
X1692629Y1465513D03*
Y1460782D03*
X1683968Y1471805D03*
Y1476536D03*
Y1481267D03*
X1692629Y1476136D03*
Y1470244D03*
Y1480867D03*
X1683968Y1487159D03*
Y1491890D03*
Y1496621D03*
X1692629Y1491490D03*
Y1485598D03*
Y1496221D03*
X1683968Y1502514D03*
Y1511976D03*
X1692629Y1506845D03*
Y1500952D03*
Y1511576D03*
X1683968Y1507245D03*
X1692629Y1516307D03*
X1683968Y1558813D03*
Y1563544D03*
X1692629Y1563144D03*
Y1572606D03*
X1683968Y1568275D03*
Y1574167D03*
Y1578898D03*
X1692629Y1567875D03*
Y1578498D03*
X1683968Y1583629D03*
Y1589522D03*
Y1594253D03*
X1692629Y1583229D03*
Y1593853D03*
Y1587960D03*
X1683968Y1598984D03*
X1692629Y1609207D03*
Y1598584D03*
Y1603315D03*
X1683968Y1609607D03*
Y1604876D03*
Y1614338D03*
X1692629Y1613938D03*
Y1618669D03*
X1692000Y1644980D03*
X1698583Y109172D03*
X1701583D03*
X1700590Y106495D03*
X1709134Y116497D03*
X1704334D03*
X1709134Y123584D03*
Y130670D03*
X1704334Y123584D03*
Y130670D03*
X1700324Y146012D03*
X1702230Y141228D03*
X1709134Y137757D03*
X1704334D03*
X1705118Y150847D03*
X1707086Y247292D03*
X1699795Y253198D03*
X1701495Y289735D03*
X1695142Y303839D03*
X1708889Y1189221D03*
X1696300Y1350683D03*
Y1345691D03*
X1701256Y1350683D03*
Y1345691D03*
X1708540D03*
Y1350683D03*
X1696300Y1357603D03*
Y1362595D03*
X1701256Y1357603D03*
Y1362595D03*
X1708540D03*
Y1357603D03*
X1696300Y1374881D03*
Y1369889D03*
Y1381801D03*
X1701256Y1369889D03*
Y1381801D03*
Y1374881D03*
X1708540D03*
Y1369889D03*
Y1381801D03*
X1696300Y1386793D03*
Y1394087D03*
Y1399079D03*
X1701256Y1386793D03*
Y1394087D03*
Y1399079D03*
X1708540D03*
Y1394087D03*
Y1386793D03*
X1696300Y1405999D03*
Y1410991D03*
X1701256Y1405999D03*
Y1410991D03*
X1708540Y1405999D03*
Y1410991D03*
X1701290Y1465913D03*
Y1456451D03*
Y1461182D03*
Y1471805D03*
Y1476536D03*
Y1481267D03*
Y1487159D03*
Y1491890D03*
Y1496621D03*
Y1507245D03*
Y1502514D03*
Y1511976D03*
Y1558813D03*
Y1563544D03*
Y1568275D03*
Y1574167D03*
Y1578898D03*
Y1583629D03*
Y1589522D03*
Y1594253D03*
Y1609607D03*
Y1604876D03*
Y1598984D03*
Y1614338D03*
X1724796Y82984D03*
Y77784D03*
Y80384D03*
Y75184D03*
Y85584D03*
X1716334Y116496D03*
Y109410D03*
Y102323D03*
X1711634Y116497D03*
Y109410D03*
X1716334Y130670D03*
Y123583D03*
X1711634D03*
Y130670D03*
X1716334Y137756D03*
X1720960Y1148000D03*
X1723796Y1160168D03*
X1725660Y1193019D03*
X1721660D03*
X1711783Y1193848D03*
X1713496Y1350683D03*
Y1345691D03*
X1720780Y1350683D03*
Y1345597D03*
X1725736Y1350683D03*
Y1345597D03*
X1713496Y1357603D03*
Y1362595D03*
X1720780Y1357603D03*
Y1362595D03*
X1725736Y1357603D03*
Y1362595D03*
X1713496Y1374881D03*
Y1369889D03*
Y1381801D03*
X1720780Y1369889D03*
Y1381801D03*
Y1374881D03*
X1725736Y1381801D03*
Y1374881D03*
Y1369889D03*
X1713496Y1399079D03*
Y1394087D03*
Y1386793D03*
X1720780D03*
Y1393993D03*
Y1399079D03*
X1725736Y1386793D03*
Y1399079D03*
Y1393993D03*
X1713496Y1405999D03*
Y1410991D03*
X1720780Y1405999D03*
Y1410991D03*
X1725736Y1405999D03*
Y1410991D03*
X1709952Y1465513D03*
Y1460782D03*
X1718613Y1465914D03*
Y1456452D03*
Y1461183D03*
Y1476537D03*
Y1471806D03*
Y1481268D03*
X1709952Y1476136D03*
Y1470244D03*
Y1480867D03*
Y1491490D03*
Y1485598D03*
Y1496221D03*
X1718613Y1491891D03*
Y1487160D03*
Y1496622D03*
Y1502515D03*
Y1511977D03*
X1709952Y1506845D03*
Y1500952D03*
Y1511576D03*
X1718613Y1507246D03*
X1709952Y1516307D03*
Y1563144D03*
X1718613Y1563544D03*
Y1558813D03*
X1709952Y1567875D03*
X1718613Y1568275D03*
X1709952Y1578498D03*
Y1572606D03*
X1718613Y1578898D03*
Y1574167D03*
Y1589522D03*
X1709952Y1583229D03*
X1718613Y1583629D03*
X1709952Y1593853D03*
Y1587960D03*
X1718613Y1594253D03*
Y1609607D03*
Y1598984D03*
Y1604876D03*
X1709952Y1609207D03*
Y1598584D03*
Y1603315D03*
Y1618669D03*
X1718613Y1614338D03*
X1709952Y1613938D03*
X1712000Y1644980D03*
X1727350Y92849D03*
X1734310Y103037D03*
X1734444Y116496D03*
Y109410D03*
Y130670D03*
Y123583D03*
X1730647Y137756D03*
X1739125Y293796D03*
X1736625D03*
X1737703Y472189D03*
X1728038Y491870D03*
X1730538D03*
X1730675Y1132361D03*
X1726963Y1132319D03*
X1739917Y1146937D03*
X1729207Y1159455D03*
X1737393Y1162817D03*
X1733660Y1193019D03*
X1729660D03*
X1737660D03*
X1733695Y1212164D03*
X1735989Y1214458D03*
X1731619Y1210089D03*
X1740785Y1219254D03*
X1737976Y1350683D03*
Y1345691D03*
X1733020D03*
Y1350683D03*
X1737976Y1362595D03*
Y1357603D03*
X1733020Y1362595D03*
Y1357603D03*
X1737976Y1369889D03*
Y1374881D03*
X1733020Y1369889D03*
Y1381801D03*
Y1374881D03*
X1737976Y1381801D03*
Y1399079D03*
Y1394087D03*
Y1386793D03*
X1733020Y1399079D03*
Y1394087D03*
Y1386793D03*
X1737976Y1405999D03*
Y1410991D03*
X1733020Y1405999D03*
Y1410991D03*
X1732000Y1644980D03*
X1755727Y94017D03*
X1747727D03*
X1751727D03*
X1751855Y110445D03*
Y115401D03*
X1756847D03*
Y110445D03*
X1751855Y129574D03*
Y124618D03*
X1756847D03*
Y129574D03*
X1753418Y191941D03*
X1753285Y188727D03*
X1747242Y226141D03*
X1750042D03*
X1755112Y256535D03*
X1749939Y288190D03*
X1747139D03*
X1744639D03*
X1749939Y285690D03*
X1744639D03*
X1747139D03*
X1758165Y290755D03*
X1754165D03*
X1744524Y370010D03*
X1753474Y542699D03*
X1757402Y825111D03*
Y820155D03*
X1744937Y912517D03*
X1747937D03*
X1750751Y910785D03*
X1748081Y984379D03*
X1756192Y996132D03*
X1743224Y1119055D03*
X1752000Y1644980D03*
X1764804Y84140D03*
Y76140D03*
Y80140D03*
X1759736Y94017D03*
X1767249Y117557D03*
X1762257D03*
Y122513D03*
Y131731D03*
X1767249Y122513D03*
Y131731D03*
X1762257Y136687D03*
X1767249D03*
X1765950Y180572D03*
X1770633Y180527D03*
X1774356Y192421D03*
X1759918Y184619D03*
X1770588Y185121D03*
X1765950Y185165D03*
X1761898Y206760D03*
X1763112Y256535D03*
X1764142Y279208D03*
X1768246Y281307D03*
X1762165Y290755D03*
X1765497Y370899D03*
X1766204Y398949D03*
X1770778Y402642D03*
X1773278D03*
X1763704Y401949D03*
X1767953Y413611D03*
X1770453D03*
X1772953D03*
X1772893Y423944D03*
X1770393D03*
X1767893D03*
X1765093D03*
X1765153Y413611D03*
X1764912Y482382D03*
X1765006Y478382D03*
X1761953Y706827D03*
Y865160D03*
X1772599Y993053D03*
X1762898Y992883D03*
X1764744Y1101930D03*
Y1097879D03*
X1766899Y1121122D03*
X1769499D03*
X1772099D03*
X1774799D03*
X1766999Y1130822D03*
X1772199D03*
X1769599D03*
X1774339Y1437975D03*
X1774216Y1470165D03*
X1772000Y1644980D03*
X1788884Y59871D03*
X1782382Y55513D03*
X1778179Y117261D03*
X1785886Y172665D03*
Y180665D03*
X1785918Y200864D03*
Y212864D03*
Y216864D03*
Y221864D03*
X1790014Y468607D03*
X1784602Y564092D03*
X1782600Y874500D03*
X1774899Y1130822D03*
Y1139822D03*
X1777399D03*
Y1147822D03*
X1774899D03*
X1785961Y1224892D03*
X1791099Y1260421D03*
X1779868Y1446668D03*
X1786564Y1478858D03*
X1777131Y1604357D03*
X1791570Y74535D03*
X1793149Y662810D03*
X1798705Y718793D03*
X1805013Y1091877D03*
X1792847Y1099210D03*
X1799012Y1095893D03*
X1805013Y1096470D03*
X1792863Y1103246D03*
X1801147Y1208555D03*
X1802844Y1227695D03*
X1793976Y1440762D03*
X1807270Y1468535D03*
X1793879Y1472952D03*
X1792000Y1644980D03*
X1816322Y977215D03*
X1823074Y992833D03*
X1812296Y1075688D03*
X1809696Y1091832D03*
X1809651Y1096426D03*
X1823028Y1124289D03*
X1817728D03*
X1815128D03*
X1820328D03*
X1822928Y1114589D03*
X1820228D03*
X1815028D03*
X1817628D03*
X1815865Y1133356D03*
X1809897Y1237285D03*
Y1230385D03*
Y1232885D03*
Y1239785D03*
Y1244185D03*
Y1246685D03*
X1807393Y1436345D03*
X1812000Y1644980D03*
X1831511Y978888D03*
X1831914Y992877D03*
X1824706Y1081145D03*
Y1089145D03*
X1837933Y1636171D03*
X1832000Y1644980D03*
G54D35*
X141337Y1228542D03*
X141336Y1247242D03*
Y1239762D03*
X161909Y1129429D03*
X160039Y1228543D03*
X169389Y1121948D03*
X167519Y1198621D03*
Y1213582D03*
X174999Y1228543D03*
X182480D03*
X167519D03*
X189960D03*
X197440D03*
X210531Y1211712D03*
X212401Y1228543D03*
X204921D03*
X213969Y1453293D03*
Y1464293D03*
X218011Y1211712D03*
X227362Y1228543D03*
X219881D03*
X227249Y1464293D03*
Y1453293D03*
X294685Y1127558D03*
Y1135039D03*
Y1194881D03*
Y1202362D03*
X290944Y1191141D03*
X294685Y1209842D03*
X302165Y1108858D03*
X298425Y1112598D03*
X309645D03*
Y1120078D03*
X305905Y1116338D03*
X298425Y1120078D03*
X305905Y1123818D03*
X309645Y1135039D03*
Y1127558D03*
X311515Y1136909D03*
X304035Y1140649D03*
X305905Y1131299D03*
X296555Y1151869D03*
X304035Y1155610D03*
Y1148129D03*
X296555Y1144389D03*
X311515D03*
Y1151869D03*
X296555Y1159350D03*
Y1166830D03*
X304035Y1170570D03*
X300295D03*
X311515Y1159350D03*
X300295Y1185531D03*
Y1178051D03*
X296555Y1174310D03*
X298425Y1187401D03*
X304035Y1185531D03*
Y1178051D03*
Y1193011D03*
X302165Y1198621D03*
X305905Y1206102D03*
X302165Y1213582D03*
Y1206102D03*
X298425Y1221062D03*
Y1217322D03*
X317125Y1116338D03*
Y1123818D03*
X313385D03*
Y1116338D03*
X315255Y1136909D03*
X313384Y1131299D03*
X315255Y1144389D03*
Y1151869D03*
Y1159350D03*
Y1166830D03*
Y1181791D03*
Y1189271D03*
Y1174310D03*
X313385Y1198621D03*
Y1206102D03*
X320866Y1217322D03*
X317125Y1221062D03*
X313385Y1213582D03*
X324606Y1209842D03*
Y1217322D03*
X320866Y1236023D03*
Y1224803D03*
X324606Y1232283D03*
Y1236023D03*
Y1224803D03*
Y1243503D03*
X598424Y1228542D03*
X598423Y1239762D03*
Y1247242D03*
X618996Y1129429D03*
X617126Y1228543D03*
X626476Y1121948D03*
X624606Y1198621D03*
Y1213582D03*
X632086Y1228543D03*
X624606D03*
X639567D03*
X647047D03*
X667618Y1211712D03*
X654527Y1228543D03*
X662008D03*
X669488D03*
X675098Y1211712D03*
X676968Y1228543D03*
X684449D03*
X748031Y1194881D03*
X762992Y1116338D03*
X766732Y1120078D03*
X762992Y1123818D03*
X766732Y1112598D03*
X759252Y1108858D03*
X755512Y1120078D03*
X761122Y1140649D03*
X762992Y1131299D03*
X766732Y1135039D03*
Y1127558D03*
X751772D03*
Y1135039D03*
X753642Y1144389D03*
X761122Y1148129D03*
Y1155610D03*
X753642Y1151869D03*
X757382Y1170570D03*
X761122D03*
X753642Y1166830D03*
Y1159350D03*
Y1181791D03*
Y1174310D03*
X757382Y1178051D03*
Y1185531D03*
X761122Y1178051D03*
Y1185531D03*
X753642Y1189271D03*
X759252Y1191141D03*
X762992D03*
X755512Y1194881D03*
X759252Y1198621D03*
X751772Y1202362D03*
X755512Y1221062D03*
Y1217322D03*
X759252Y1213582D03*
X762992Y1206102D03*
X759252D03*
X751772Y1209842D03*
X770472Y1123818D03*
X774212D03*
X770472Y1116338D03*
X774212D03*
X770471Y1131299D03*
X770472Y1138779D03*
X772342Y1151869D03*
Y1144389D03*
X768602Y1151869D03*
Y1144389D03*
X772342Y1166830D03*
X768602Y1159350D03*
X772342D03*
Y1174310D03*
Y1181791D03*
Y1196751D03*
X770472Y1198621D03*
X781693Y1217322D03*
X777953D03*
X774212Y1221062D03*
X781693Y1209842D03*
X770472Y1213582D03*
Y1206102D03*
X781693Y1224803D03*
X777953D03*
X781693Y1232283D03*
X777953Y1236023D03*
X781693D03*
Y1243503D03*
X1055510Y1228542D03*
X1055509Y1239762D03*
Y1247242D03*
X1074212Y1228543D03*
X1083562Y1121948D03*
X1076082Y1129429D03*
X1081692Y1198621D03*
Y1213582D03*
Y1228543D03*
X1089172D03*
X1104133D03*
X1096653D03*
X1124704Y1211712D03*
X1119094Y1228543D03*
X1111613D03*
X1132184Y1211712D03*
X1126574Y1228543D03*
X1134054D03*
X1141535D03*
X1203247Y1193011D03*
X1216338Y1108858D03*
X1212598Y1120078D03*
X1220078Y1116338D03*
Y1123818D03*
X1218208Y1140649D03*
X1208858Y1127558D03*
X1220078Y1131299D03*
X1208858Y1135039D03*
X1210728Y1151869D03*
X1218208Y1155610D03*
Y1148129D03*
X1210728Y1144389D03*
Y1159350D03*
Y1166830D03*
X1218208Y1170570D03*
X1214468D03*
X1210728Y1181791D03*
Y1189271D03*
X1218208Y1185531D03*
Y1178051D03*
X1214468Y1185531D03*
Y1178051D03*
X1210728Y1174310D03*
X1212598Y1194881D03*
X1218208Y1193011D03*
X1214468D03*
X1216338Y1198621D03*
X1208858Y1202362D03*
X1220078Y1206102D03*
X1216338D03*
X1212598Y1221062D03*
Y1217322D03*
X1216338Y1213582D03*
X1208858Y1209842D03*
X1223818Y1112598D03*
Y1120078D03*
X1227558Y1116338D03*
X1231298D03*
X1227558Y1123818D03*
X1231298D03*
X1229428Y1136909D03*
X1223818Y1127558D03*
X1227557Y1131299D03*
X1223818Y1135039D03*
X1225688Y1144389D03*
Y1151869D03*
X1229428Y1144389D03*
Y1151869D03*
Y1159350D03*
X1225688D03*
X1229428Y1166830D03*
Y1181791D03*
Y1189271D03*
Y1174310D03*
Y1196751D03*
X1227558Y1198621D03*
Y1206102D03*
X1235039Y1217322D03*
X1231298Y1221062D03*
X1227558Y1213582D03*
X1235039Y1224803D03*
Y1236023D03*
X1238779Y1217322D03*
Y1209842D03*
Y1224803D03*
Y1232283D03*
Y1236023D03*
Y1243503D03*
X1514468Y1166829D03*
Y1174309D03*
Y1181790D03*
X1512597Y1228542D03*
X1512596Y1239762D03*
Y1247242D03*
X1540649Y1121948D03*
X1533169Y1129429D03*
X1538779Y1198621D03*
Y1213582D03*
X1531299Y1228543D03*
X1538779D03*
X1546259D03*
X1561220D03*
X1553740D03*
X1576181D03*
X1568700D03*
X1589271Y1211712D03*
X1581791D03*
X1583661Y1228543D03*
X1591141D03*
X1598622D03*
X1660334Y1204232D03*
Y1200491D03*
Y1193011D03*
Y1196751D03*
Y1207972D03*
X1673425Y1108858D03*
X1669685Y1112598D03*
Y1120078D03*
X1675295Y1140649D03*
X1665945Y1127558D03*
Y1135039D03*
X1667815Y1151869D03*
X1675295Y1155610D03*
Y1148129D03*
X1667815Y1144389D03*
Y1159350D03*
Y1166830D03*
X1675295Y1170570D03*
X1671555D03*
Y1185531D03*
Y1178051D03*
X1667815Y1174310D03*
Y1181791D03*
Y1189271D03*
X1675295Y1185531D03*
Y1178051D03*
X1669685Y1194881D03*
X1675295Y1193011D03*
X1671555D03*
X1665945Y1202362D03*
X1673425Y1198621D03*
X1669685Y1221062D03*
Y1217322D03*
X1673425Y1213582D03*
X1665945Y1209842D03*
X1673425Y1206102D03*
X1677165Y1116338D03*
X1680905Y1112598D03*
X1677165Y1123818D03*
X1680905Y1120078D03*
X1684645Y1116338D03*
X1688385D03*
X1684645Y1123818D03*
X1688385D03*
X1686515Y1136909D03*
X1682775D03*
X1680905Y1127558D03*
X1677165Y1131299D03*
X1684644D03*
X1680905Y1135039D03*
X1682775Y1144389D03*
Y1151869D03*
X1686515Y1144389D03*
Y1151869D03*
Y1159350D03*
X1682775D03*
X1686515Y1166830D03*
Y1174310D03*
Y1181791D03*
Y1189271D03*
X1684645Y1198621D03*
X1692126Y1217322D03*
X1688385Y1221062D03*
X1684645Y1213582D03*
Y1206102D03*
X1677165D03*
X1692126Y1224803D03*
Y1236023D03*
X1695866Y1217322D03*
Y1209842D03*
Y1232283D03*
Y1236023D03*
Y1224803D03*
Y1243503D03*
G54D27*
X73872Y1348187D03*
X81752D03*
X73872Y1360099D03*
X81752D03*
X73872Y1384297D03*
Y1372385D03*
X81752Y1384297D03*
Y1372385D03*
X86112Y1348187D03*
X98352D03*
X93992D03*
X86112Y1360099D03*
X98352D03*
X93992D03*
X86112Y1384297D03*
Y1372385D03*
X98352Y1384297D03*
Y1372385D03*
X93992D03*
Y1384297D03*
X86112Y1396583D03*
X93992D03*
X98352D03*
X86112Y1408495D03*
X93992D03*
X98352D03*
X110592Y1348187D03*
X106232D03*
X110592Y1360099D03*
X106232D03*
X110592Y1384297D03*
X106232D03*
Y1372385D03*
X110592D03*
Y1396583D03*
X106232D03*
X110592Y1408495D03*
X106232D03*
X118472Y1348187D03*
X122832D03*
X130712D03*
X118472Y1360099D03*
X122832D03*
X130712D03*
X118472Y1384297D03*
Y1372385D03*
X122832Y1384297D03*
Y1372385D03*
X130712Y1384297D03*
Y1372385D03*
X118472Y1396583D03*
X122832D03*
X130712D03*
X118472Y1408495D03*
X122832D03*
X130712D03*
X146948Y1080806D03*
Y1103247D03*
X143208D03*
X146948Y1133169D03*
Y1140649D03*
X139468Y1136909D03*
X143208Y1125688D03*
Y1133169D03*
Y1140649D03*
X146948Y1125688D03*
X143208Y1144389D03*
Y1151870D03*
X146948Y1144389D03*
Y1151870D03*
X140707Y1170569D03*
X143208Y1159350D03*
X146948D03*
X148818Y1183661D03*
X140707Y1178050D03*
X145078Y1187401D03*
Y1183661D03*
X148818Y1187401D03*
X146947Y1174310D03*
X141337Y1191142D03*
X145078Y1194881D03*
Y1202362D03*
X148818Y1194881D03*
Y1202362D03*
X141337Y1198622D03*
Y1206103D03*
X145078Y1209842D03*
Y1217322D03*
X148818Y1209842D03*
Y1217322D03*
X141337Y1213583D03*
Y1221063D03*
X148818Y1224803D03*
X145078Y1232283D03*
Y1236023D03*
X148818Y1232283D03*
Y1236023D03*
X145078Y1224803D03*
X148818Y1254724D03*
X135072Y1348187D03*
X142952D03*
X147312D03*
X135072Y1360099D03*
X147312D03*
X142952D03*
X135072Y1384297D03*
Y1372385D03*
X147312Y1384297D03*
Y1372385D03*
X142952Y1384297D03*
Y1372385D03*
X135072Y1396583D03*
X147312D03*
X142952D03*
X135072Y1408495D03*
X147312D03*
X142952D03*
X150688Y1077066D03*
X158169Y1106988D03*
X165649D03*
X161909D03*
X158169Y1118208D03*
Y1121948D03*
X154429D03*
X150689D03*
X165649Y1114468D03*
X161909D03*
X158169Y1133169D03*
X161909Y1140649D03*
X158169Y1125688D03*
X154429Y1129429D03*
X150689D03*
Y1136909D03*
X154429Y1140649D03*
X150689D03*
X165649D03*
Y1129429D03*
Y1136909D03*
X158169Y1140649D03*
X150689Y1151870D03*
X158169Y1155610D03*
X154429D03*
X150689D03*
X161909Y1144389D03*
Y1148129D03*
Y1151870D03*
Y1155610D03*
X150689Y1144389D03*
Y1148129D03*
Y1159350D03*
X158169Y1166830D03*
X150688D03*
X154429Y1170570D03*
X150688D03*
X161909Y1159350D03*
X160039Y1187401D03*
X156299Y1183661D03*
X152559D03*
X161909Y1174310D03*
Y1178051D03*
X165649Y1181791D03*
X161909D03*
X158169Y1174310D03*
X154429D03*
X150688Y1178051D03*
Y1174310D03*
X156299Y1179921D03*
X160039Y1183661D03*
X163779D03*
X156299Y1198621D03*
X152559D03*
X163779D03*
X160039D03*
X152559Y1191141D03*
X156299D03*
X160039D03*
X163779D03*
X160039Y1206102D03*
X156299D03*
X152559D03*
X163779D03*
X156299Y1213582D03*
X152559D03*
X160039Y1221062D03*
X156299D03*
X152559D03*
X163779D03*
X152559Y1228543D03*
X160039Y1224803D03*
X152559D03*
X156299Y1232283D03*
Y1236023D03*
X163779D03*
Y1232283D03*
X160039Y1239763D03*
X152559D03*
Y1243503D03*
X160039D03*
X163779Y1239763D03*
X152559Y1258465D03*
X160039D03*
X159552Y1348187D03*
X155192D03*
X159552Y1360099D03*
X155192D03*
X159552Y1372385D03*
Y1384297D03*
X155192D03*
Y1372385D03*
X159552Y1396583D03*
X155192D03*
X159552Y1408495D03*
X155192D03*
X174998Y1071455D03*
X182479D03*
X178740Y1090157D03*
X174999D03*
X171259D03*
X182480D03*
X178740Y1093897D03*
Y1097637D03*
X174999Y1101377D03*
X169389Y1106988D03*
X171259Y1093897D03*
X174999Y1105117D03*
X182480Y1101377D03*
Y1105117D03*
X174999Y1108858D03*
X178740D03*
X176870Y1114468D03*
Y1118208D03*
Y1121948D03*
X178740Y1112598D03*
X173129Y1110728D03*
X169389D03*
X180610Y1114468D03*
Y1118208D03*
Y1121948D03*
X182480Y1112598D03*
Y1108858D03*
X180610Y1136909D03*
X173129Y1133169D03*
X169389D03*
X176870Y1140649D03*
Y1125688D03*
Y1129429D03*
Y1133169D03*
Y1136909D03*
X173129Y1140649D03*
X169389D03*
X180610D03*
Y1125688D03*
Y1129429D03*
Y1133169D03*
Y1148129D03*
X173129Y1144389D03*
X169389D03*
X173129Y1148129D03*
Y1155610D03*
Y1151870D03*
X180610Y1155610D03*
Y1151870D03*
Y1144389D03*
X176870Y1170570D03*
X173129Y1159350D03*
Y1166830D03*
Y1170570D03*
X180610Y1166830D03*
Y1159350D03*
Y1174310D03*
Y1181791D03*
X173129Y1174310D03*
Y1178051D03*
Y1181791D03*
X171259Y1187401D03*
X174999D03*
X180610Y1178051D03*
X167519Y1183661D03*
X178740Y1187401D03*
X182480D03*
X176870Y1185531D03*
X173129D03*
X171259Y1202362D03*
Y1194881D03*
X174999Y1202362D03*
Y1194881D03*
X167519Y1191141D03*
X178740D03*
Y1194881D03*
Y1198621D03*
Y1202362D03*
X182480Y1191141D03*
Y1198621D03*
Y1202362D03*
X171259Y1209842D03*
X174999Y1217322D03*
X171259Y1221062D03*
X174999D03*
X171259Y1217322D03*
X167519Y1206102D03*
X178740D03*
Y1209842D03*
Y1213582D03*
Y1221062D03*
X182480D03*
X178740Y1217322D03*
X182480Y1206102D03*
Y1209842D03*
Y1213582D03*
Y1217322D03*
X178740Y1232283D03*
Y1236023D03*
X171259Y1232283D03*
X174999Y1224803D03*
X171259Y1236023D03*
X182480Y1224803D03*
X167519D03*
X182480Y1243503D03*
X171259Y1250984D03*
X174999Y1247243D03*
Y1239763D03*
X171259D03*
X167519D03*
Y1243503D03*
X175000Y1258465D03*
X182480D03*
X167519D03*
X167432Y1348187D03*
X171792D03*
X179672D03*
X167432Y1360099D03*
X171792D03*
X179672D03*
X167432Y1384297D03*
Y1372385D03*
X171792Y1384297D03*
Y1372385D03*
X179672Y1384297D03*
Y1372385D03*
X171792Y1396583D03*
X179672D03*
X167432D03*
Y1408495D03*
X171792D03*
X179672D03*
X197439Y1071455D03*
X189959D03*
X193700Y1090157D03*
X189960D03*
X186220D03*
X197440D03*
X193700Y1093897D03*
X189960Y1101377D03*
X186220Y1097637D03*
X189960Y1105117D03*
X186220Y1093897D03*
X193700Y1097637D03*
X197440Y1101377D03*
Y1105117D03*
X195570Y1121948D03*
X191830Y1118208D03*
X188090D03*
X184350D03*
X191830Y1121948D03*
X188090D03*
X184350D03*
X195570Y1118208D03*
X186220Y1108858D03*
X189960D03*
X193700D03*
X197440D03*
X191830Y1125688D03*
X188090D03*
X184350D03*
X188090Y1129429D03*
X184350D03*
X188090Y1133169D03*
X184350D03*
X188090Y1136909D03*
Y1140649D03*
X184350D03*
X195570Y1133169D03*
Y1129429D03*
Y1125688D03*
Y1136909D03*
X188090Y1144389D03*
Y1151870D03*
X191830Y1155610D03*
Y1148129D03*
X195570Y1151869D03*
Y1144389D03*
X188090Y1159350D03*
Y1170570D03*
X191830Y1166830D03*
X195570Y1159350D03*
Y1170570D03*
X188090Y1185531D03*
X195570Y1189271D03*
X191830Y1181791D03*
Y1174310D03*
X195570Y1185531D03*
Y1178051D03*
X188090Y1196751D03*
Y1200491D03*
Y1204232D03*
X191830D03*
Y1196751D03*
Y1200491D03*
X184350Y1193011D03*
Y1196751D03*
X195570Y1200491D03*
Y1196751D03*
Y1193011D03*
Y1204232D03*
X186220Y1198621D03*
X193700Y1209842D03*
X191830Y1207972D03*
X189960Y1209842D03*
X195570Y1207972D03*
X193700Y1213582D03*
X191830Y1219192D03*
X186220Y1221062D03*
X189960D03*
X193700D03*
X197440D03*
X186220Y1206102D03*
Y1209842D03*
Y1213582D03*
X197440Y1209842D03*
Y1224803D03*
X193700Y1232283D03*
X186220D03*
X189960Y1224803D03*
X193700Y1236023D03*
X186220D03*
X197440Y1239763D03*
Y1243503D03*
X193700Y1239763D03*
X186220D03*
X189960Y1243503D03*
Y1258465D03*
X197441D03*
X184032Y1348187D03*
X191912D03*
X196272D03*
X184032Y1360099D03*
X196272D03*
X191912D03*
X184032Y1384297D03*
Y1372385D03*
X196272Y1384297D03*
Y1372385D03*
X191912Y1384297D03*
Y1372385D03*
X184032Y1396583D03*
X191912D03*
X196272D03*
X184032Y1408495D03*
X191912D03*
X196272D03*
X204920Y1071455D03*
X212400D03*
X204921Y1090157D03*
X212401D03*
X208661D03*
X201181D03*
X204921Y1101377D03*
X208661Y1097637D03*
X201181D03*
X204921Y1105117D03*
X212401Y1101377D03*
Y1105117D03*
X201181Y1093897D03*
X208661D03*
X199311Y1118208D03*
Y1121948D03*
X206791Y1118208D03*
X203051D03*
Y1121948D03*
X206791D03*
X210531Y1118208D03*
X214271Y1110728D03*
X210531Y1121948D03*
X214271Y1118208D03*
Y1121948D03*
X201181Y1108858D03*
X204921D03*
X208661D03*
X212401D03*
X199311Y1140649D03*
X203051D03*
X206791D03*
X199311Y1125688D03*
X203051D03*
X206791D03*
Y1133169D03*
X203051D03*
X199311D03*
X210531D03*
Y1140649D03*
X214271D03*
Y1125688D03*
X210531D03*
X214271Y1133169D03*
X203051Y1148129D03*
X199311D03*
X206791D03*
X214271D03*
X210531D03*
X199311Y1155610D03*
X206791D03*
X214271D03*
X206791Y1166830D03*
X203051Y1159350D03*
X199311Y1166830D03*
X203051Y1170570D03*
X214271Y1166830D03*
X210531Y1159350D03*
Y1170570D03*
X206791Y1181791D03*
X203051D03*
X199311D03*
X206791Y1189271D03*
X203051D03*
X199311D03*
X214271Y1181791D03*
X210531D03*
X214271Y1189271D03*
X210531D03*
X199311Y1174310D03*
X206791D03*
X214271D03*
X206791Y1196751D03*
X203051D03*
X199311D03*
Y1204232D03*
X203051D03*
X206791D03*
X214271Y1196751D03*
X210531D03*
Y1204232D03*
X214271D03*
X206791Y1207972D03*
X203051D03*
X199311D03*
X210531D03*
X214271D03*
X212401Y1221062D03*
X208661D03*
X204921D03*
X201181D03*
X212401Y1224803D03*
X208661Y1232283D03*
X201181D03*
X204921Y1224803D03*
X201181Y1236023D03*
X208661D03*
X212401Y1243503D03*
X208661Y1239763D03*
X204921Y1243503D03*
X212401Y1258465D03*
X204921D03*
X204152Y1348187D03*
Y1360099D03*
Y1384297D03*
Y1372385D03*
Y1396583D03*
Y1408495D03*
X219880Y1071455D03*
X227361D03*
X227362Y1090157D03*
X223622D03*
X219881D03*
X231102D03*
X216141D03*
X223622Y1093897D03*
X231102D03*
Y1097637D03*
X227362Y1101377D03*
Y1105117D03*
X219881Y1101377D03*
Y1105117D03*
X223622Y1097637D03*
X216141D03*
Y1093897D03*
X225492Y1118208D03*
Y1121948D03*
X218011Y1118208D03*
X221751D03*
X218011Y1121948D03*
X221751D03*
X229232D03*
Y1118208D03*
Y1114468D03*
X216141Y1108858D03*
X219881D03*
X223622D03*
X227362D03*
X231102D03*
X225492Y1133169D03*
Y1140649D03*
Y1125688D03*
X218011Y1140649D03*
X221751D03*
X218011Y1125688D03*
X221751D03*
Y1133169D03*
X218011D03*
X229330Y1132677D03*
X229232Y1140649D03*
Y1125688D03*
X225492Y1148129D03*
X221751D03*
X218011D03*
X229232D03*
X221751Y1155610D03*
X229232D03*
X225492Y1170570D03*
Y1159350D03*
X218011Y1170570D03*
X221752Y1166830D03*
X218011Y1159350D03*
X229232Y1166830D03*
X225492Y1181791D03*
Y1189271D03*
X221751Y1181791D03*
X218011D03*
X221751Y1189271D03*
X218011D03*
X229232Y1181791D03*
Y1189271D03*
X221751Y1174310D03*
X229232D03*
X218011Y1204232D03*
X229232Y1196751D03*
Y1204232D03*
X225492Y1196751D03*
Y1204232D03*
X221751D03*
Y1196751D03*
X218011D03*
X225492Y1207972D03*
X221751D03*
X218011D03*
X229232D03*
X231102Y1221062D03*
X227362D03*
X219881Y1217322D03*
X223622Y1221062D03*
X219881D03*
X216141D03*
X227362Y1224803D03*
X223622Y1232283D03*
X219881Y1224803D03*
X223622Y1236023D03*
X231102Y1232283D03*
Y1236023D03*
X216141Y1232283D03*
Y1236023D03*
X223622Y1239763D03*
X231102D03*
X227362Y1243503D03*
X219881D03*
X216141Y1239763D03*
X219882Y1258465D03*
X227363D03*
X246062Y1075196D03*
X234841Y1071454D03*
X242321Y1071455D03*
X238582Y1075196D03*
X234842Y1090157D03*
X246062D03*
Y1078936D03*
X238582Y1090157D03*
X242322Y1086417D03*
X234842Y1082677D03*
Y1086417D03*
X242322Y1090157D03*
X246062Y1097637D03*
Y1093897D03*
X242322Y1105117D03*
X234842Y1101377D03*
X238582Y1093897D03*
X242322Y1101377D03*
X234842Y1105117D03*
X236712Y1121948D03*
X240452D03*
X244192D03*
X234842Y1108858D03*
X238582D03*
X242322D03*
X246062D03*
X236712Y1133464D03*
X240452Y1133169D03*
X236712Y1140649D03*
X240452D03*
X236712Y1125688D03*
X240452D03*
X244192Y1133169D03*
Y1140649D03*
Y1125688D03*
X236712Y1148129D03*
X240452D03*
X244192D03*
X240452Y1155610D03*
Y1166830D03*
X236712Y1170570D03*
Y1159350D03*
X244192Y1170570D03*
Y1159350D03*
X240452Y1181791D03*
X236712D03*
Y1189271D03*
X240452D03*
X244192Y1181791D03*
Y1189271D03*
X240452Y1174310D03*
Y1204232D03*
X236712D03*
Y1196751D03*
X240452D03*
X244192Y1204232D03*
Y1196751D03*
X240452Y1207972D03*
Y1211712D03*
X242322Y1221062D03*
X244192Y1211712D03*
Y1207972D03*
X236712D03*
X234842Y1221062D03*
X238582D03*
X246062Y1232283D03*
Y1236023D03*
X238582Y1232283D03*
X234842Y1228543D03*
Y1224803D03*
X238582Y1236023D03*
X242322Y1228543D03*
Y1224803D03*
X246062Y1239763D03*
X238582D03*
X234842Y1258465D03*
X242322D03*
X239383Y1348187D03*
X247263D03*
Y1360099D03*
X239383D03*
X247263Y1384297D03*
Y1372385D03*
X239383Y1384297D03*
Y1372385D03*
X253543Y1075196D03*
X261023D03*
X249802Y1071455D03*
X257282D03*
X253543Y1090157D03*
X249803D03*
Y1086417D03*
X253543Y1078936D03*
X257283Y1090157D03*
Y1086417D03*
X261023Y1090157D03*
Y1078936D03*
X249803Y1105117D03*
X253543Y1093897D03*
Y1097637D03*
X257283Y1105117D03*
X261023Y1093897D03*
Y1097637D03*
X255413Y1121948D03*
X251673D03*
X247933D03*
X262893D03*
X259153D03*
X249803Y1108858D03*
X253543D03*
X257283D03*
X261023D03*
X247933Y1133169D03*
X251673D03*
X255413D03*
X247933Y1140649D03*
X251673D03*
X255413D03*
X247933Y1125688D03*
X251673D03*
X255413D03*
X259153Y1133169D03*
X262893D03*
Y1140649D03*
X259153Y1125688D03*
X262893D03*
X259153Y1140649D03*
Y1148129D03*
X262893D03*
Y1155610D03*
X247933Y1148129D03*
X251673D03*
X255413D03*
X247933Y1155610D03*
X255413D03*
X262893Y1166830D03*
X251673Y1170570D03*
X255413Y1166830D03*
X247933D03*
X251673Y1159350D03*
X259153D03*
Y1170570D03*
X247933Y1181791D03*
X251673D03*
X255413D03*
X247933Y1189271D03*
X251673D03*
X255413D03*
X262893D03*
Y1174310D03*
X259153Y1181791D03*
X262893D03*
X259153Y1189271D03*
X255413Y1174310D03*
X247933D03*
Y1204232D03*
X255413D03*
X251673D03*
X247933Y1196751D03*
X251673D03*
X255413D03*
X259153Y1204232D03*
X262893D03*
X259153Y1196751D03*
X262893D03*
X247933Y1207972D03*
X251673D03*
X255413Y1211712D03*
Y1207972D03*
X262893D03*
X259153D03*
X262893Y1211712D03*
X259153D03*
X249803Y1228543D03*
X257283D03*
X249803Y1224803D03*
X253543Y1236023D03*
X257283Y1224803D03*
X261023Y1236023D03*
X253543Y1232283D03*
X261023D03*
X257283Y1239763D03*
X249803Y1258465D03*
X257283D03*
X263863Y1348187D03*
X259503D03*
X251623D03*
X263863Y1360099D03*
X259503D03*
X251623D03*
X263863Y1384297D03*
Y1372385D03*
X259503Y1384297D03*
Y1372385D03*
X251623D03*
Y1384297D03*
X263863Y1396583D03*
X259503D03*
X251623D03*
X263863Y1408495D03*
X259503D03*
X251623D03*
X279723Y1071455D03*
X264762D03*
X272243D03*
X268503Y1075196D03*
X275984D03*
X279724Y1090157D03*
X272244Y1082677D03*
X275984Y1090157D03*
X272244Y1086417D03*
X268503Y1078936D03*
Y1090157D03*
X264763Y1086417D03*
X272244Y1090157D03*
X264763D03*
X268503Y1093897D03*
Y1097637D03*
X272244Y1105117D03*
X279724D03*
X275984Y1093897D03*
X264763Y1105117D03*
X274114Y1118208D03*
X270373D03*
X266633Y1121948D03*
X270373D03*
X277854Y1118208D03*
X264763Y1108858D03*
X268503D03*
X272244D03*
X275984D03*
X279724D03*
X274114Y1125688D03*
X270373Y1136909D03*
X266633Y1133169D03*
X270373D03*
X266633Y1140649D03*
X270373Y1125688D03*
Y1129429D03*
X266633Y1125688D03*
X270373Y1140649D03*
X277854Y1136909D03*
Y1140649D03*
X274114Y1155610D03*
Y1151869D03*
Y1148129D03*
X266633D03*
X270373Y1144389D03*
Y1148129D03*
Y1151869D03*
X277854Y1144389D03*
Y1148129D03*
Y1151870D03*
X270373Y1155610D03*
X274114Y1166830D03*
Y1159350D03*
Y1170570D03*
X266633Y1181791D03*
X270373Y1189271D03*
X277854Y1178051D03*
Y1189271D03*
Y1185531D03*
X270373Y1174310D03*
X277854Y1181791D03*
X274114D03*
Y1174310D03*
X266633Y1189271D03*
X270373Y1178051D03*
Y1185531D03*
X274114Y1196751D03*
X270393Y1196732D03*
X270373Y1204232D03*
X266633D03*
X270373Y1200491D03*
X266633Y1196751D03*
X270373Y1193011D03*
X277854D03*
X274114Y1207972D03*
X270373Y1211712D03*
X266633Y1207972D03*
Y1211712D03*
X270373Y1207972D03*
X277854Y1211712D03*
X279724Y1221062D03*
X275984D03*
X272244D03*
X268503D03*
X279724Y1224803D03*
X272244D03*
X268503Y1236023D03*
Y1232283D03*
X272244Y1228543D03*
X264763Y1224803D03*
X275984Y1232283D03*
Y1236023D03*
X264763Y1228543D03*
X279724D03*
X268503Y1239763D03*
X279724Y1258465D03*
X264763D03*
X272244D03*
X276103Y1348187D03*
X271743D03*
X276103Y1360099D03*
X271743D03*
X276103Y1384297D03*
Y1372385D03*
X271743Y1384297D03*
Y1372385D03*
X276103Y1396583D03*
X271743D03*
Y1408495D03*
X276103D03*
X294684Y1071455D03*
X290944Y1075196D03*
X287203Y1071455D03*
X283464Y1075196D03*
X287204Y1090157D03*
X283464Y1078936D03*
Y1090157D03*
X290943D03*
X290944Y1093897D03*
X287204Y1101377D03*
Y1105117D03*
X294685D03*
X294684Y1120078D03*
Y1112598D03*
X283464Y1108858D03*
X287204D03*
X290944D03*
X294685D03*
X290944Y1112598D03*
Y1116338D03*
Y1120078D03*
Y1123818D03*
X281594Y1140649D03*
Y1136909D03*
X290944Y1127558D03*
Y1131299D03*
Y1135039D03*
Y1138779D03*
X281594Y1148129D03*
Y1155610D03*
Y1151869D03*
X285334D03*
X289074D03*
Y1155610D03*
X292814Y1151869D03*
Y1144389D03*
X281594Y1159350D03*
X289074Y1166830D03*
Y1170570D03*
Y1159350D03*
X281594Y1170570D03*
Y1166830D03*
X292814Y1159350D03*
Y1166830D03*
Y1181791D03*
X285334Y1185531D03*
X289074Y1174310D03*
Y1178051D03*
Y1185531D03*
X281594Y1189271D03*
Y1185531D03*
X285334Y1181791D03*
X281594Y1178051D03*
Y1174310D03*
X292814D03*
Y1189271D03*
X281594Y1196751D03*
Y1204232D03*
Y1193011D03*
X285334D03*
X290944Y1194881D03*
Y1198621D03*
Y1202362D03*
X294685Y1221062D03*
Y1217322D03*
X290944Y1221062D03*
X287204D03*
X283464D03*
X290944Y1206102D03*
Y1209842D03*
Y1213582D03*
Y1217322D03*
X294685Y1228543D03*
Y1224803D03*
X290944Y1232283D03*
Y1236023D03*
X283464Y1232283D03*
X287204Y1228543D03*
X283464Y1236023D03*
X287204Y1224803D03*
X283464Y1239763D03*
X290944D03*
X294685Y1258465D03*
X287204D03*
X288343Y1348187D03*
X296223D03*
X283983D03*
X288343Y1360099D03*
X296223D03*
X283983D03*
X288343Y1384297D03*
Y1372385D03*
X296223Y1384297D03*
Y1372385D03*
X283983D03*
Y1384297D03*
X288343Y1396583D03*
X296223D03*
X283983D03*
X288343Y1408495D03*
X296223D03*
X283983D03*
X309645Y1071455D03*
X302165D03*
X298425Y1075196D03*
X305906D03*
X298424Y1090157D03*
X298426Y1078936D03*
X305906D03*
X302165Y1105117D03*
X309645D03*
X298425Y1093897D03*
X305905D03*
X302165Y1123818D03*
X305904Y1108857D03*
X302165Y1116338D03*
X298425Y1108858D03*
X300295Y1140649D03*
X302165Y1131299D03*
X300295Y1148129D03*
Y1159350D03*
Y1166830D03*
X311515D03*
X307775Y1170570D03*
X300295Y1181791D03*
Y1174310D03*
Y1189271D03*
X311515Y1174310D03*
X307775Y1178051D03*
X311515Y1181791D03*
X307775Y1185531D03*
X311515Y1189271D03*
X298425Y1202362D03*
Y1194881D03*
X309645Y1198621D03*
X307775Y1193011D03*
X311515Y1196751D03*
X305905Y1198621D03*
X309645Y1202362D03*
X298425Y1209842D03*
X302165Y1221062D03*
X309645Y1217322D03*
Y1209842D03*
X305905Y1213582D03*
X309645D03*
Y1206102D03*
Y1221062D03*
X305905D03*
X298425Y1236023D03*
Y1232283D03*
X302165Y1228543D03*
Y1224803D03*
X305905Y1232283D03*
X309645Y1228543D03*
Y1224803D03*
X305905Y1236023D03*
X298425Y1239763D03*
X309645D03*
Y1258465D03*
X302165D03*
X308463Y1348187D03*
X300583D03*
X308463Y1360099D03*
X300583D03*
X308463Y1372385D03*
X300583D03*
Y1384297D03*
X308463D03*
Y1396583D03*
X300583D03*
X308463Y1408495D03*
X300583D03*
X317125Y1071455D03*
X320866Y1075196D03*
X313386D03*
X320866Y1078936D03*
X313384Y1090157D03*
X313386Y1078936D03*
X328347Y1082677D03*
Y1090158D03*
X324606Y1078936D03*
X313385Y1093897D03*
X328347Y1101378D03*
Y1116339D03*
Y1123819D03*
Y1108859D03*
X313385Y1108858D03*
X328347Y1131300D03*
X318996Y1140649D03*
Y1155610D03*
Y1148129D03*
X322736Y1170570D03*
X318996D03*
Y1185531D03*
Y1178051D03*
X322736D03*
Y1185531D03*
X328347Y1198621D03*
X322736Y1193011D03*
X320866Y1202362D03*
X318996Y1193011D03*
X326416D03*
X324606Y1202362D03*
X328347Y1206102D03*
Y1221062D03*
Y1213582D03*
X320866Y1209842D03*
X313385Y1221062D03*
X320866Y1232283D03*
X313385D03*
X317125Y1228543D03*
Y1224803D03*
X313385Y1236023D03*
X328347Y1228543D03*
Y1239762D03*
Y1247243D03*
X324606Y1250984D03*
X317125Y1258465D03*
X320703Y1348187D03*
X312823D03*
X325063D03*
X320703Y1360099D03*
X312823D03*
X325063D03*
X320703Y1372385D03*
Y1384297D03*
X312823Y1372385D03*
Y1384297D03*
X325063Y1372385D03*
Y1384297D03*
Y1396583D03*
X320703D03*
X312823D03*
X320703Y1408495D03*
X312823D03*
X325063D03*
X318448Y1750941D03*
Y1760941D03*
X318348Y1796941D03*
Y1806941D03*
X337303Y1348187D03*
X332943D03*
Y1360099D03*
X337303D03*
X332943Y1384297D03*
Y1372385D03*
X337303D03*
Y1384297D03*
X332943Y1396583D03*
X337303D03*
X332943Y1408495D03*
X337303D03*
X349543Y1348187D03*
X357423D03*
X345183D03*
X349543Y1360099D03*
X357423D03*
X345183D03*
Y1372385D03*
Y1384297D03*
X349543D03*
Y1372385D03*
X357423D03*
Y1384297D03*
X345183Y1396583D03*
X349543D03*
X357423D03*
X345183Y1408495D03*
X349543D03*
X357423D03*
X369663Y1348187D03*
X361783D03*
X369663Y1360099D03*
X361783D03*
X369663Y1372385D03*
Y1384297D03*
X361783D03*
Y1372385D03*
X369663Y1396583D03*
X361783D03*
X369663Y1408495D03*
X361783D03*
X458282Y1348187D03*
X446042D03*
X458282Y1360099D03*
X446042D03*
X458282Y1372385D03*
X446042D03*
X458282Y1384297D03*
X446042D03*
X458282Y1396583D03*
Y1408495D03*
X470522Y1348187D03*
Y1360099D03*
Y1384297D03*
Y1372385D03*
Y1396583D03*
Y1408495D03*
X482762Y1348187D03*
Y1360099D03*
Y1384297D03*
Y1372385D03*
Y1396583D03*
Y1408495D03*
X507242Y1348187D03*
X495002D03*
X507242Y1360099D03*
X495002D03*
Y1384297D03*
X507242D03*
X495002Y1372385D03*
X507242D03*
Y1396583D03*
X495002D03*
X507242Y1408495D03*
X495002D03*
X519482Y1348187D03*
Y1360099D03*
Y1384297D03*
Y1372385D03*
Y1396583D03*
Y1408495D03*
X531722Y1348187D03*
Y1360099D03*
Y1384297D03*
Y1372385D03*
Y1396583D03*
Y1408495D03*
X556202Y1348187D03*
X543962D03*
X556202Y1360099D03*
X543962D03*
Y1372385D03*
Y1384297D03*
X556202D03*
Y1372385D03*
Y1396583D03*
X543962D03*
X556202Y1408495D03*
X543962D03*
X568442Y1348187D03*
Y1360099D03*
Y1384297D03*
Y1372385D03*
Y1396583D03*
Y1408495D03*
X604035Y1080806D03*
Y1103247D03*
X600295D03*
Y1125688D03*
Y1133169D03*
Y1140649D03*
X604035Y1125688D03*
Y1133169D03*
Y1140649D03*
X600295Y1144389D03*
Y1151870D03*
X604035Y1144389D03*
Y1151870D03*
X600295Y1159350D03*
X604035D03*
X597795Y1170570D03*
X604034Y1174310D03*
X597795Y1178050D03*
X602165Y1183661D03*
Y1187401D03*
Y1202362D03*
Y1194881D03*
X598424Y1198622D03*
Y1191142D03*
X602165Y1217322D03*
Y1209842D03*
X598424Y1221063D03*
Y1213583D03*
Y1206103D03*
X602165Y1224803D03*
Y1236023D03*
Y1232283D03*
X605386Y1728583D03*
Y1738583D03*
X605312Y1774624D03*
Y1784624D03*
X607775Y1077066D03*
X615256Y1106988D03*
X618996D03*
X615256Y1118208D03*
Y1121948D03*
X611516D03*
X607776D03*
X618996Y1114468D03*
X615256Y1125688D03*
X611516Y1129429D03*
X607776D03*
Y1136909D03*
X615256Y1140649D03*
X611516D03*
X607776D03*
X618996D03*
Y1144389D03*
Y1148129D03*
Y1151870D03*
Y1155610D03*
X607776Y1144389D03*
Y1148129D03*
Y1151870D03*
X615256Y1155610D03*
X611516D03*
X607776D03*
Y1159350D03*
X615256Y1166830D03*
X607775D03*
X611516Y1170570D03*
X607775D03*
X618996Y1159350D03*
Y1174310D03*
Y1178051D03*
X607775Y1174310D03*
Y1178051D03*
X611516Y1174310D03*
X615256D03*
X613386Y1183661D03*
X617126Y1187401D03*
Y1183661D03*
X613386Y1179921D03*
X620866Y1183661D03*
X609646D03*
X605905D03*
Y1187401D03*
X613386Y1198621D03*
X609646Y1191141D03*
X613386D03*
X617126Y1198621D03*
X620866D03*
X617126Y1191141D03*
X620866D03*
X605905Y1202362D03*
Y1194881D03*
X609646Y1198621D03*
X613386Y1221062D03*
X609646D03*
Y1213582D03*
X613386D03*
X620866Y1206102D03*
X617126D03*
X620866Y1221062D03*
X617126D03*
X613386Y1206102D03*
X605905Y1217322D03*
Y1209842D03*
X609646Y1206102D03*
X605905Y1224803D03*
Y1232283D03*
Y1236023D03*
X620866D03*
Y1232283D03*
X617126Y1224803D03*
X609646D03*
Y1228543D03*
X613386Y1232283D03*
Y1236023D03*
X617126Y1243503D03*
Y1239763D03*
X620866D03*
X609646Y1243503D03*
Y1239763D03*
X617126Y1258465D03*
X609646D03*
X632085Y1071455D03*
X626476Y1092027D03*
X635827Y1090157D03*
X628346D03*
X632086D03*
X630216Y1099507D03*
X626476Y1106988D03*
X622736D03*
X626476Y1095767D03*
X630216Y1103247D03*
X635827Y1093897D03*
X632086Y1101377D03*
Y1105117D03*
X628346Y1093897D03*
X635827Y1097637D03*
X633957Y1110728D03*
X630216D03*
X626476D03*
X622736Y1114468D03*
X630216Y1118208D03*
X626476D03*
X633957Y1114468D03*
Y1118208D03*
Y1121948D03*
X635827Y1108858D03*
X632086D03*
X633957Y1140649D03*
Y1125688D03*
Y1129429D03*
Y1133169D03*
Y1136909D03*
X630216Y1140649D03*
X626476D03*
X622736D03*
Y1129429D03*
X630216Y1144389D03*
X626476D03*
X630216Y1148129D03*
Y1155610D03*
Y1151870D03*
Y1159350D03*
Y1166830D03*
Y1170570D03*
X633957D03*
Y1185531D03*
X628346Y1183661D03*
X630216Y1174310D03*
Y1178051D03*
Y1181791D03*
X632086Y1187401D03*
X628346D03*
X624606Y1183661D03*
X635827Y1187401D03*
X624606Y1191141D03*
X632086Y1202362D03*
X628346D03*
X632086Y1194881D03*
X628346D03*
X635827Y1191141D03*
Y1194881D03*
Y1198621D03*
Y1202362D03*
X624606Y1206102D03*
X628346Y1209842D03*
Y1217322D03*
Y1221062D03*
X632086D03*
Y1217322D03*
X635827Y1221062D03*
Y1206102D03*
Y1209842D03*
Y1213582D03*
Y1217322D03*
X632086Y1224803D03*
X624606D03*
X628346Y1236023D03*
Y1232283D03*
X635827Y1236023D03*
Y1232283D03*
X632086Y1247243D03*
Y1239763D03*
X628346D03*
Y1250984D03*
X624606Y1243503D03*
Y1239763D03*
X632087Y1258465D03*
X624606D03*
X631928Y1396583D03*
Y1408495D03*
X647046Y1071455D03*
X639566D03*
X643307Y1090157D03*
X639567D03*
X650787D03*
X647047D03*
X639567Y1101377D03*
Y1105117D03*
X647047D03*
Y1101377D03*
X650787Y1097637D03*
X643307D03*
Y1093897D03*
X650787D03*
X637697Y1114468D03*
X648917Y1118208D03*
X645177D03*
X641437D03*
X637697D03*
X648917Y1121948D03*
X645177D03*
X641437D03*
X637697D03*
Y1110728D03*
X652657Y1118208D03*
Y1121948D03*
X650787Y1108858D03*
X647047D03*
X643307D03*
X639567D03*
X641437Y1133169D03*
X637697D03*
X645177Y1136909D03*
X637697D03*
X645177Y1140649D03*
X641437D03*
X652657Y1133169D03*
Y1129429D03*
Y1125688D03*
Y1136909D03*
X637697Y1140649D03*
X648917Y1125688D03*
X645177D03*
X641437D03*
X637697D03*
X645177Y1129429D03*
X641437D03*
X637697D03*
X645177Y1133169D03*
X637697Y1155610D03*
Y1151870D03*
X645177Y1144389D03*
X637697D03*
Y1148129D03*
X645177Y1151870D03*
X648917Y1155610D03*
Y1148129D03*
X652657Y1151869D03*
Y1144389D03*
X645177Y1170570D03*
X637697Y1166830D03*
X645177Y1159350D03*
X637697D03*
X648917Y1166830D03*
X652657Y1159350D03*
Y1170570D03*
X637697Y1189271D03*
X645177Y1185531D03*
X637697D03*
Y1178051D03*
Y1174310D03*
Y1181791D03*
X652657Y1189271D03*
X648917Y1181791D03*
Y1174310D03*
X652657Y1185531D03*
Y1178051D03*
Y1193011D03*
Y1204232D03*
X637697Y1193011D03*
X645177Y1196751D03*
Y1200491D03*
X641437D03*
Y1204232D03*
X645177D03*
X648917D03*
Y1196751D03*
Y1200491D03*
X641437Y1193011D03*
Y1196751D03*
X652657Y1200491D03*
Y1196751D03*
Y1211712D03*
X648917Y1219192D03*
X641437D03*
Y1211712D03*
X645177D03*
X648917D03*
Y1207972D03*
X645177D03*
X641437D03*
X652657D03*
X639567Y1221062D03*
X647047D03*
X643307D03*
X650787D03*
X639567Y1224803D03*
X643307Y1236023D03*
Y1232283D03*
X650787Y1236023D03*
X647047Y1224803D03*
X650787Y1232283D03*
X639567Y1243503D03*
X647047D03*
X650787Y1239763D03*
X643307D03*
X647047Y1258465D03*
X639567D03*
X644168Y1384297D03*
Y1372385D03*
Y1396583D03*
Y1408495D03*
X669487Y1071455D03*
X662007D03*
X654526D03*
X669488Y1090157D03*
X665748D03*
X654527D03*
X658268D03*
X662008D03*
Y1101377D03*
X665748Y1093897D03*
X658268D03*
X654527Y1105117D03*
Y1101377D03*
X662008Y1105117D03*
X658268Y1097637D03*
X669488Y1101377D03*
Y1105117D03*
X665748Y1097637D03*
X656398Y1118208D03*
Y1121948D03*
X663878Y1118208D03*
X660138D03*
Y1121948D03*
X663878D03*
X667618Y1118208D03*
Y1121948D03*
X669488Y1108858D03*
X665748D03*
X662008D03*
X658268D03*
X654527D03*
X656398Y1140649D03*
X660138D03*
X663878D03*
X656398Y1125688D03*
X660138D03*
X663878D03*
Y1133169D03*
X660138D03*
X656398D03*
X667618D03*
Y1140649D03*
Y1125688D03*
Y1148129D03*
X660138D03*
X656398D03*
X663878D03*
X656398Y1155610D03*
X663878D03*
Y1166830D03*
X660138Y1159350D03*
X656398Y1166830D03*
X660138Y1170570D03*
X667618Y1159350D03*
Y1170570D03*
X663878Y1181791D03*
X660138D03*
X656398D03*
X663878Y1189271D03*
X660138D03*
X656398D03*
X667618Y1181791D03*
Y1189271D03*
X656398Y1174310D03*
X663878D03*
Y1196751D03*
X660138D03*
X656398D03*
Y1204232D03*
X660138D03*
X663878D03*
X667618Y1196751D03*
Y1204232D03*
X663878Y1207972D03*
X660138D03*
X656398D03*
X667618D03*
X654527Y1221062D03*
X658268D03*
X662008D03*
X665748D03*
X669488D03*
X654527Y1224803D03*
X658268Y1236023D03*
Y1232283D03*
X662008Y1224803D03*
X665748Y1236023D03*
Y1232283D03*
X669488Y1224803D03*
X654527Y1239763D03*
Y1243503D03*
X665748Y1239763D03*
X669488Y1243503D03*
X662008D03*
Y1258465D03*
X669488D03*
X654528D03*
X668648Y1348187D03*
X656408D03*
X668648Y1360099D03*
X656408D03*
Y1384297D03*
Y1372385D03*
X668648D03*
Y1384297D03*
Y1396583D03*
X656408D03*
X668648Y1408495D03*
X656408D03*
X684448Y1071455D03*
X676967D03*
X680709Y1090157D03*
X676968D03*
X684449D03*
X673228D03*
X676968Y1105117D03*
X684449Y1101377D03*
Y1105117D03*
X680709Y1093897D03*
X676968Y1101377D03*
X680709Y1097637D03*
X673228D03*
Y1093897D03*
X682579Y1118208D03*
Y1121948D03*
X671358Y1118208D03*
X675098D03*
X678838D03*
X675098Y1121948D03*
X678838D03*
X671358D03*
X684449Y1108858D03*
X680709D03*
X676968D03*
X673228D03*
X682579Y1133169D03*
Y1140649D03*
Y1125688D03*
X671358Y1140649D03*
X675098D03*
X678838D03*
X675098Y1125688D03*
X671358D03*
X678838D03*
Y1133169D03*
X675098D03*
X671358D03*
X682579Y1148129D03*
X678838D03*
X675098D03*
X671358D03*
Y1155610D03*
X678838D03*
X682579Y1170570D03*
Y1159350D03*
X675098Y1170570D03*
X678839Y1166830D03*
X671358D03*
X675098Y1159350D03*
Y1181791D03*
X671358D03*
X678838Y1189271D03*
X675098D03*
X671358D03*
X682579Y1181791D03*
Y1189271D03*
X678838Y1181791D03*
X671358Y1174310D03*
X678838D03*
X682579Y1196751D03*
Y1204232D03*
X678838D03*
Y1196751D03*
X675098D03*
X671358D03*
Y1204232D03*
X675098D03*
X682579Y1207972D03*
X678838Y1219192D03*
Y1207972D03*
X675098D03*
X671358D03*
X673228Y1221062D03*
X676968D03*
X680709D03*
X684449D03*
X673228Y1236023D03*
Y1232283D03*
X676968Y1224803D03*
X680709Y1236023D03*
Y1232283D03*
X684449Y1224803D03*
X673228Y1239763D03*
X680709D03*
X676968Y1243503D03*
X684449D03*
X684450Y1258465D03*
X676969D03*
X680888Y1348187D03*
Y1360099D03*
Y1372385D03*
Y1384297D03*
Y1396583D03*
Y1408495D03*
X695669Y1075196D03*
X699408Y1071455D03*
X691928Y1071454D03*
X688189Y1090157D03*
X691929Y1082677D03*
Y1086417D03*
X695669Y1090157D03*
X699409D03*
Y1086417D03*
X691929Y1090157D03*
X688189Y1097637D03*
X695669Y1093897D03*
X688189D03*
X699409Y1105117D03*
X691929Y1101377D03*
X699409D03*
X691929Y1105117D03*
X693799Y1121948D03*
X697539D03*
X701279D03*
X686319D03*
Y1118208D03*
Y1114468D03*
X699409Y1108858D03*
X695669D03*
X691929D03*
X688189D03*
X693799Y1133464D03*
X697539Y1133169D03*
X686417Y1132677D03*
X693799Y1140649D03*
X697539D03*
X693799Y1125688D03*
X697539D03*
X701279D03*
Y1140649D03*
Y1133169D03*
X686319Y1140649D03*
Y1125688D03*
X697539Y1148129D03*
X701279D03*
X693799D03*
X697539Y1155610D03*
X686319Y1148129D03*
Y1155610D03*
X697539Y1166830D03*
X693799Y1170570D03*
Y1159350D03*
X701279D03*
Y1170570D03*
X686319Y1166830D03*
X693799Y1181791D03*
Y1189271D03*
X697539D03*
X701279D03*
Y1181791D03*
X697539D03*
Y1174310D03*
X686319Y1181791D03*
Y1189271D03*
Y1174310D03*
X697539Y1204232D03*
X693799D03*
Y1196751D03*
X697539D03*
X701279D03*
Y1204232D03*
X686319Y1196751D03*
Y1204232D03*
X693799Y1207972D03*
X697539D03*
Y1211712D03*
X701279Y1207972D03*
Y1211712D03*
X686319Y1207972D03*
X695669Y1221062D03*
X699409D03*
X691929D03*
X688189D03*
Y1236023D03*
Y1232283D03*
X691929Y1224803D03*
Y1228543D03*
X699409Y1224803D03*
Y1228543D03*
X695669Y1236023D03*
Y1232283D03*
X688189Y1239763D03*
X695669D03*
X699409Y1258465D03*
X691929D03*
X693128Y1348187D03*
Y1360099D03*
Y1372385D03*
Y1384297D03*
Y1396583D03*
Y1408495D03*
X703149Y1075196D03*
X718110D03*
X710630D03*
X714369Y1071455D03*
X706889D03*
X710630Y1078936D03*
X706890Y1086417D03*
Y1090157D03*
X718110Y1078936D03*
X714370Y1086417D03*
Y1090157D03*
X710630D03*
X718110D03*
X703149Y1078936D03*
Y1090157D03*
X706890Y1105117D03*
X714370D03*
X710630Y1097637D03*
Y1093897D03*
X718110Y1097637D03*
Y1093897D03*
X703149D03*
Y1097637D03*
X716240Y1121948D03*
X705020D03*
X708760D03*
X712500D03*
X718110Y1108858D03*
X714370D03*
X710630D03*
X706890D03*
X703149D03*
X716240Y1140649D03*
Y1125688D03*
Y1133169D03*
X712500Y1125688D03*
X708760D03*
X705020D03*
X712500Y1140649D03*
X708760D03*
X705020D03*
X712500Y1133169D03*
X708760D03*
X705020D03*
X716240Y1148129D03*
X712500D03*
X708760D03*
X705020D03*
X712500Y1155610D03*
X705020D03*
X716240Y1170570D03*
Y1159350D03*
X708760D03*
X705020Y1166830D03*
X712500D03*
X708760Y1170570D03*
X716240Y1189271D03*
Y1181791D03*
X712500Y1189271D03*
X708760D03*
X705020D03*
X712500Y1181791D03*
X708760D03*
X705020D03*
Y1174310D03*
X712500D03*
X716240Y1196751D03*
Y1204232D03*
X712500Y1196751D03*
X708760D03*
X705020D03*
X708760Y1204232D03*
X712500D03*
X705020D03*
X716240Y1211712D03*
Y1207972D03*
X712500D03*
Y1211712D03*
X708760Y1207972D03*
X705020D03*
X703149Y1221062D03*
X706890D03*
X710630D03*
X714370D03*
X718110D03*
X703149Y1236023D03*
Y1232283D03*
X710630Y1236023D03*
X718110D03*
Y1232283D03*
X710630D03*
X714370Y1224803D03*
Y1228543D03*
X706890Y1224803D03*
Y1228543D03*
X703149Y1239763D03*
X714370D03*
Y1258465D03*
X706890D03*
X705368Y1348187D03*
X717608D03*
X705368Y1360099D03*
X717608D03*
X705368Y1372385D03*
Y1384297D03*
X717608Y1372385D03*
Y1384297D03*
Y1396583D03*
X705368D03*
X717608Y1408495D03*
X705368D03*
X725590Y1075196D03*
X733071D03*
X729330Y1071455D03*
X721849D03*
X729331Y1086417D03*
Y1082677D03*
X733071Y1090157D03*
X729331D03*
X725590D03*
X721850D03*
X725590Y1078936D03*
X721850Y1086417D03*
X725590Y1097637D03*
X721850Y1105117D03*
X725590Y1093897D03*
X729331Y1105117D03*
X733071Y1093897D03*
X734941Y1118208D03*
X727460Y1121948D03*
X719980D03*
X723720D03*
X727460Y1118208D03*
X731201D03*
X733071Y1108858D03*
X729331D03*
X725590D03*
X721850D03*
X734941Y1140649D03*
Y1136909D03*
X727460Y1140649D03*
X723720Y1125688D03*
X719980D03*
X727460Y1129429D03*
Y1125688D03*
X723720Y1140649D03*
X719980D03*
X727460Y1133169D03*
X723720D03*
X719980D03*
X727460Y1136909D03*
X731201Y1125688D03*
X727460Y1151869D03*
Y1148129D03*
Y1144389D03*
X723720Y1148129D03*
X719980D03*
X731201D03*
Y1151869D03*
Y1155610D03*
X734941Y1151870D03*
Y1148129D03*
Y1144389D03*
X719980Y1155610D03*
X727460D03*
X731201Y1170570D03*
X719980Y1166830D03*
X731201Y1159350D03*
Y1166830D03*
X727460Y1185531D03*
X734941Y1181791D03*
Y1185531D03*
Y1189271D03*
Y1178051D03*
X727460Y1189271D03*
X723720Y1181791D03*
X719980D03*
Y1174310D03*
X727460Y1178051D03*
X723720Y1189271D03*
X719980D03*
X731201Y1174310D03*
Y1181791D03*
X727460Y1174310D03*
X719980Y1204232D03*
X727460D03*
X727480Y1196732D03*
X731201Y1196751D03*
X734941Y1193011D03*
X727460D03*
X723720Y1196751D03*
X719980D03*
X727460Y1200491D03*
X723720Y1204232D03*
X734941Y1211712D03*
X727460Y1207972D03*
X723720Y1211712D03*
Y1207972D03*
X719980Y1211712D03*
Y1207972D03*
X727460Y1211712D03*
X731201Y1207972D03*
X733071Y1221062D03*
X721850D03*
X725590D03*
X729331D03*
Y1224803D03*
Y1228543D03*
X733071Y1236023D03*
Y1232283D03*
X725590Y1236023D03*
Y1232283D03*
X721850Y1224803D03*
Y1228543D03*
X725590Y1239763D03*
X729331Y1258465D03*
X721850D03*
X729848Y1348187D03*
Y1360099D03*
Y1372385D03*
Y1384297D03*
Y1396489D03*
Y1408401D03*
X740551Y1075196D03*
X748031D03*
X744290Y1071455D03*
X736810D03*
X748030Y1090157D03*
X744291D03*
X740551Y1078936D03*
Y1090157D03*
X736811D03*
X744291Y1101377D03*
X748031Y1093897D03*
X744291Y1105117D03*
X736811D03*
X748031Y1123818D03*
Y1120078D03*
Y1116338D03*
Y1112598D03*
Y1108858D03*
X744291D03*
X740551D03*
X736811D03*
X738681Y1136909D03*
Y1140649D03*
X748031Y1138779D03*
Y1135039D03*
Y1131299D03*
Y1127558D03*
X738681Y1155610D03*
Y1148129D03*
X749901Y1144389D03*
Y1151869D03*
X746161Y1155610D03*
Y1151869D03*
X742421D03*
X738681D03*
Y1166830D03*
X746161Y1170570D03*
Y1166830D03*
X738681Y1159350D03*
X749901Y1166830D03*
Y1159350D03*
X738681Y1170570D03*
X746161Y1159350D03*
X749901Y1181791D03*
Y1174310D03*
X738681D03*
Y1178051D03*
X742421Y1181791D03*
X738681Y1185531D03*
Y1189271D03*
X746161Y1185531D03*
Y1178051D03*
Y1174310D03*
X742421Y1185531D03*
X748031Y1191141D03*
X738681Y1204232D03*
Y1193011D03*
Y1196751D03*
X742421Y1193011D03*
X748031Y1202362D03*
Y1198621D03*
X736811Y1221062D03*
X740551D03*
X748031D03*
X744291D03*
X748031Y1217322D03*
Y1213582D03*
Y1209842D03*
Y1206102D03*
X736811Y1224803D03*
Y1228543D03*
X748031Y1236023D03*
Y1232283D03*
X740551Y1236023D03*
X744291Y1228543D03*
X740551Y1232283D03*
X744291Y1224803D03*
X748031Y1239763D03*
X740551D03*
X744291Y1258465D03*
X736811D03*
X742088Y1348187D03*
Y1360099D03*
Y1384297D03*
Y1372385D03*
Y1396489D03*
Y1408401D03*
X755512Y1075196D03*
X762993D03*
X766732Y1071455D03*
X759252D03*
X751771D03*
X755511Y1090157D03*
X762993Y1078936D03*
X755513D03*
X751772Y1105117D03*
X762992Y1093897D03*
X759252Y1105117D03*
X766732D03*
X755512Y1093897D03*
X762991Y1108857D03*
X755512Y1108858D03*
X751772D03*
X759252Y1116338D03*
Y1123818D03*
X751771Y1112598D03*
Y1120078D03*
X757382Y1140649D03*
X759252Y1131299D03*
X757382Y1148129D03*
X764862Y1170570D03*
X757382Y1166830D03*
Y1159350D03*
Y1174310D03*
Y1181791D03*
X764862Y1185531D03*
Y1178051D03*
X755512Y1187401D03*
X764862Y1189271D03*
X766732Y1194881D03*
X751772D03*
X755512Y1202362D03*
X766732D03*
Y1198621D03*
X762992D03*
X766732Y1221062D03*
Y1217322D03*
X762992Y1221062D03*
X759252D03*
X762992Y1213582D03*
X766732D03*
Y1209842D03*
X755512D03*
X766732Y1206102D03*
X751772Y1221062D03*
Y1217322D03*
X759252Y1224803D03*
Y1228543D03*
X755512Y1232283D03*
Y1236023D03*
X766732Y1224803D03*
Y1228543D03*
X762992Y1232283D03*
Y1236023D03*
X751772Y1224803D03*
Y1228543D03*
X755512Y1239763D03*
X766732D03*
Y1258465D03*
X759252D03*
X751772D03*
X766568Y1348187D03*
X754328D03*
X766568Y1360099D03*
X754328D03*
Y1372385D03*
Y1384297D03*
X766568Y1372385D03*
Y1384297D03*
X777953Y1075196D03*
X770473D03*
X774212Y1071455D03*
X777953Y1078936D03*
X781693D03*
X770473D03*
X770471Y1090157D03*
X770472Y1093897D03*
Y1108858D03*
X776083Y1140649D03*
Y1148129D03*
Y1155610D03*
Y1170570D03*
X768602Y1166830D03*
X779823Y1170570D03*
X776083Y1178051D03*
Y1185531D03*
X779823D03*
Y1178051D03*
X768602Y1181791D03*
Y1174310D03*
X772342Y1189271D03*
X783503Y1193011D03*
X776083D03*
X779823D03*
X781693Y1202362D03*
X777953D03*
X770472Y1221062D03*
X777953Y1209842D03*
X774212Y1224803D03*
Y1228543D03*
X770472Y1236023D03*
Y1232283D03*
X777953D03*
X781693Y1250984D03*
X774212Y1258465D03*
X778808Y1348187D03*
Y1360099D03*
X785434Y1090158D03*
Y1082677D03*
Y1101378D03*
Y1123819D03*
Y1116339D03*
Y1108859D03*
Y1131300D03*
Y1198621D03*
Y1221062D03*
Y1213582D03*
Y1206102D03*
Y1228543D03*
Y1247243D03*
Y1239762D03*
X892183Y1728286D03*
Y1738286D03*
X891761Y1775438D03*
Y1785438D03*
X1057381Y1103247D03*
Y1140649D03*
Y1133169D03*
Y1125688D03*
Y1151870D03*
Y1144389D03*
X1054881Y1170570D03*
X1057381Y1159350D03*
X1054881Y1178050D03*
X1059251Y1187401D03*
Y1183661D03*
Y1194881D03*
Y1202362D03*
X1055510Y1198622D03*
Y1191142D03*
X1059251Y1209842D03*
Y1217322D03*
X1055510Y1221063D03*
Y1213583D03*
Y1206103D03*
X1059251Y1232283D03*
Y1236023D03*
Y1224803D03*
X1052473Y1348187D03*
Y1360099D03*
Y1384297D03*
Y1372385D03*
X1064861Y1077066D03*
X1061121Y1080806D03*
X1072342Y1106988D03*
X1061121Y1103247D03*
X1072342Y1121948D03*
Y1118208D03*
X1064862Y1121948D03*
X1068602D03*
X1072342Y1140649D03*
Y1125688D03*
X1061121D03*
Y1140649D03*
X1064862D03*
X1068602D03*
X1064862Y1136909D03*
X1061121Y1133169D03*
X1064862Y1129429D03*
X1068602D03*
X1072342Y1155610D03*
X1064862D03*
X1068602D03*
X1061121Y1151870D03*
X1064862D03*
Y1148129D03*
X1061121Y1144389D03*
X1064862D03*
X1072342Y1166830D03*
X1064861Y1170570D03*
X1068602D03*
X1064861Y1166830D03*
X1061121Y1159350D03*
X1064862D03*
X1072342Y1181791D03*
Y1174310D03*
X1061120Y1181791D03*
X1064861D03*
X1068602D03*
Y1174310D03*
X1064861Y1178051D03*
X1061120Y1174310D03*
X1064861D03*
X1074212Y1187401D03*
X1062991D03*
Y1183661D03*
X1066732D03*
X1070472D03*
X1074212D03*
Y1191141D03*
Y1198621D03*
X1070472Y1191141D03*
X1066732D03*
X1070472Y1198621D03*
X1066732D03*
X1062991Y1194881D03*
Y1202362D03*
X1074212Y1206102D03*
X1066732D03*
X1070472D03*
Y1213582D03*
X1066732D03*
X1062991Y1209842D03*
Y1217322D03*
X1074212Y1221062D03*
X1066732D03*
X1070472D03*
Y1236023D03*
Y1232283D03*
X1066732Y1228543D03*
Y1224803D03*
X1074212D03*
X1062991Y1236023D03*
Y1232283D03*
Y1224803D03*
X1066732Y1239763D03*
Y1243503D03*
X1074212Y1239763D03*
Y1243503D03*
Y1258465D03*
X1066732D03*
X1072593Y1348187D03*
X1064713D03*
X1060353D03*
X1072593Y1360099D03*
X1064713D03*
X1060353D03*
X1072593Y1384297D03*
Y1372385D03*
X1064713D03*
Y1384297D03*
X1060353D03*
Y1372385D03*
X1072593Y1396583D03*
X1064713D03*
X1072593Y1408495D03*
X1064713D03*
X1089171Y1071455D03*
X1083562Y1092027D03*
X1089172Y1090157D03*
X1083562Y1095767D03*
X1087302Y1106988D03*
X1079822D03*
X1083562D03*
X1076082D03*
X1089172Y1101377D03*
Y1105117D03*
X1083562Y1118208D03*
X1087302D03*
X1079822Y1114468D03*
X1083562Y1110728D03*
X1087302D03*
X1091043D03*
Y1121948D03*
Y1118208D03*
Y1114468D03*
X1076082D03*
X1089172Y1108858D03*
X1091043Y1125688D03*
Y1140649D03*
X1079822Y1129429D03*
Y1140649D03*
X1083562D03*
X1087302D03*
X1091043Y1136909D03*
Y1133169D03*
Y1129429D03*
X1076082Y1140649D03*
X1087302Y1151870D03*
Y1155610D03*
Y1148129D03*
X1083562Y1144389D03*
X1087302D03*
X1076082Y1155610D03*
Y1151870D03*
Y1148129D03*
Y1144389D03*
X1087302Y1170570D03*
Y1166830D03*
Y1159350D03*
X1091043Y1170570D03*
X1076082Y1159350D03*
X1081692Y1179921D03*
X1083562Y1181791D03*
X1087302D03*
Y1178051D03*
Y1174310D03*
X1076082Y1181791D03*
Y1178051D03*
Y1174310D03*
X1077952Y1183661D03*
X1081692D03*
X1085432D03*
X1089172Y1187401D03*
X1085432D03*
X1091043Y1185531D03*
X1077952Y1191141D03*
Y1198621D03*
X1081692Y1191141D03*
X1085432Y1194881D03*
X1089172D03*
X1085432Y1202362D03*
X1089172D03*
X1077952Y1206102D03*
X1081692D03*
X1085432Y1209842D03*
X1077952Y1221062D03*
X1089172Y1217322D03*
Y1221062D03*
X1085432D03*
Y1217322D03*
X1077952Y1232283D03*
Y1236023D03*
X1085432Y1232283D03*
Y1236023D03*
X1081692Y1224803D03*
X1089172D03*
X1077952Y1239763D03*
X1081692D03*
Y1243503D03*
X1085432Y1250984D03*
Y1239763D03*
X1089172D03*
Y1247243D03*
X1089173Y1258465D03*
X1081692D03*
X1089193Y1348187D03*
X1084833D03*
X1076953D03*
X1089193Y1360099D03*
X1084833D03*
X1076953D03*
X1089193Y1384297D03*
Y1372385D03*
X1084833Y1384297D03*
Y1372385D03*
X1076953Y1384297D03*
Y1372385D03*
X1089193Y1396583D03*
X1084833D03*
X1076953D03*
X1089193Y1408495D03*
X1084833D03*
X1076953D03*
X1104132Y1071455D03*
X1096652D03*
X1092913Y1090157D03*
X1104133D03*
X1107873D03*
X1100393D03*
X1096653D03*
X1092913Y1093897D03*
Y1097637D03*
X1107873Y1093897D03*
Y1097637D03*
X1104133Y1101377D03*
X1100393Y1097637D03*
Y1093897D03*
X1096653Y1101377D03*
X1104133Y1105117D03*
X1096653D03*
X1094783Y1110728D03*
Y1121948D03*
X1098523D03*
X1102263D03*
X1106003D03*
X1094783Y1118208D03*
X1098523D03*
X1102263D03*
X1106003D03*
X1094783Y1114468D03*
X1107873Y1108858D03*
X1104133D03*
X1100393D03*
X1096653D03*
X1092913D03*
X1098523Y1140649D03*
X1102263D03*
X1094783Y1136909D03*
X1102263D03*
X1094783Y1133169D03*
X1098523D03*
X1102263D03*
X1094783Y1129429D03*
X1098523D03*
X1102263D03*
X1094783Y1125688D03*
X1098523D03*
X1102263D03*
X1106003D03*
X1094783Y1140649D03*
Y1151870D03*
Y1155610D03*
X1102263Y1151870D03*
X1094783Y1148129D03*
Y1144389D03*
X1102263D03*
X1106003Y1148129D03*
Y1155610D03*
X1102263Y1170570D03*
X1094783Y1159350D03*
X1102263D03*
X1094783Y1166830D03*
X1106003D03*
X1094783Y1181791D03*
X1102263Y1185531D03*
X1094783Y1174310D03*
Y1178051D03*
X1106003Y1181791D03*
Y1174310D03*
X1092913Y1187401D03*
X1098523Y1196751D03*
Y1193011D03*
X1106003Y1200491D03*
Y1196751D03*
Y1204232D03*
X1102263D03*
X1098523D03*
Y1200491D03*
X1102263D03*
Y1196751D03*
X1092913Y1191141D03*
Y1194881D03*
Y1198621D03*
Y1202362D03*
X1098523Y1207972D03*
X1102263D03*
X1106003D03*
Y1211712D03*
X1102263D03*
X1098523D03*
Y1219192D03*
X1106003D03*
X1092913Y1206102D03*
Y1209842D03*
Y1213582D03*
Y1217322D03*
X1107873Y1221062D03*
X1104133D03*
X1100393D03*
X1096653D03*
X1092913D03*
Y1232283D03*
Y1236023D03*
X1107873Y1232283D03*
X1104133Y1224803D03*
X1107873Y1236023D03*
X1100393Y1232283D03*
Y1236023D03*
X1096653Y1224803D03*
X1100393Y1239763D03*
X1107873D03*
X1104133Y1243503D03*
X1096653D03*
X1104133Y1258465D03*
X1096653D03*
X1101433Y1348187D03*
X1097073D03*
X1101433Y1360099D03*
X1097073D03*
X1101433Y1384297D03*
Y1372385D03*
X1097073D03*
Y1384297D03*
X1101433Y1396583D03*
X1097073D03*
X1101433Y1408495D03*
X1097073D03*
X1119093Y1071455D03*
X1111612D03*
X1115354Y1090157D03*
X1119094D03*
X1122834D03*
X1111613D03*
X1122834Y1093897D03*
X1115354D03*
X1122834Y1097637D03*
X1115354D03*
X1119094Y1101377D03*
X1111613D03*
X1119094Y1105117D03*
X1111613D03*
X1117224Y1121948D03*
Y1118208D03*
X1120964D03*
X1109743Y1121948D03*
X1113484D03*
X1109743Y1118208D03*
X1113484D03*
X1124704Y1121948D03*
Y1118208D03*
X1120964Y1121948D03*
X1122834Y1108858D03*
X1119094D03*
X1115354D03*
X1111613D03*
X1109743Y1136909D03*
X1124704Y1125688D03*
Y1140649D03*
Y1133169D03*
X1113484D03*
X1117224D03*
X1120964D03*
X1109743Y1125688D03*
X1120964D03*
X1117224D03*
X1113484D03*
X1120964Y1140649D03*
X1117224D03*
X1113484D03*
X1109743Y1129429D03*
Y1133169D03*
X1113484Y1155610D03*
X1109743Y1144389D03*
X1120964Y1155610D03*
X1109743Y1151869D03*
X1120964Y1148129D03*
X1113484D03*
X1117224D03*
X1124704D03*
X1117224Y1170570D03*
X1109743D03*
X1113484Y1166830D03*
X1117224Y1159350D03*
X1120964Y1166830D03*
X1109743Y1159350D03*
X1124704Y1170570D03*
Y1159350D03*
X1109743Y1189271D03*
X1113484D03*
X1117224D03*
X1120964D03*
X1113484Y1181791D03*
X1117224D03*
X1120964D03*
X1124704Y1189271D03*
Y1181791D03*
X1109743Y1178051D03*
X1120964Y1174310D03*
X1109743Y1185531D03*
X1113484Y1174310D03*
X1124704Y1204232D03*
Y1196751D03*
X1120964Y1204232D03*
X1117224D03*
X1113484D03*
X1109743D03*
Y1193011D03*
Y1196751D03*
Y1200491D03*
X1113484Y1196751D03*
X1117224D03*
X1120964D03*
X1113484Y1207972D03*
X1117224D03*
X1120964D03*
X1109743Y1211712D03*
Y1207972D03*
X1124704D03*
X1122834Y1221062D03*
X1119094D03*
X1115354D03*
X1111613D03*
X1122834Y1232283D03*
Y1236023D03*
X1119094Y1224803D03*
X1115354Y1232283D03*
Y1236023D03*
X1111613Y1224803D03*
X1119094Y1243503D03*
X1122834Y1239763D03*
X1111613Y1243503D03*
Y1239763D03*
X1119094Y1258465D03*
X1111614D03*
X1113673Y1348187D03*
X1121553D03*
X1109313D03*
X1113673Y1360099D03*
X1121553D03*
X1109313D03*
X1113673Y1372385D03*
Y1384297D03*
X1121553Y1372385D03*
Y1384297D03*
X1109313D03*
Y1372385D03*
X1113673Y1396583D03*
X1121553D03*
X1109313D03*
X1113673Y1408495D03*
X1121553D03*
X1109313D03*
X1134053Y1071455D03*
X1126573D03*
X1126574Y1090157D03*
X1130314D03*
X1134054D03*
X1137795D03*
X1126574Y1101377D03*
X1130314Y1097637D03*
Y1093897D03*
X1137795D03*
Y1097637D03*
X1134054Y1101377D03*
X1126574Y1105117D03*
X1134054D03*
X1139665Y1121948D03*
X1130314Y1112598D03*
X1128444Y1118208D03*
X1132184D03*
X1135924D03*
X1132184Y1121948D03*
X1135924D03*
X1128444D03*
X1139665Y1118208D03*
X1137795Y1108858D03*
X1134054D03*
X1130314D03*
X1126574D03*
X1139665Y1125688D03*
X1128444Y1140649D03*
X1132184D03*
X1135924D03*
X1132184Y1125688D03*
X1128444D03*
X1135924D03*
Y1133169D03*
X1132184D03*
X1128444D03*
X1139665D03*
Y1140649D03*
X1135924Y1148129D03*
X1132184D03*
X1128444D03*
X1139665D03*
X1128444Y1155610D03*
X1135924D03*
X1139665Y1170570D03*
Y1159350D03*
X1132184Y1170570D03*
X1135925Y1166830D03*
X1128444D03*
X1132184Y1159350D03*
X1135924Y1181791D03*
X1132184D03*
X1128444D03*
X1135924Y1189271D03*
X1132184D03*
X1128444D03*
Y1174310D03*
X1135924D03*
X1139665Y1181791D03*
Y1189271D03*
Y1196751D03*
Y1204232D03*
X1135924D03*
Y1196751D03*
X1132184D03*
X1128444D03*
Y1204232D03*
X1132184D03*
X1139665Y1207972D03*
X1134054Y1217322D03*
X1135924Y1207972D03*
X1132184D03*
X1128444D03*
X1137795Y1221062D03*
X1134054D03*
X1130314D03*
X1126574D03*
Y1224803D03*
X1137795Y1232283D03*
Y1236023D03*
X1134054Y1224803D03*
X1130314Y1232283D03*
Y1236023D03*
X1126574Y1243503D03*
X1134054D03*
X1137795Y1239763D03*
X1130314D03*
X1134055Y1258465D03*
X1126574D03*
X1138153Y1348187D03*
X1133793D03*
X1125913D03*
X1138153Y1360099D03*
X1133793D03*
X1125913D03*
X1138153Y1384297D03*
Y1372385D03*
X1133793Y1384297D03*
Y1372385D03*
X1125913Y1384297D03*
Y1372385D03*
X1138153Y1396583D03*
X1133793D03*
X1125913D03*
X1138153Y1408495D03*
X1133793D03*
X1125913D03*
X1152755Y1075196D03*
X1156494Y1071455D03*
X1149014Y1071454D03*
X1141534Y1071455D03*
X1141535Y1090157D03*
X1149015Y1082677D03*
Y1086417D03*
X1152755Y1090157D03*
X1156495D03*
Y1086417D03*
X1149015Y1090157D03*
X1145275D03*
X1141535Y1101377D03*
X1149015D03*
X1152755Y1093897D03*
X1156495Y1101377D03*
X1145275Y1093897D03*
Y1097637D03*
X1141535Y1105117D03*
X1149015D03*
X1156495D03*
X1150885Y1121948D03*
X1143405D03*
Y1118208D03*
Y1114468D03*
X1154625Y1121948D03*
X1156495Y1108858D03*
X1152755D03*
X1149015D03*
X1145275D03*
X1141535D03*
X1154625Y1125688D03*
X1150885Y1133464D03*
X1154625Y1133169D03*
X1143503Y1132677D03*
X1143405Y1140649D03*
Y1125688D03*
X1150885Y1140649D03*
X1154625D03*
X1150885Y1125688D03*
X1143405Y1148129D03*
X1150885D03*
X1154625D03*
X1143405Y1155610D03*
X1154625D03*
Y1166830D03*
X1150885Y1170570D03*
X1143405Y1166830D03*
X1150885Y1159350D03*
X1143405Y1181791D03*
X1154625D03*
X1150885D03*
Y1189271D03*
X1154625D03*
X1143405D03*
Y1174310D03*
X1154625D03*
X1150885Y1196751D03*
X1154625Y1204232D03*
X1150885D03*
X1154625Y1196751D03*
X1143405D03*
Y1204232D03*
X1150885Y1207972D03*
X1154625D03*
Y1211712D03*
X1143405Y1207972D03*
X1149015Y1221062D03*
X1156495D03*
X1152755D03*
X1145275D03*
X1141535D03*
Y1224803D03*
X1152755Y1232283D03*
Y1236023D03*
X1156495Y1228543D03*
Y1224803D03*
X1149015Y1228543D03*
Y1224803D03*
X1145275Y1232283D03*
Y1236023D03*
X1141535Y1243503D03*
X1152755Y1239763D03*
X1145275D03*
X1156495Y1258465D03*
X1149015D03*
X1141536D03*
X1150393Y1348187D03*
X1146033D03*
X1150393Y1360099D03*
X1146033D03*
X1150393Y1384297D03*
Y1372385D03*
X1146033D03*
Y1384297D03*
X1150393Y1396583D03*
X1146033D03*
X1150393Y1408495D03*
X1146033D03*
X1167716Y1075196D03*
X1160235D03*
X1171455Y1071455D03*
X1163975D03*
X1167716Y1078936D03*
X1163976Y1086417D03*
Y1090157D03*
X1171456Y1086417D03*
Y1090157D03*
X1167716D03*
X1160235Y1078936D03*
Y1090157D03*
X1167716Y1097637D03*
Y1093897D03*
X1160235D03*
Y1097637D03*
X1163976Y1105117D03*
X1171456D03*
X1169586Y1121948D03*
X1165846D03*
X1162106D03*
X1158365D03*
X1173326D03*
X1171456Y1108858D03*
X1167716D03*
X1163976D03*
X1160235D03*
X1162106Y1133169D03*
X1165846D03*
X1169586D03*
X1158365Y1140649D03*
X1162106D03*
X1165846D03*
X1169586D03*
X1158365Y1125688D03*
X1162106D03*
X1165846D03*
X1169586D03*
X1173326Y1133169D03*
Y1125688D03*
Y1140649D03*
X1158365Y1133169D03*
X1173326Y1148129D03*
X1158365D03*
X1162106D03*
X1165846D03*
X1169586D03*
X1162106Y1155610D03*
X1169586D03*
X1158365Y1170570D03*
X1165846D03*
X1169586Y1166830D03*
X1158365Y1159350D03*
X1162106Y1166830D03*
X1165846Y1159350D03*
X1173326D03*
Y1170570D03*
Y1189271D03*
X1158365Y1181791D03*
X1162106D03*
X1165846D03*
X1169586D03*
X1158365Y1189271D03*
X1162106D03*
X1165846D03*
X1169586D03*
X1173326Y1181791D03*
X1169586Y1174310D03*
X1162106D03*
Y1204232D03*
X1158365D03*
X1169586D03*
X1165846D03*
X1158365Y1196751D03*
X1162106D03*
X1165846D03*
X1169586D03*
X1173326Y1204232D03*
Y1196751D03*
X1158365Y1211712D03*
Y1207972D03*
X1173326D03*
Y1211712D03*
X1162106Y1207972D03*
X1165846D03*
X1169586Y1211712D03*
Y1207972D03*
X1171456Y1221062D03*
X1167716D03*
X1163976D03*
X1160235D03*
X1163976Y1228543D03*
Y1224803D03*
X1171456Y1228543D03*
Y1224803D03*
X1167716Y1232283D03*
Y1236023D03*
X1160235Y1232283D03*
Y1236023D03*
X1171456Y1239763D03*
X1160235D03*
X1171456Y1258465D03*
X1163976D03*
X1162633Y1348187D03*
X1170513D03*
X1158273D03*
X1162633Y1360099D03*
X1170513D03*
X1158273D03*
X1162633Y1372385D03*
Y1384297D03*
X1170513Y1372385D03*
Y1384297D03*
X1158273D03*
Y1372385D03*
X1162633Y1396583D03*
X1170513D03*
X1158273D03*
X1162633Y1408495D03*
X1170513D03*
X1158273D03*
X1175196Y1075196D03*
X1182676D03*
X1186416Y1071455D03*
X1178935D03*
X1175196Y1078936D03*
Y1090157D03*
X1178936D03*
X1182676Y1078936D03*
X1178936Y1086417D03*
X1182676Y1090157D03*
X1186417D03*
Y1086417D03*
Y1082677D03*
X1175196Y1097637D03*
Y1093897D03*
X1182676Y1097637D03*
Y1093897D03*
X1178936Y1105117D03*
X1186417D03*
X1188287Y1118208D03*
X1184546D03*
X1180806Y1121948D03*
X1177066D03*
X1184546D03*
X1186417Y1108858D03*
X1182676D03*
X1178936D03*
X1175196D03*
X1188287Y1125688D03*
X1184546Y1136909D03*
X1177066Y1133169D03*
X1180806D03*
X1184546D03*
X1177066Y1140649D03*
X1180806D03*
X1184546Y1125688D03*
Y1129429D03*
X1177066Y1125688D03*
X1180806D03*
X1184546Y1140649D03*
X1188287Y1155610D03*
Y1151869D03*
Y1148129D03*
X1177066D03*
X1180806D03*
X1184546Y1144389D03*
Y1148129D03*
Y1151869D03*
X1177066Y1155610D03*
X1184546D03*
X1177066Y1166830D03*
X1188287D03*
Y1159350D03*
Y1170570D03*
Y1181791D03*
Y1174310D03*
X1177066Y1189271D03*
X1180806D03*
X1184546Y1178051D03*
X1177066Y1174310D03*
X1184546Y1185531D03*
X1177066Y1181791D03*
X1180806D03*
X1184546Y1189271D03*
Y1174310D03*
Y1204232D03*
X1177066D03*
X1180806D03*
X1184546Y1200491D03*
X1177066Y1196751D03*
X1180806D03*
X1184546Y1193011D03*
X1188287Y1196751D03*
X1184566Y1196732D03*
X1188287Y1207972D03*
X1184546Y1211712D03*
X1177066Y1207972D03*
Y1211712D03*
X1180806Y1207972D03*
Y1211712D03*
X1184546Y1207972D03*
X1186417Y1221062D03*
X1182676D03*
X1178936D03*
X1175196D03*
Y1232283D03*
Y1236023D03*
X1178936Y1228543D03*
Y1224803D03*
X1182676Y1232283D03*
Y1236023D03*
X1186417Y1228543D03*
Y1224803D03*
X1182676Y1239763D03*
X1186417Y1258465D03*
X1178936D03*
X1182753Y1348187D03*
X1174873D03*
X1182753Y1360099D03*
X1174873D03*
X1182753Y1384297D03*
Y1372385D03*
X1174873Y1384297D03*
Y1372385D03*
X1182753Y1396583D03*
X1174873D03*
X1182753Y1408495D03*
X1174873D03*
X1179329Y1728990D03*
Y1738990D03*
X1179123Y1776014D03*
Y1786014D03*
X1190157Y1075196D03*
X1197637D03*
X1205117D03*
X1201376Y1071455D03*
X1193896D03*
X1190157Y1090157D03*
X1197637Y1078936D03*
Y1090157D03*
X1201377D03*
X1205116D03*
X1193897D03*
X1190157Y1093897D03*
X1201377Y1101377D03*
X1205117Y1093897D03*
X1201377Y1105117D03*
X1193897D03*
X1192027Y1118208D03*
X1205117Y1123818D03*
Y1120078D03*
Y1116338D03*
Y1108858D03*
X1201377D03*
X1197637D03*
X1193897D03*
X1190157D03*
X1192027Y1136909D03*
X1195767Y1140649D03*
X1192027D03*
X1195767Y1136909D03*
X1205117Y1135039D03*
Y1131299D03*
Y1127558D03*
X1195767Y1148129D03*
X1192027Y1144389D03*
X1195767Y1155610D03*
X1192027Y1148129D03*
X1195767Y1151869D03*
X1199507D03*
X1203247D03*
Y1155610D03*
X1192027Y1151870D03*
X1195767Y1170570D03*
Y1159350D03*
X1203247Y1166830D03*
Y1170570D03*
Y1159350D03*
X1195767Y1166830D03*
X1192027Y1181791D03*
X1199507Y1185531D03*
X1203247Y1174310D03*
Y1178051D03*
Y1185531D03*
X1192027Y1178051D03*
Y1189271D03*
X1195767D03*
X1192027Y1185531D03*
X1195767D03*
X1199507Y1181791D03*
X1195767Y1178051D03*
Y1174310D03*
Y1204232D03*
X1199507Y1193011D03*
X1195767Y1196751D03*
Y1193011D03*
X1192027D03*
X1205117Y1198621D03*
Y1202362D03*
X1192027Y1211712D03*
X1205117Y1206102D03*
Y1209842D03*
Y1213582D03*
Y1217322D03*
Y1221062D03*
X1201377D03*
X1197637D03*
X1193897D03*
X1190157D03*
Y1232283D03*
Y1236023D03*
X1197637Y1232283D03*
X1201377Y1228543D03*
X1197637Y1236023D03*
X1201377Y1224803D03*
X1205117Y1232283D03*
Y1236023D03*
X1193897Y1228543D03*
Y1224803D03*
X1197637Y1239763D03*
X1205117D03*
X1201377Y1258465D03*
X1193897D03*
X1212598Y1075196D03*
X1220079D03*
X1216338Y1071455D03*
X1208857D03*
X1220079Y1078936D03*
X1212599D03*
X1212597Y1090157D03*
X1212598Y1093897D03*
X1220078D03*
X1216338Y1105117D03*
X1208858D03*
X1212598Y1108858D03*
X1216338Y1116338D03*
Y1123818D03*
X1208857Y1112598D03*
Y1120078D03*
X1220077Y1108857D03*
X1208858Y1108858D03*
X1214468Y1140649D03*
X1206987Y1136909D03*
X1216338Y1131299D03*
X1206987Y1151869D03*
X1214468Y1148129D03*
X1206987Y1144389D03*
Y1159350D03*
X1214468D03*
X1206987Y1166830D03*
X1214468D03*
X1221948Y1170570D03*
X1206987Y1181791D03*
X1214468Y1189271D03*
X1221948Y1178051D03*
Y1185531D03*
X1206987Y1174310D03*
Y1189271D03*
X1214468Y1181791D03*
Y1174310D03*
X1208858Y1194881D03*
X1221948Y1193011D03*
X1212598Y1202362D03*
X1220078Y1198621D03*
Y1221062D03*
X1216338D03*
X1220078Y1213582D03*
X1212598Y1209842D03*
X1208858Y1221062D03*
Y1217322D03*
X1216338Y1224803D03*
Y1228543D03*
X1212598Y1232283D03*
Y1236023D03*
X1220078Y1232283D03*
Y1236023D03*
X1208858Y1224803D03*
Y1228543D03*
X1212598Y1239763D03*
X1216338Y1258465D03*
X1208858D03*
X1227559Y1075196D03*
X1235039D03*
X1231298Y1071455D03*
X1223818D03*
X1235039Y1078936D03*
X1227559D03*
X1227557Y1090157D03*
X1227558Y1093897D03*
X1223818Y1105117D03*
X1227558Y1108858D03*
X1233169Y1140649D03*
Y1155610D03*
Y1148129D03*
X1236909Y1170570D03*
X1225688Y1166830D03*
X1233169Y1170570D03*
X1236909Y1178051D03*
Y1185531D03*
X1233169D03*
Y1178051D03*
X1225688Y1174310D03*
Y1181791D03*
Y1189271D03*
X1233169Y1193011D03*
X1223818Y1194881D03*
X1236909Y1193011D03*
X1223818Y1202362D03*
Y1198621D03*
X1235039Y1202362D03*
X1223818Y1206102D03*
Y1221062D03*
Y1217322D03*
Y1213582D03*
Y1209842D03*
X1227558Y1221062D03*
X1235039Y1209842D03*
X1223818Y1224803D03*
Y1228543D03*
X1231298Y1224803D03*
Y1228543D03*
X1227558Y1236023D03*
Y1232283D03*
X1235039D03*
X1225688Y1222932D03*
X1223818Y1239763D03*
X1231298Y1258465D03*
X1223818D03*
X1235966Y1348187D03*
X1228086D03*
X1235966Y1360099D03*
X1228086D03*
X1235966Y1372385D03*
Y1384297D03*
X1228086Y1372385D03*
Y1384297D03*
X1238779Y1078936D03*
X1242520Y1090158D03*
Y1082677D03*
Y1101378D03*
Y1123819D03*
Y1116339D03*
Y1108859D03*
Y1131300D03*
X1240589Y1193011D03*
X1238779Y1202362D03*
X1242520Y1198621D03*
Y1221062D03*
Y1213582D03*
Y1206102D03*
Y1228543D03*
X1238779Y1250984D03*
X1242520Y1247243D03*
Y1239762D03*
X1252566Y1348187D03*
X1240326D03*
X1248206D03*
X1252566Y1360099D03*
X1240326D03*
X1248206D03*
X1252566Y1372385D03*
Y1384297D03*
X1240326D03*
Y1372385D03*
X1248206D03*
Y1384297D03*
X1252566Y1396583D03*
X1240326D03*
X1248206D03*
X1252566Y1408495D03*
X1240326D03*
X1248206D03*
X1264806Y1348187D03*
X1260446D03*
X1264806Y1360099D03*
X1260446D03*
X1264806Y1372385D03*
Y1384297D03*
X1260446Y1372385D03*
Y1384297D03*
X1264806Y1396583D03*
X1260446D03*
X1264806Y1408495D03*
X1260446D03*
X1284926Y1348187D03*
X1277046D03*
X1272686D03*
X1284926Y1360099D03*
X1277046D03*
X1272686D03*
X1284926Y1372385D03*
Y1384297D03*
X1277046Y1372385D03*
Y1384297D03*
X1272686D03*
Y1372385D03*
X1284926Y1396583D03*
X1277046D03*
X1272686D03*
X1284926Y1408495D03*
X1277046D03*
X1272686D03*
X1301526Y1348187D03*
X1289286D03*
X1297166D03*
X1301526Y1360099D03*
X1289286D03*
X1297166D03*
X1301526Y1372385D03*
Y1384297D03*
X1289286D03*
Y1372385D03*
X1297166Y1384297D03*
Y1372385D03*
X1301526Y1396583D03*
X1289286D03*
X1297166D03*
X1301526Y1408495D03*
X1289286D03*
X1297166D03*
X1313766Y1348187D03*
X1309406D03*
X1313766Y1360099D03*
X1309406D03*
X1313766Y1372385D03*
Y1384297D03*
X1309406Y1372385D03*
Y1384297D03*
X1313766Y1396583D03*
X1309406D03*
X1313766Y1408495D03*
X1309406D03*
X1333886Y1348187D03*
X1326006D03*
X1321646D03*
X1333886Y1360099D03*
X1326006D03*
X1321646D03*
X1333886Y1372385D03*
Y1384297D03*
X1326006Y1372385D03*
Y1384297D03*
X1321646D03*
Y1372385D03*
X1333886Y1396583D03*
X1326006D03*
X1321646D03*
X1333886Y1408495D03*
X1326006D03*
X1321646D03*
X1350486Y1348187D03*
X1338246D03*
X1346126D03*
X1350486Y1360099D03*
X1338246D03*
X1346126D03*
X1350486Y1372385D03*
Y1384297D03*
X1338246D03*
Y1372385D03*
X1346126Y1384297D03*
Y1372385D03*
X1350486Y1396583D03*
X1338246D03*
X1346126D03*
X1350486Y1408495D03*
X1338246D03*
X1346126D03*
X1358366Y1348187D03*
Y1360099D03*
Y1372385D03*
Y1384297D03*
Y1396583D03*
Y1408495D03*
X1459130Y1348187D03*
Y1360099D03*
Y1384297D03*
Y1372385D03*
X1479250Y1348187D03*
X1471370D03*
X1467010D03*
X1479250Y1360099D03*
X1471370D03*
X1467010D03*
X1479250Y1384297D03*
Y1372385D03*
X1471370D03*
Y1384297D03*
X1467010D03*
Y1372385D03*
X1479250Y1396583D03*
X1471370D03*
X1479250Y1408495D03*
X1471370D03*
X1495850Y1348187D03*
X1483610D03*
X1491490D03*
X1495850Y1360099D03*
X1483610D03*
X1491490D03*
X1483610Y1384297D03*
Y1372385D03*
X1491490Y1384297D03*
Y1372385D03*
X1495850Y1384297D03*
Y1372385D03*
Y1396583D03*
X1483610D03*
X1491490D03*
X1495850Y1408495D03*
X1483610D03*
X1491490D03*
X1514468Y1103247D03*
Y1125688D03*
Y1133169D03*
Y1140649D03*
Y1144389D03*
Y1151870D03*
Y1159350D03*
X1512597Y1198622D03*
Y1191142D03*
Y1221063D03*
Y1213583D03*
Y1206103D03*
X1508090Y1348187D03*
X1503730D03*
X1508090Y1360099D03*
X1503730D03*
X1508090Y1384297D03*
Y1372385D03*
X1503730D03*
Y1384297D03*
X1508090Y1396583D03*
X1503730D03*
X1508090Y1408495D03*
X1503730D03*
X1521948Y1077066D03*
X1518208Y1080806D03*
Y1103247D03*
X1529429Y1106988D03*
Y1118208D03*
Y1121948D03*
X1525689D03*
X1521949D03*
X1529429Y1125688D03*
X1518208D03*
X1525689Y1129429D03*
X1521949D03*
X1518208Y1133169D03*
X1521949Y1136909D03*
X1529429Y1140649D03*
X1525689D03*
X1521949D03*
X1518208D03*
X1521949Y1144389D03*
X1518208D03*
X1521949Y1148129D03*
Y1151870D03*
X1518208D03*
X1529429Y1155610D03*
X1525689D03*
X1521949D03*
Y1159350D03*
X1518208D03*
X1529429Y1166830D03*
X1521948D03*
X1525689Y1170570D03*
X1521948D03*
Y1174310D03*
X1518207D03*
X1521948Y1178051D03*
X1525689Y1174310D03*
X1529429D03*
X1527559Y1179921D03*
X1523819D03*
X1518207Y1181791D03*
X1516338Y1187401D03*
X1520078D03*
X1527559Y1183661D03*
X1523819D03*
X1520078D03*
X1516338D03*
Y1194881D03*
Y1202362D03*
X1527559Y1191141D03*
X1523819D03*
X1527559Y1198621D03*
X1523819D03*
X1520078Y1194881D03*
Y1202362D03*
X1516338Y1209842D03*
Y1217322D03*
X1523819Y1206102D03*
X1527559D03*
Y1213582D03*
X1523819D03*
X1520078Y1209842D03*
Y1217322D03*
X1523819Y1221062D03*
X1527559D03*
X1516338Y1232283D03*
Y1236023D03*
Y1224803D03*
X1527559Y1236023D03*
Y1232283D03*
X1523819Y1228543D03*
Y1224803D03*
X1520078Y1236023D03*
Y1232283D03*
Y1224803D03*
X1523819Y1239763D03*
Y1243503D03*
Y1258465D03*
X1528210Y1348187D03*
X1520330D03*
X1515970D03*
X1528210Y1360099D03*
X1520330D03*
X1515970D03*
X1528210Y1372385D03*
Y1384297D03*
X1520330Y1372385D03*
Y1384297D03*
X1515970D03*
Y1372385D03*
X1528210Y1396583D03*
X1520330D03*
X1515970D03*
X1528210Y1408495D03*
X1520330D03*
X1515970D03*
X1546258Y1071455D03*
X1540649Y1092027D03*
X1546259Y1090157D03*
X1544389Y1099507D03*
X1540649Y1106988D03*
X1536909D03*
X1533169D03*
X1544389D03*
X1540649Y1095767D03*
X1546259Y1101377D03*
Y1105117D03*
X1544389Y1118208D03*
X1540649D03*
X1544389Y1110728D03*
X1540649D03*
X1536909Y1114468D03*
X1533169D03*
X1544389Y1140649D03*
X1540649D03*
X1536909D03*
X1533169D03*
X1536909Y1129429D03*
X1544389Y1144389D03*
X1540649D03*
X1533169D03*
Y1148129D03*
Y1151870D03*
Y1155610D03*
X1544389Y1148129D03*
Y1155610D03*
Y1151870D03*
X1533169Y1159350D03*
X1544389D03*
Y1166830D03*
Y1170570D03*
X1533169Y1174310D03*
Y1178051D03*
X1544389Y1174310D03*
Y1178051D03*
Y1181791D03*
X1540649D03*
X1538779Y1179921D03*
X1531299D03*
Y1187401D03*
X1546259D03*
X1542519D03*
Y1183661D03*
X1538779D03*
X1535039D03*
X1531299D03*
X1535039Y1191141D03*
X1531299D03*
X1535039Y1198621D03*
X1531299D03*
X1538779Y1191141D03*
X1542519Y1194881D03*
X1546259D03*
X1542519Y1202362D03*
X1546259D03*
X1531299Y1206102D03*
X1535039D03*
X1538779D03*
X1542519Y1209842D03*
X1531299Y1221062D03*
X1535039D03*
X1546259Y1217322D03*
Y1221062D03*
X1542519D03*
Y1217322D03*
X1531299Y1224803D03*
X1535039Y1232283D03*
Y1236023D03*
X1542519Y1232283D03*
Y1236023D03*
X1538779Y1224803D03*
X1546259D03*
X1535039Y1239763D03*
X1531299D03*
Y1243503D03*
X1538779Y1239763D03*
Y1243503D03*
X1542519Y1250984D03*
Y1239763D03*
X1546259D03*
Y1247243D03*
X1546260Y1258465D03*
X1538779D03*
X1531299D03*
X1544810Y1348187D03*
X1532570D03*
X1540450D03*
X1544810Y1360099D03*
X1532570D03*
X1540450D03*
X1544810Y1384297D03*
Y1372385D03*
X1532570Y1384297D03*
Y1372385D03*
X1540450Y1384297D03*
Y1372385D03*
X1544810Y1396583D03*
X1532570D03*
X1540450D03*
X1544810Y1408495D03*
X1532570D03*
X1540450D03*
X1561219Y1071455D03*
X1553739D03*
X1561220Y1090157D03*
X1557480D03*
X1553740D03*
X1550000D03*
X1561220Y1105117D03*
X1553740D03*
X1561220Y1101377D03*
X1557480Y1097637D03*
Y1093897D03*
X1553740Y1101377D03*
X1550000Y1093897D03*
Y1097637D03*
X1551870Y1114468D03*
X1548130D03*
X1563090Y1118208D03*
X1559350D03*
X1555610D03*
X1551870D03*
X1548130D03*
X1563090Y1121948D03*
X1559350D03*
X1555610D03*
X1551870D03*
X1548130D03*
Y1110728D03*
X1561220Y1108858D03*
X1557480D03*
X1553740D03*
X1550000D03*
X1551870Y1110728D03*
X1548130Y1140649D03*
X1563090Y1125688D03*
X1559350D03*
X1555610D03*
X1551870D03*
X1548130D03*
X1559350Y1129429D03*
X1555610D03*
X1551870D03*
X1548130D03*
X1559350Y1133169D03*
X1555610D03*
X1551870D03*
X1548130D03*
X1559350Y1136909D03*
X1551870D03*
X1548130D03*
X1559350Y1140649D03*
X1555610D03*
X1551870D03*
Y1155610D03*
Y1151870D03*
X1559350Y1144389D03*
X1551870D03*
Y1148129D03*
X1559350Y1151870D03*
X1563090Y1155610D03*
Y1148129D03*
X1559350Y1170570D03*
X1551870Y1166830D03*
X1559350Y1159350D03*
X1551870D03*
X1548130Y1170570D03*
X1563090Y1166830D03*
X1551870Y1189271D03*
X1559350Y1185531D03*
X1551870D03*
Y1178051D03*
Y1174310D03*
Y1181791D03*
X1563090D03*
Y1174310D03*
X1550000Y1187401D03*
X1548130Y1185531D03*
X1551870Y1193011D03*
X1559350Y1196751D03*
Y1200491D03*
X1555610D03*
Y1204232D03*
X1559350D03*
X1563090D03*
Y1196751D03*
Y1200491D03*
X1555610Y1193011D03*
Y1196751D03*
X1550000Y1191141D03*
Y1194881D03*
Y1198621D03*
Y1202362D03*
X1555610Y1211712D03*
X1559350D03*
X1563090D03*
Y1207972D03*
X1559350D03*
X1555610D03*
X1563090Y1219192D03*
X1550000Y1221062D03*
X1553740D03*
X1557480D03*
X1561220D03*
X1550000Y1206102D03*
Y1209842D03*
Y1213582D03*
Y1217322D03*
X1553740D03*
X1550000Y1232283D03*
Y1236023D03*
X1561220Y1224803D03*
X1557480Y1232283D03*
Y1236023D03*
X1553740Y1224803D03*
X1557480Y1239763D03*
X1561220Y1243503D03*
X1553740D03*
X1561220Y1258465D03*
X1553740D03*
X1557050Y1348187D03*
X1552690D03*
Y1360099D03*
X1557050D03*
Y1384297D03*
Y1372385D03*
X1552690D03*
Y1384297D03*
X1557050Y1396583D03*
X1552690D03*
X1557050Y1408495D03*
X1552690D03*
X1576180Y1071455D03*
X1568699D03*
X1564960Y1090157D03*
X1572441D03*
X1576181D03*
X1568700D03*
X1576181Y1105117D03*
X1568700D03*
X1564960Y1093897D03*
Y1097637D03*
X1572441Y1093897D03*
Y1097637D03*
X1576181Y1101377D03*
X1568700D03*
X1566830Y1121948D03*
X1578051Y1118208D03*
X1574311D03*
Y1121948D03*
X1578051D03*
X1570571Y1118208D03*
X1566830D03*
X1570571Y1121948D03*
X1576181Y1108858D03*
X1572441D03*
X1568700D03*
X1564960D03*
X1566830Y1133169D03*
Y1129429D03*
X1570571Y1140649D03*
X1574311D03*
X1578051D03*
X1570571Y1125688D03*
X1574311D03*
X1578051D03*
X1566830D03*
X1578051Y1133169D03*
X1574311D03*
X1570571D03*
X1566830Y1136909D03*
X1574311Y1148129D03*
X1570571D03*
X1578051D03*
X1570571Y1155610D03*
X1566830Y1151869D03*
X1578051Y1155610D03*
X1566830Y1144389D03*
Y1159350D03*
X1578051Y1166830D03*
X1574311Y1159350D03*
X1570571Y1166830D03*
X1566830Y1170570D03*
X1574311D03*
X1578051Y1181791D03*
X1574311D03*
X1570571D03*
X1578051Y1189271D03*
X1574311D03*
X1570571D03*
X1566830D03*
Y1178051D03*
X1570571Y1174310D03*
X1566830Y1185531D03*
X1578051Y1174310D03*
X1574311Y1204232D03*
X1578051D03*
Y1196751D03*
X1574311D03*
X1570571D03*
X1566830Y1200491D03*
Y1196751D03*
Y1193011D03*
Y1204232D03*
X1570571D03*
X1566830Y1207972D03*
Y1211712D03*
X1578051Y1207972D03*
X1574311D03*
X1570571D03*
X1564960Y1221062D03*
X1568700D03*
X1572441D03*
X1576181D03*
X1564960Y1232283D03*
Y1236023D03*
X1576181Y1224803D03*
X1572441Y1232283D03*
Y1236023D03*
X1568700Y1224803D03*
X1564960Y1239763D03*
X1576181Y1243503D03*
X1568700D03*
Y1239763D03*
X1576181Y1258465D03*
X1568701D03*
X1564930Y1348187D03*
X1569290D03*
X1577170D03*
X1569290Y1360099D03*
X1577170D03*
X1564930D03*
X1577170Y1372385D03*
Y1384297D03*
X1569290Y1372385D03*
Y1384297D03*
X1564930D03*
Y1372385D03*
X1577170Y1396583D03*
X1569290D03*
X1564930D03*
X1577170Y1408495D03*
X1569290D03*
X1564930D03*
X1591140Y1071455D03*
X1583660D03*
X1579921Y1090157D03*
X1583661D03*
X1587401D03*
X1591141D03*
X1594882D03*
X1583661Y1105117D03*
X1591141D03*
X1579921Y1093897D03*
Y1097637D03*
X1583661Y1101377D03*
X1587401Y1097637D03*
Y1093897D03*
X1594882D03*
Y1097637D03*
X1591141Y1101377D03*
X1581791Y1121948D03*
X1585531Y1118208D03*
X1589271D03*
X1593011D03*
X1589271Y1121948D03*
X1593011D03*
X1585531D03*
X1581791Y1118208D03*
X1594882Y1108858D03*
X1591141D03*
X1587401D03*
X1583661D03*
X1579921D03*
X1587401Y1112598D03*
X1581791Y1133169D03*
Y1140649D03*
X1585531D03*
X1589271D03*
X1593011D03*
X1589271Y1125688D03*
X1585531D03*
X1581791D03*
X1593011D03*
Y1133169D03*
X1589271D03*
X1585531D03*
X1593011Y1148129D03*
X1589271D03*
X1585531D03*
X1581791D03*
X1593011Y1155610D03*
X1585531D03*
X1589271Y1170570D03*
X1593012Y1166830D03*
X1585531D03*
X1581791Y1159350D03*
X1589271D03*
X1581791Y1170570D03*
X1593011Y1181791D03*
X1589271D03*
X1585531D03*
X1581791D03*
X1593011Y1189271D03*
X1589271D03*
X1585531D03*
X1581791D03*
X1585531Y1174310D03*
X1593011D03*
Y1204232D03*
Y1196751D03*
X1589271D03*
X1585531D03*
X1581791D03*
Y1204232D03*
X1585531D03*
X1589271D03*
X1593011Y1219192D03*
X1591141Y1217322D03*
X1593011Y1207972D03*
X1589271D03*
X1585531D03*
X1581791D03*
X1591141Y1221062D03*
X1587401D03*
X1579921D03*
X1583661D03*
X1594882D03*
X1583661Y1224803D03*
X1579921Y1232283D03*
Y1236023D03*
X1594882Y1232283D03*
Y1236023D03*
X1591141Y1224803D03*
X1587401Y1232283D03*
Y1236023D03*
X1583661Y1243503D03*
X1579921Y1239763D03*
X1591141Y1243503D03*
X1594882Y1239763D03*
X1587401D03*
X1591142Y1258465D03*
X1583661D03*
X1589410Y1348187D03*
X1581530D03*
X1589410Y1360099D03*
X1581530D03*
Y1384297D03*
Y1372385D03*
X1589410Y1384297D03*
Y1372385D03*
X1581530Y1396583D03*
X1589410D03*
X1581530Y1408495D03*
X1589410D03*
X1609842Y1075196D03*
X1606101Y1071454D03*
X1598621Y1071455D03*
X1598622Y1090157D03*
X1606102Y1082677D03*
Y1086417D03*
X1609842Y1090157D03*
X1606102D03*
X1602362D03*
X1598622Y1105117D03*
X1606102D03*
X1598622Y1101377D03*
X1606102D03*
X1609842Y1093897D03*
X1602362D03*
Y1097637D03*
X1596752Y1121948D03*
X1600492Y1118208D03*
Y1114468D03*
X1611712Y1121948D03*
X1607972D03*
X1596752Y1118208D03*
X1600492Y1121948D03*
X1609842Y1108858D03*
X1606102D03*
X1602362D03*
X1598622D03*
X1607972Y1125688D03*
X1611712D03*
X1607972Y1133464D03*
X1611712Y1133169D03*
X1600590Y1132677D03*
X1596752Y1133169D03*
Y1140649D03*
X1600492D03*
Y1125688D03*
X1596752D03*
X1607972Y1140649D03*
X1611712D03*
X1600492Y1148129D03*
X1596752D03*
X1607972D03*
X1611712D03*
X1600492Y1155610D03*
X1611712D03*
X1596752Y1170570D03*
Y1159350D03*
X1611712Y1166830D03*
X1607972Y1170570D03*
X1600492Y1166830D03*
X1607972Y1159350D03*
X1600492Y1181791D03*
X1611712D03*
X1607972D03*
Y1189271D03*
X1611712D03*
X1596752Y1181791D03*
X1600492Y1189271D03*
X1596752D03*
X1600492Y1174310D03*
X1611712D03*
Y1204232D03*
X1607972D03*
Y1196751D03*
X1611712D03*
X1600492D03*
X1596752D03*
Y1204232D03*
X1600492D03*
X1606102Y1221062D03*
X1596752Y1207972D03*
X1607972D03*
X1611712D03*
Y1211712D03*
X1596752Y1219192D03*
X1600492Y1207972D03*
X1598622Y1221062D03*
X1609842D03*
X1602362D03*
X1598622Y1224803D03*
X1609842Y1232283D03*
Y1236023D03*
X1606102Y1228543D03*
Y1224803D03*
X1602362Y1232283D03*
Y1236023D03*
X1598622Y1243503D03*
X1609842Y1239763D03*
X1602362D03*
X1606102Y1258465D03*
X1598623D03*
X1609158Y1348187D03*
Y1360099D03*
Y1384297D03*
Y1372385D03*
X1624803Y1075196D03*
X1617322D03*
X1621062Y1071455D03*
X1613581D03*
X1617322Y1090157D03*
Y1078936D03*
X1613582Y1090157D03*
Y1086417D03*
X1624803Y1078936D03*
X1621063Y1086417D03*
Y1090157D03*
X1624803D03*
X1617322Y1093897D03*
Y1097637D03*
X1624803Y1093897D03*
Y1097637D03*
X1621063Y1105117D03*
X1613582D03*
Y1101377D03*
X1626673Y1121948D03*
X1622933D03*
X1619193D03*
X1615452D03*
X1624803Y1108858D03*
X1621063D03*
X1617322D03*
X1613582D03*
X1615452Y1133169D03*
X1619193D03*
X1622933D03*
X1626673D03*
X1615452Y1140649D03*
X1619193D03*
X1622933D03*
X1626673D03*
X1615452Y1125688D03*
X1619193D03*
X1622933D03*
X1626673D03*
X1615452Y1148129D03*
X1619193D03*
X1622933D03*
X1626673D03*
X1619193Y1155610D03*
X1626673D03*
X1615452Y1170570D03*
X1622933D03*
X1626673Y1166830D03*
X1615452Y1159350D03*
X1619193Y1166830D03*
X1622933Y1159350D03*
X1615452Y1181791D03*
X1619193D03*
X1622933D03*
X1626673D03*
X1615452Y1189271D03*
X1619193D03*
X1622933D03*
X1626673D03*
Y1174310D03*
X1619193D03*
Y1204232D03*
X1615452D03*
X1626673D03*
X1622933D03*
X1615452Y1196751D03*
X1619193D03*
X1622933D03*
X1626673D03*
X1617322Y1221062D03*
X1619193Y1207972D03*
X1622933D03*
X1626673Y1211712D03*
Y1207972D03*
X1615452Y1211712D03*
Y1207972D03*
X1621063Y1221062D03*
X1613582D03*
X1624803D03*
X1613582Y1228543D03*
Y1224803D03*
X1621063Y1228543D03*
Y1224803D03*
X1624803Y1232283D03*
Y1236023D03*
X1617322Y1232283D03*
Y1236023D03*
Y1239763D03*
X1621063Y1258465D03*
X1613582D03*
X1617038Y1348187D03*
X1621398D03*
X1617038Y1360099D03*
X1621398D03*
X1617038Y1384297D03*
Y1372385D03*
X1621398D03*
Y1384297D03*
Y1396583D03*
Y1408495D03*
X1639763Y1075196D03*
X1632283D03*
X1643503Y1071455D03*
X1636022D03*
X1628542D03*
X1636023Y1090157D03*
X1643504Y1082677D03*
X1636023Y1086417D03*
X1643504Y1090157D03*
Y1086417D03*
X1639763Y1090157D03*
Y1078936D03*
X1632283D03*
X1628543Y1086417D03*
Y1090157D03*
X1632283D03*
Y1093897D03*
Y1097637D03*
X1639763Y1093897D03*
Y1097637D03*
X1628543Y1105117D03*
X1636023D03*
X1643504D03*
X1641633Y1118208D03*
X1637893Y1121948D03*
X1634153D03*
X1630413D03*
X1641633D03*
X1643504Y1108858D03*
X1639763D03*
X1636023D03*
X1632283D03*
X1628543D03*
X1641633Y1136909D03*
X1630413Y1133169D03*
X1634153D03*
X1637893D03*
X1641633D03*
X1634153Y1140649D03*
X1637893D03*
X1641633Y1125688D03*
Y1129429D03*
X1630413Y1125688D03*
X1634153D03*
X1637893D03*
X1641633Y1140649D03*
X1630413D03*
Y1148129D03*
X1634153D03*
X1637893D03*
X1641633Y1144389D03*
Y1148129D03*
Y1151869D03*
X1634153Y1155610D03*
X1641633D03*
X1634153Y1166830D03*
X1630413Y1159350D03*
Y1170570D03*
X1634153Y1189271D03*
X1637893D03*
X1641633Y1178051D03*
X1634153Y1174310D03*
X1641633Y1185531D03*
X1630413Y1181791D03*
X1634153D03*
X1637893D03*
X1641633Y1189271D03*
X1630413D03*
X1641633Y1174310D03*
X1641653Y1196732D03*
X1641633Y1204232D03*
X1630413D03*
X1634153D03*
X1637893D03*
X1641633Y1200491D03*
X1630413Y1196751D03*
X1634153D03*
X1637893D03*
X1641633Y1193011D03*
Y1211712D03*
X1634153Y1207972D03*
X1630413D03*
X1634153Y1211712D03*
X1637893Y1207972D03*
Y1211712D03*
X1630413D03*
X1641633Y1207972D03*
X1628543Y1221062D03*
X1632283D03*
X1636023D03*
X1639763D03*
X1643504D03*
X1628543Y1228543D03*
Y1224803D03*
X1632283Y1232283D03*
Y1236023D03*
X1636023Y1228543D03*
Y1224803D03*
X1639763Y1232283D03*
Y1236023D03*
X1643504Y1228543D03*
Y1224803D03*
X1628543Y1239763D03*
X1639763D03*
X1643504Y1258465D03*
X1636023D03*
X1628543D03*
X1629278Y1348187D03*
X1641518D03*
X1633638D03*
X1629278Y1360099D03*
X1641518D03*
X1633638D03*
X1629278Y1384297D03*
Y1372385D03*
X1641518Y1384297D03*
Y1372385D03*
X1633638Y1384297D03*
Y1372385D03*
X1629278Y1396583D03*
X1641518D03*
X1633638D03*
Y1408495D03*
X1629278D03*
X1641518D03*
X1647244Y1075196D03*
X1654724D03*
X1658463Y1071455D03*
X1650983D03*
X1654724Y1078936D03*
Y1090157D03*
X1658464D03*
X1650984D03*
X1647244D03*
Y1093897D03*
X1658464Y1101377D03*
Y1105117D03*
X1650984D03*
X1645374Y1118208D03*
X1649114D03*
X1658464Y1108858D03*
X1654724D03*
X1650984D03*
X1647244D03*
X1649114Y1140649D03*
X1652854Y1136909D03*
X1645374Y1125688D03*
X1649114Y1136909D03*
X1652854Y1140649D03*
X1645374Y1155610D03*
Y1151869D03*
Y1148129D03*
X1652854D03*
X1649114Y1144389D03*
X1652854Y1155610D03*
X1649114Y1148129D03*
X1652854Y1151869D03*
X1656594D03*
X1660334D03*
Y1155610D03*
X1649114Y1151870D03*
X1645374Y1166830D03*
X1652854Y1159350D03*
X1660334Y1166830D03*
Y1170570D03*
X1645374Y1159350D03*
X1660334D03*
X1645374Y1170570D03*
X1652854D03*
Y1166830D03*
Y1185531D03*
X1656594Y1181791D03*
X1652854Y1178051D03*
Y1174310D03*
X1649114Y1181791D03*
X1656594Y1185531D03*
X1660334Y1174310D03*
Y1178051D03*
Y1185531D03*
X1645374Y1181791D03*
Y1174310D03*
X1649114Y1178051D03*
Y1189271D03*
X1652854D03*
X1649114Y1185531D03*
X1656594Y1193011D03*
X1652854Y1204232D03*
Y1196751D03*
Y1193011D03*
X1649114D03*
X1645374Y1196751D03*
X1649114Y1211712D03*
X1645374Y1207972D03*
X1660334Y1215452D03*
Y1211712D03*
X1654724Y1221062D03*
X1658464D03*
X1650984D03*
X1647244D03*
Y1232283D03*
Y1236023D03*
X1654724Y1232283D03*
X1658464Y1228543D03*
X1654724Y1236023D03*
X1658464Y1224803D03*
X1650984Y1228543D03*
Y1224803D03*
X1654724Y1239763D03*
X1658464Y1258465D03*
X1650984D03*
X1645878Y1348187D03*
X1653758D03*
X1658118D03*
X1645878Y1360099D03*
X1653758D03*
X1658118D03*
X1645878Y1384297D03*
Y1372385D03*
X1653758D03*
Y1384297D03*
X1658118D03*
Y1372385D03*
X1645878Y1396583D03*
X1653758D03*
X1658118D03*
X1645878Y1408495D03*
X1653758D03*
X1658118D03*
X1662204Y1075196D03*
X1669685D03*
X1673425Y1071455D03*
X1665944D03*
X1662203Y1090157D03*
X1669686Y1078936D03*
X1669684Y1090157D03*
X1662204Y1093897D03*
X1669685D03*
X1673425Y1105117D03*
X1665945D03*
X1669685Y1108858D03*
X1673425Y1116338D03*
Y1123818D03*
X1665944Y1112598D03*
Y1120078D03*
X1665945Y1108858D03*
X1662204Y1123818D03*
Y1120078D03*
Y1116338D03*
Y1108858D03*
X1671555Y1140649D03*
X1673425Y1131299D03*
X1662204Y1135039D03*
Y1131299D03*
Y1127558D03*
Y1138779D03*
X1664074Y1151869D03*
X1671555Y1148129D03*
X1664074Y1144389D03*
Y1159350D03*
X1671555D03*
X1664074Y1166830D03*
X1671555D03*
X1664074Y1189271D03*
Y1174310D03*
X1671555Y1181791D03*
Y1174310D03*
X1664074Y1181791D03*
X1671555Y1189271D03*
X1665945Y1194881D03*
X1664074Y1204232D03*
X1669685Y1202362D03*
X1673425Y1221062D03*
X1669685Y1209842D03*
X1665945Y1221062D03*
Y1217322D03*
X1662204Y1221062D03*
Y1232283D03*
Y1236023D03*
X1673425Y1224803D03*
Y1228543D03*
X1669685Y1232283D03*
Y1236023D03*
X1665945Y1224803D03*
Y1228543D03*
X1662204Y1239763D03*
X1669685D03*
X1673425Y1258465D03*
X1665945D03*
X1665998Y1348187D03*
X1670358D03*
X1665998Y1360099D03*
X1670358D03*
X1665998Y1384297D03*
Y1372385D03*
X1670358D03*
Y1384297D03*
X1665998Y1396583D03*
X1670358D03*
X1665998Y1408495D03*
X1670358D03*
X1677166Y1075196D03*
X1684646D03*
X1692126D03*
X1688385Y1071455D03*
X1680905D03*
X1677166Y1078936D03*
X1692126D03*
X1684646D03*
X1684644Y1090157D03*
X1677165Y1093897D03*
X1684645D03*
X1680905Y1105117D03*
X1677164Y1108857D03*
X1684645Y1108858D03*
X1690256Y1140649D03*
Y1155610D03*
Y1148129D03*
X1682775Y1166830D03*
X1679035Y1170570D03*
X1690256D03*
Y1178051D03*
X1682775Y1174310D03*
X1679035Y1178051D03*
X1682775Y1181791D03*
X1679035Y1185531D03*
X1682775Y1189271D03*
X1690256Y1185531D03*
X1680905Y1194881D03*
X1690256Y1193011D03*
X1679035D03*
X1692126Y1202362D03*
X1680905D03*
Y1198621D03*
X1677165D03*
X1684645Y1221062D03*
X1692126Y1209842D03*
X1680905Y1221062D03*
Y1217322D03*
X1677165Y1221062D03*
Y1213582D03*
X1680905D03*
Y1209842D03*
Y1206102D03*
X1688385Y1224803D03*
Y1228543D03*
X1684645Y1236023D03*
Y1232283D03*
X1692126D03*
X1680905Y1224803D03*
Y1228543D03*
X1677165Y1232283D03*
Y1236023D03*
X1680905Y1239763D03*
X1688385Y1258465D03*
X1680905D03*
X1678238Y1348187D03*
X1690478D03*
X1682598D03*
X1678238Y1360099D03*
X1690478D03*
X1682598D03*
X1678238Y1372385D03*
Y1384297D03*
X1690478D03*
Y1372385D03*
X1682598Y1384297D03*
Y1372385D03*
X1678238Y1396583D03*
X1690478D03*
X1682598D03*
X1678238Y1408495D03*
X1690478D03*
X1682598D03*
X1695866Y1078936D03*
X1699607Y1090158D03*
Y1082677D03*
Y1101378D03*
Y1123819D03*
Y1116339D03*
Y1108859D03*
Y1131300D03*
X1693996Y1170570D03*
Y1178051D03*
Y1185531D03*
Y1193011D03*
X1697676D03*
X1695866Y1202362D03*
X1699607Y1198621D03*
Y1221062D03*
Y1213582D03*
Y1206102D03*
Y1228543D03*
X1695866Y1250984D03*
X1699607Y1247243D03*
Y1239762D03*
X1694838Y1348187D03*
X1702718D03*
X1707078D03*
X1702718Y1360099D03*
X1707078D03*
X1694838D03*
Y1384297D03*
Y1372385D03*
X1702718D03*
Y1384297D03*
X1707078D03*
Y1372385D03*
X1694838Y1396583D03*
X1702718D03*
X1707078D03*
X1694838Y1408495D03*
X1702718D03*
X1707078D03*
X1714958Y1348187D03*
X1719318D03*
X1714958Y1360099D03*
X1719318D03*
X1714958Y1384297D03*
Y1372385D03*
X1719318D03*
Y1384297D03*
X1714958Y1396583D03*
X1719318D03*
X1714958Y1408495D03*
X1719318D03*
X1727198Y1348187D03*
X1739438D03*
X1731558D03*
X1727198Y1360099D03*
X1739438D03*
X1731558D03*
X1739438Y1372385D03*
X1731558Y1384297D03*
Y1372385D03*
X1727198D03*
Y1384297D03*
X1739438D03*
X1727198Y1396583D03*
X1739438D03*
X1731558D03*
X1727198Y1408495D03*
X1739438D03*
X1731558D03*
G54D52*
X956448Y-30304D03*
Y-33204D03*
X953192Y-25085D03*
X956445Y-25099D03*
X950167Y-26405D03*
X953207Y-27600D03*
X956460Y-27614D03*
X978036Y-64265D03*
X975011Y-65585D03*
X978051Y-66780D03*
X981289Y-64279D03*
X981292Y-69484D03*
Y-72384D03*
X981304Y-66794D03*
X1231351Y-77080D03*
X1234592Y-79984D03*
X1234604Y-77094D03*
X1234592Y-82584D03*
Y-71970D03*
X1231336Y-74565D03*
X1234589Y-74579D03*
X1231336Y-64265D03*
X1234589D03*
X1234592Y-69470D03*
X1231351Y-66780D03*
X1234604D03*
X1228311Y-65585D03*
Y-75885D03*
X1236692Y-35515D03*
X1236707Y-38030D03*
X1233667Y-36835D03*
X1236692Y-25215D03*
X1236707Y-27730D03*
X1233667Y-26535D03*
X1239948Y-32920D03*
X1239945Y-35529D03*
X1239948Y-30420D03*
Y-40934D03*
X1239960Y-38044D03*
X1239948Y-43534D03*
X1239945Y-25215D03*
X1239960Y-27730D03*
X1487851Y-77080D03*
X1491092Y-79984D03*
X1491104Y-77094D03*
X1491092Y-82584D03*
Y-71970D03*
X1487836Y-74565D03*
X1491089Y-74579D03*
X1487836Y-64265D03*
X1491089D03*
X1491092Y-69470D03*
X1487851Y-66780D03*
X1491104D03*
X1484811Y-65585D03*
Y-75885D03*
X1526448Y-33050D03*
X1523192Y-35645D03*
X1526445Y-35659D03*
X1526448Y-30550D03*
X1523207Y-38160D03*
X1526448Y-41064D03*
X1526460Y-38174D03*
X1526448Y-43664D03*
X1520167Y-36965D03*
X1523192Y-25345D03*
X1526445D03*
X1523207Y-27860D03*
X1526460D03*
X1520167Y-26665D03*
X1742336Y-74565D03*
Y-64265D03*
X1739311Y-65585D03*
Y-75885D03*
X1742351Y-77080D03*
X1745592Y-79984D03*
X1745604Y-77094D03*
X1745592Y-82584D03*
Y-71970D03*
X1745589Y-74579D03*
Y-64265D03*
X1745592Y-69470D03*
X1742351Y-66780D03*
X1745604D03*
X1804667Y-37095D03*
Y-26795D03*
X1810948Y-33180D03*
X1807692Y-35775D03*
X1810945Y-35789D03*
X1810948Y-30680D03*
X1807707Y-38290D03*
X1810948Y-41194D03*
X1810960Y-38304D03*
X1810948Y-43794D03*
X1807692Y-25475D03*
X1810945D03*
X1807707Y-27990D03*
X1810960D03*
G54D24*
X46348Y1727941D03*
Y1737941D03*
Y1773941D03*
Y1783941D03*
X333112Y1751624D03*
Y1761624D03*
X333212Y1797624D03*
Y1807624D03*
X619861Y1751765D03*
Y1761765D03*
X619475Y1798845D03*
Y1808845D03*
X907163Y1752566D03*
Y1762566D03*
X907166Y1800435D03*
Y1810435D03*
G54D40*
X266841Y421555D03*
Y550020D03*
X295856Y421555D03*
Y550020D03*
X723927Y421555D03*
Y550020D03*
X752942Y421555D03*
Y550020D03*
X1181014Y421555D03*
Y550020D03*
X1210029Y421555D03*
Y550020D03*
X1638101Y421555D03*
Y550020D03*
X1667116Y421555D03*
Y550020D03*
G54D56*
X1236871Y1715189D03*
X1236864Y1773377D03*
X1235371Y1802909D03*
G54D57*
X1236871Y1744208D03*
%LPC*%
G75*
G54D64*
G01X-20602Y-468335D02*
Y-543335D01*
X479398D01*
Y-468335D01*
X-20602D01*
G01X-8602Y-533335D02*
Y-538335D01*
G01X-10059Y-533335D02*
X-7145D01*
G01X-2235Y-538335D02*
X-4769D01*
Y-533335D01*
X-2235D01*
G01X-3249Y-535752D02*
X-4769D01*
G01X331Y-533335D02*
Y-538335D01*
X2865D01*
G01X6698Y-538502D02*
X6571Y-538418D01*
Y-538252D01*
X6698Y-538168D01*
X6825Y-538252D01*
Y-538418D01*
X6698Y-538502D01*
G01Y-536252D02*
X6571Y-536168D01*
Y-536002D01*
X6698Y-535918D01*
X6825Y-536002D01*
Y-536168D01*
X6698Y-536252D01*
G01X11481Y-540002D02*
X10848Y-539168D01*
X10531Y-538335D01*
Y-535002D01*
X10848Y-534168D01*
X11481Y-533335D01*
G01X16898D02*
X16391Y-533502D01*
X16011Y-533918D01*
X15758Y-534418D01*
X15568Y-535085D01*
X15505Y-535835D01*
X15568Y-536585D01*
X15758Y-537252D01*
X16011Y-537752D01*
X16391Y-538168D01*
X16898Y-538335D01*
X17405Y-538168D01*
X17785Y-537752D01*
X18038Y-537252D01*
X18228Y-536585D01*
X18291Y-535835D01*
X18228Y-535085D01*
X18038Y-534418D01*
X17785Y-533918D01*
X17405Y-533502D01*
X16898Y-533335D01*
G01X20605Y-537335D02*
X20985Y-537918D01*
X21491Y-538252D01*
X22061Y-538335D01*
X22568Y-538252D01*
X23075Y-537835D01*
X23391Y-537335D01*
X23455Y-536835D01*
X23328Y-536252D01*
X22885Y-535835D01*
X22441Y-535668D01*
X21871D01*
G01X22441D02*
X22821Y-535418D01*
X23138Y-535002D01*
X23265Y-534502D01*
X23138Y-534002D01*
X22821Y-533585D01*
X22251Y-533335D01*
X21681Y-533418D01*
X21111Y-533752D01*
G01X27415Y-540002D02*
X28048Y-539168D01*
X28365Y-538335D01*
Y-535002D01*
X28048Y-534168D01*
X27415Y-533335D01*
G01X30805Y-537335D02*
X31185Y-537918D01*
X31691Y-538252D01*
X32261Y-538335D01*
X32768Y-538252D01*
X33275Y-537835D01*
X33591Y-537335D01*
X33655Y-536835D01*
X33528Y-536252D01*
X33085Y-535835D01*
X32641Y-535668D01*
X32071D01*
G01X32641D02*
X33021Y-535418D01*
X33338Y-535002D01*
X33465Y-534502D01*
X33338Y-534002D01*
X33021Y-533585D01*
X32451Y-533335D01*
X31881Y-533418D01*
X31311Y-533752D01*
G01X36095Y-534168D02*
X36475Y-533668D01*
X36918Y-533418D01*
X37425Y-533335D01*
X38058Y-533502D01*
X38501Y-533918D01*
X38628Y-534418D01*
X38565Y-534918D01*
X38311Y-535335D01*
X37045Y-536168D01*
X36475Y-536752D01*
X36095Y-537585D01*
X35968Y-538335D01*
X38628D01*
G01X42271D02*
X42398Y-537252D01*
X42588Y-536335D01*
X42841Y-535502D01*
X43158Y-534585D01*
X43665Y-533335D01*
X41131D01*
G01X46675Y-536668D02*
X48321D01*
G01X51395Y-534168D02*
X51775Y-533668D01*
X52218Y-533418D01*
X52725Y-533335D01*
X53358Y-533502D01*
X53801Y-533918D01*
X53928Y-534418D01*
X53865Y-534918D01*
X53611Y-535335D01*
X52345Y-536168D01*
X51775Y-536752D01*
X51395Y-537585D01*
X51268Y-538335D01*
X53928D01*
G01X56305Y-537335D02*
X56685Y-537918D01*
X57191Y-538252D01*
X57761Y-538335D01*
X58268Y-538252D01*
X58775Y-537835D01*
X59091Y-537335D01*
X59155Y-536835D01*
X59028Y-536252D01*
X58585Y-535835D01*
X58141Y-535668D01*
X57571D01*
G01X58141D02*
X58521Y-535418D01*
X58838Y-535002D01*
X58965Y-534502D01*
X58838Y-534002D01*
X58521Y-533585D01*
X57951Y-533335D01*
X57381Y-533418D01*
X56811Y-533752D01*
G01X63558Y-538335D02*
Y-533335D01*
X61215Y-536918D01*
X64381D01*
G01X66505Y-537585D02*
X66885Y-538002D01*
X67328Y-538252D01*
X67898Y-538335D01*
X68468Y-538168D01*
X68911Y-537835D01*
X69228Y-537252D01*
X69291Y-536585D01*
X69165Y-535918D01*
X68848Y-535502D01*
X68405Y-535168D01*
X67961Y-535085D01*
X67518Y-535168D01*
X66948Y-535502D01*
X67138Y-533335D01*
X68848D01*
G01X76895Y-538335D02*
Y-533335D01*
X79301D01*
G01X78415Y-535752D02*
X76895D01*
G01X81615Y-538335D02*
X83198Y-533335D01*
X84781Y-538335D01*
G01X84211Y-536585D02*
X82185D01*
G01X86968Y-538335D02*
X89628Y-533335D01*
G01X86968D02*
X89628Y-538335D01*
G01X93398Y-538502D02*
X93271Y-538418D01*
Y-538252D01*
X93398Y-538168D01*
X93525Y-538252D01*
Y-538418D01*
X93398Y-538502D01*
G01Y-536252D02*
X93271Y-536168D01*
Y-536002D01*
X93398Y-535918D01*
X93525Y-536002D01*
Y-536168D01*
X93398Y-536252D01*
G01X98181Y-540002D02*
X97548Y-539168D01*
X97231Y-538335D01*
Y-535002D01*
X97548Y-534168D01*
X98181Y-533335D01*
G01X103598D02*
X103091Y-533502D01*
X102711Y-533918D01*
X102458Y-534418D01*
X102268Y-535085D01*
X102205Y-535835D01*
X102268Y-536585D01*
X102458Y-537252D01*
X102711Y-537752D01*
X103091Y-538168D01*
X103598Y-538335D01*
X104105Y-538168D01*
X104485Y-537752D01*
X104738Y-537252D01*
X104928Y-536585D01*
X104991Y-535835D01*
X104928Y-535085D01*
X104738Y-534418D01*
X104485Y-533918D01*
X104105Y-533502D01*
X103598Y-533335D01*
G01X107305Y-537335D02*
X107685Y-537918D01*
X108191Y-538252D01*
X108761Y-538335D01*
X109268Y-538252D01*
X109775Y-537835D01*
X110091Y-537335D01*
X110155Y-536835D01*
X110028Y-536252D01*
X109585Y-535835D01*
X109141Y-535668D01*
X108571D01*
G01X109141D02*
X109521Y-535418D01*
X109838Y-535002D01*
X109965Y-534502D01*
X109838Y-534002D01*
X109521Y-533585D01*
X108951Y-533335D01*
X108381Y-533418D01*
X107811Y-533752D01*
G01X114115Y-540002D02*
X114748Y-539168D01*
X115065Y-538335D01*
Y-535002D01*
X114748Y-534168D01*
X114115Y-533335D01*
G01X117505Y-537335D02*
X117885Y-537918D01*
X118391Y-538252D01*
X118961Y-538335D01*
X119468Y-538252D01*
X119975Y-537835D01*
X120291Y-537335D01*
X120355Y-536835D01*
X120228Y-536252D01*
X119785Y-535835D01*
X119341Y-535668D01*
X118771D01*
G01X119341D02*
X119721Y-535418D01*
X120038Y-535002D01*
X120165Y-534502D01*
X120038Y-534002D01*
X119721Y-533585D01*
X119151Y-533335D01*
X118581Y-533418D01*
X118011Y-533752D01*
G01X122921Y-537752D02*
X123365Y-538168D01*
X123871Y-538335D01*
X124378Y-538168D01*
X124821Y-537668D01*
X125138Y-536918D01*
X125265Y-536168D01*
Y-535252D01*
X125138Y-534502D01*
X124821Y-533835D01*
X124441Y-533502D01*
X123998Y-533335D01*
X123491Y-533502D01*
X123111Y-533835D01*
X122858Y-534335D01*
X122731Y-535002D01*
X122858Y-535585D01*
X123175Y-536168D01*
X123555Y-536502D01*
X123998Y-536585D01*
X124505Y-536418D01*
X124885Y-536002D01*
X125265Y-535252D01*
G01X128971Y-538335D02*
X129098Y-537252D01*
X129288Y-536335D01*
X129541Y-535502D01*
X129858Y-534585D01*
X130365Y-533335D01*
X127831D01*
G01X133375Y-536668D02*
X135021D01*
G01X137905Y-537335D02*
X138285Y-537918D01*
X138791Y-538252D01*
X139361Y-538335D01*
X139868Y-538252D01*
X140375Y-537835D01*
X140691Y-537335D01*
X140755Y-536835D01*
X140628Y-536252D01*
X140185Y-535835D01*
X139741Y-535668D01*
X139171D01*
G01X139741D02*
X140121Y-535418D01*
X140438Y-535002D01*
X140565Y-534502D01*
X140438Y-534002D01*
X140121Y-533585D01*
X139551Y-533335D01*
X138981Y-533418D01*
X138411Y-533752D01*
G01X143195Y-536252D02*
X143638Y-535668D01*
X144018Y-535335D01*
X144525Y-535168D01*
X144968Y-535335D01*
X145285Y-535668D01*
X145538Y-536168D01*
X145601Y-536752D01*
X145538Y-537252D01*
X145285Y-537752D01*
X144905Y-538168D01*
X144461Y-538335D01*
X143955Y-538168D01*
X143511Y-537668D01*
X143258Y-536918D01*
X143195Y-536085D01*
X143321Y-535002D01*
X143511Y-534418D01*
X143828Y-533835D01*
X144271Y-533418D01*
X144715Y-533335D01*
X145158Y-533502D01*
X145475Y-533918D01*
G01X149498Y-538335D02*
Y-533335D01*
X148738Y-534335D01*
G01Y-538335D02*
X150258D01*
G01X155358D02*
Y-533335D01*
X153015Y-536918D01*
X156181D01*
G01X174398Y-468335D02*
Y-543335D01*
G01Y-518335D02*
X277398D01*
Y-493335D01*
G01X174398D02*
X277398D01*
G01Y-468335D02*
Y-543335D01*
G01X279398Y-468335D02*
Y-543335D01*
G01X284905Y-528335D02*
Y-523335D01*
X286171D01*
X286678Y-523585D01*
X287058Y-523918D01*
X287375Y-524418D01*
X287628Y-525002D01*
X287691Y-525835D01*
X287628Y-526668D01*
X287375Y-527252D01*
X287058Y-527752D01*
X286678Y-528085D01*
X286171Y-528335D01*
X284905D01*
G01X289815D02*
X291398Y-523335D01*
X292981Y-528335D01*
G01X292411Y-526585D02*
X290385D01*
G01X296498Y-523335D02*
Y-528335D01*
G01X295041Y-523335D02*
X297955D01*
G01X302865Y-528335D02*
X300331D01*
Y-523335D01*
X302865D01*
G01X301851Y-525752D02*
X300331D01*
G01X306698Y-528502D02*
X306571Y-528418D01*
Y-528252D01*
X306698Y-528168D01*
X306825Y-528252D01*
Y-528418D01*
X306698Y-528502D01*
G01Y-526252D02*
X306571Y-526168D01*
Y-526002D01*
X306698Y-525918D01*
X306825Y-526002D01*
Y-526168D01*
X306698Y-526252D01*
G01X279398Y-518335D02*
X479398D01*
G01X285031Y-503335D02*
Y-498335D01*
X286551D01*
X287058Y-498585D01*
X287438Y-499168D01*
X287565Y-499835D01*
X287438Y-500502D01*
X287121Y-501002D01*
X286551Y-501252D01*
X285031D01*
G01X290258Y-503502D02*
X292538Y-498335D01*
G01X295041Y-503335D02*
Y-498335D01*
X297955Y-503335D01*
Y-498335D01*
G01X301598Y-503502D02*
X301471Y-503418D01*
Y-503252D01*
X301598Y-503168D01*
X301725Y-503252D01*
Y-503418D01*
X301598Y-503502D01*
G01Y-501252D02*
X301471Y-501168D01*
Y-501002D01*
X301598Y-500918D01*
X301725Y-501002D01*
Y-501168D01*
X301598Y-501252D01*
G01X279398Y-493335D02*
X479398D01*
G01X285031Y-478335D02*
Y-473335D01*
X286551D01*
X287058Y-473585D01*
X287438Y-474168D01*
X287565Y-474835D01*
X287438Y-475502D01*
X287121Y-476002D01*
X286551Y-476252D01*
X285031D01*
G01X290131Y-478335D02*
Y-473335D01*
X291715D01*
X292221Y-473585D01*
X292538Y-473918D01*
X292665Y-474585D01*
X292538Y-475252D01*
X292158Y-475668D01*
X291715Y-475918D01*
X290131D01*
G01X291715D02*
X292665Y-478335D01*
G01X296498D02*
X295991Y-478252D01*
X295548Y-477918D01*
X295168Y-477418D01*
X294915Y-476835D01*
X294788Y-476168D01*
Y-475502D01*
X294915Y-474835D01*
X295168Y-474252D01*
X295548Y-473752D01*
X295991Y-473418D01*
X296498Y-473335D01*
X297005Y-473418D01*
X297448Y-473752D01*
X297828Y-474252D01*
X298081Y-474835D01*
X298208Y-475502D01*
Y-476168D01*
X298081Y-476835D01*
X297828Y-477418D01*
X297448Y-477918D01*
X297005Y-478252D01*
X296498Y-478335D01*
G01X300331Y-477335D02*
X300648Y-477835D01*
X301028Y-478168D01*
X301471Y-478335D01*
X301978Y-478168D01*
X302358Y-477835D01*
X302738Y-477335D01*
X302865Y-476668D01*
Y-473335D01*
G01X307965Y-478335D02*
X305431D01*
Y-473335D01*
X307965D01*
G01X306951Y-475752D02*
X305431D01*
G01X313191Y-473752D02*
X312811Y-473502D01*
X312368Y-473335D01*
X311861D01*
X311291Y-473585D01*
X310848Y-474002D01*
X310531Y-474502D01*
X310278Y-475335D01*
X310215Y-476085D01*
X310341Y-476835D01*
X310531Y-477335D01*
X310911Y-477835D01*
X311355Y-478168D01*
X311798Y-478335D01*
X312241D01*
X312685Y-478168D01*
X313065Y-477918D01*
X313381Y-477585D01*
G01X316898Y-473335D02*
Y-478335D01*
G01X315441Y-473335D02*
X318355D01*
G01X321998Y-478502D02*
X321871Y-478418D01*
Y-478252D01*
X321998Y-478168D01*
X322125Y-478252D01*
Y-478418D01*
X321998Y-478502D01*
G01Y-476252D02*
X321871Y-476168D01*
Y-476002D01*
X321998Y-475918D01*
X322125Y-476002D01*
Y-476168D01*
X321998Y-476252D01*
G01X394258Y-543563D02*
Y-518563D01*
G01X397031Y-520835D02*
Y-525835D01*
X399565D01*
G01X402638Y-520835D02*
X404158D01*
G01X403398D02*
Y-525835D01*
G01X402638D02*
X404158D01*
G01X409005Y-523168D02*
X409258Y-522918D01*
X409448Y-522502D01*
X409575Y-521918D01*
X409448Y-521418D01*
X409195Y-521085D01*
X408751Y-520835D01*
X407041D01*
Y-525835D01*
X409131D01*
X409575Y-525502D01*
X409828Y-525002D01*
X409955Y-524418D01*
X409828Y-523835D01*
X409448Y-523335D01*
X409005Y-523168D01*
X407041D01*
G01X413598Y-526002D02*
X413471Y-525918D01*
Y-525752D01*
X413598Y-525668D01*
X413725Y-525752D01*
Y-525918D01*
X413598Y-526002D01*
G01Y-523752D02*
X413471Y-523668D01*
Y-523502D01*
X413598Y-523418D01*
X413725Y-523502D01*
Y-523668D01*
X413598Y-523752D01*
G01X437258Y-518563D02*
Y-543563D01*
G01X437398Y-518335D02*
Y-543335D01*
G01X441298Y-520835D02*
Y-525835D01*
G01X439841Y-520835D02*
X442755D01*
G01X446398Y-525835D02*
X446018Y-525752D01*
X445638Y-525418D01*
X445385Y-524835D01*
X445258Y-524168D01*
X445385Y-523502D01*
X445638Y-522918D01*
X446018Y-522585D01*
X446398Y-522502D01*
X446778Y-522585D01*
X447158Y-522918D01*
X447411Y-523502D01*
X447475Y-524168D01*
X447411Y-524835D01*
X447158Y-525418D01*
X446778Y-525752D01*
X446398Y-525835D01*
G01X451498D02*
X451118Y-525752D01*
X450738Y-525418D01*
X450485Y-524835D01*
X450358Y-524168D01*
X450485Y-523502D01*
X450738Y-522918D01*
X451118Y-522585D01*
X451498Y-522502D01*
X451878Y-522585D01*
X452258Y-522918D01*
X452511Y-523502D01*
X452575Y-524168D01*
X452511Y-524835D01*
X452258Y-525418D01*
X451878Y-525752D01*
X451498Y-525835D01*
G01X456598D02*
Y-520835D01*
G01X461698Y-526002D02*
X461571Y-525918D01*
Y-525752D01*
X461698Y-525668D01*
X461825Y-525752D01*
Y-525918D01*
X461698Y-526002D01*
G01Y-523752D02*
X461571Y-523668D01*
Y-523502D01*
X461698Y-523418D01*
X461825Y-523502D01*
Y-523668D01*
X461698Y-523752D01*
G01X437398Y-493335D02*
Y-518335D01*
G01X440031Y-500835D02*
Y-495835D01*
X441615D01*
X442121Y-496085D01*
X442438Y-496418D01*
X442565Y-497085D01*
X442438Y-497752D01*
X442058Y-498168D01*
X441615Y-498418D01*
X440031D01*
G01X441615D02*
X442565Y-500835D01*
G01X447665D02*
X445131D01*
Y-495835D01*
X447665D01*
G01X446651Y-498252D02*
X445131D01*
G01X449915Y-495835D02*
X451498Y-500835D01*
X453081Y-495835D01*
G01X456598Y-501002D02*
X456471Y-500918D01*
Y-500752D01*
X456598Y-500668D01*
X456725Y-500752D01*
Y-500918D01*
X456598Y-501002D01*
G01Y-498752D02*
X456471Y-498668D01*
Y-498502D01*
X456598Y-498418D01*
X456725Y-498502D01*
Y-498668D01*
X456598Y-498752D01*
G01X445411Y-546502D02*
X445518Y-546377D01*
X445598Y-546168D01*
X445651Y-545877D01*
X445598Y-545627D01*
X445491Y-545460D01*
X445305Y-545335D01*
X444585D01*
Y-547835D01*
X445465D01*
X445651Y-547668D01*
X445758Y-547418D01*
X445811Y-547127D01*
X445758Y-546835D01*
X445598Y-546585D01*
X445411Y-546502D01*
X444585D01*
G01X447878Y-547835D02*
Y-546168D01*
G01Y-546460D02*
X447771Y-546293D01*
X447611Y-546210D01*
X447425Y-546168D01*
X447238Y-546252D01*
X447078Y-546418D01*
X446971Y-546668D01*
X446918Y-547002D01*
X446971Y-547335D01*
X447078Y-547585D01*
X447238Y-547752D01*
X447425Y-547835D01*
X447611Y-547793D01*
X447771Y-547668D01*
X447878Y-547502D01*
G01X449198Y-547543D02*
X449331Y-547710D01*
X449518Y-547835D01*
X449678D01*
X449838Y-547752D01*
X449945Y-547627D01*
X449998Y-547460D01*
X449971Y-547210D01*
X449865Y-547085D01*
X449385Y-546835D01*
X449278Y-546543D01*
X449331Y-546335D01*
X449438Y-546210D01*
X449598Y-546168D01*
X449758Y-546210D01*
X449918Y-546335D01*
G01X451398Y-546710D02*
X452251D01*
X452171Y-546418D01*
X452038Y-546252D01*
X451851Y-546168D01*
X451665Y-546210D01*
X451505Y-546335D01*
X451398Y-546627D01*
X451345Y-546877D01*
Y-547127D01*
X451398Y-547377D01*
X451531Y-547627D01*
X451691Y-547793D01*
X451878Y-547835D01*
X452065Y-547752D01*
X452251Y-547502D01*
G01X453518Y-547835D02*
Y-545335D01*
G01Y-546585D02*
X453651Y-546335D01*
X453811Y-546210D01*
X453971Y-546168D01*
X454211Y-546252D01*
X454371Y-546418D01*
X454478Y-546710D01*
Y-547043D01*
X454425Y-547377D01*
X454318Y-547627D01*
X454131Y-547793D01*
X453971Y-547835D01*
X453811Y-547793D01*
X453651Y-547668D01*
X453518Y-547460D01*
G01X456198Y-547835D02*
X456038Y-547793D01*
X455878Y-547627D01*
X455771Y-547335D01*
X455718Y-547002D01*
X455771Y-546668D01*
X455878Y-546377D01*
X456038Y-546210D01*
X456198Y-546168D01*
X456358Y-546210D01*
X456518Y-546377D01*
X456625Y-546668D01*
X456651Y-547002D01*
X456625Y-547335D01*
X456518Y-547627D01*
X456358Y-547793D01*
X456198Y-547835D01*
G01X458878D02*
Y-546168D01*
G01Y-546460D02*
X458771Y-546293D01*
X458611Y-546210D01*
X458425Y-546168D01*
X458238Y-546252D01*
X458078Y-546418D01*
X457971Y-546668D01*
X457918Y-547002D01*
X457971Y-547335D01*
X458078Y-547585D01*
X458238Y-547752D01*
X458425Y-547835D01*
X458611Y-547793D01*
X458771Y-547668D01*
X458878Y-547502D01*
G01X460225Y-547835D02*
Y-546168D01*
G01Y-546502D02*
X460358Y-546335D01*
X460491Y-546210D01*
X460678Y-546168D01*
X460811Y-546210D01*
X460971Y-546335D01*
G01X463278Y-545335D02*
Y-547835D01*
G01Y-547460D02*
X463171Y-547668D01*
X463011Y-547793D01*
X462825Y-547835D01*
X462611Y-547752D01*
X462451Y-547543D01*
X462345Y-547293D01*
X462318Y-547002D01*
X462345Y-546710D01*
X462451Y-546460D01*
X462611Y-546252D01*
X462825Y-546168D01*
X463011Y-546210D01*
X463145Y-546293D01*
X463278Y-546460D01*
G01X466665Y-547835D02*
Y-545335D01*
X467331D01*
X467545Y-545460D01*
X467678Y-545627D01*
X467731Y-545960D01*
X467678Y-546293D01*
X467518Y-546502D01*
X467331Y-546627D01*
X466665D01*
G01X467331D02*
X467731Y-547835D01*
G01X468998Y-546710D02*
X469851D01*
X469771Y-546418D01*
X469638Y-546252D01*
X469451Y-546168D01*
X469265Y-546210D01*
X469105Y-546335D01*
X468998Y-546627D01*
X468945Y-546877D01*
Y-547127D01*
X468998Y-547377D01*
X469131Y-547627D01*
X469291Y-547793D01*
X469478Y-547835D01*
X469665Y-547752D01*
X469851Y-547502D01*
G01X471118Y-546168D02*
X471598Y-547835D01*
X472078Y-546168D01*
G01X473798Y-547918D02*
X473745Y-547877D01*
Y-547793D01*
X473798Y-547752D01*
X473851Y-547793D01*
Y-547877D01*
X473798Y-547918D01*
G01X475545Y-547543D02*
X475731Y-547752D01*
X475945Y-547835D01*
X476158Y-547752D01*
X476345Y-547502D01*
X476478Y-547127D01*
X476531Y-546752D01*
Y-546293D01*
X476478Y-545918D01*
X476345Y-545585D01*
X476185Y-545418D01*
X475998Y-545335D01*
X475785Y-545418D01*
X475625Y-545585D01*
X475518Y-545835D01*
X475465Y-546168D01*
X475518Y-546460D01*
X475651Y-546752D01*
X475811Y-546918D01*
X475998Y-546960D01*
X476211Y-546877D01*
X476371Y-546668D01*
X476531Y-546293D01*
G01X478411Y-546502D02*
X478518Y-546377D01*
X478598Y-546168D01*
X478651Y-545877D01*
X478598Y-545627D01*
X478491Y-545460D01*
X478305Y-545335D01*
X477585D01*
Y-547835D01*
X478465D01*
X478651Y-547668D01*
X478758Y-547418D01*
X478811Y-547127D01*
X478758Y-546835D01*
X478598Y-546585D01*
X478411Y-546502D01*
X477585D01*
G01X-1490433Y-1677216D02*
Y3837819D01*
X4496476D01*
Y-1677216D01*
X-1490433D01*
G01X-7782Y-515685D02*
X-6215D01*
Y-517575D01*
X-6685Y-518205D01*
X-7234Y-518625D01*
X-8017Y-518835D01*
X-8800Y-518625D01*
X-9349Y-518205D01*
X-9819Y-517575D01*
X-10132Y-516840D01*
X-10289Y-516000D01*
Y-515265D01*
X-10132Y-514635D01*
X-9819Y-513900D01*
X-9349Y-513270D01*
X-8879Y-512850D01*
X-8252Y-512535D01*
X-7704D01*
X-7077Y-512745D01*
X-6607Y-513165D01*
G01X-3675Y-512535D02*
Y-517050D01*
X-3362Y-517995D01*
X-2735Y-518625D01*
X-1952Y-518835D01*
X-1169Y-518625D01*
X-542Y-517995D01*
X-229Y-517050D01*
Y-512535D01*
G01X3408D02*
X5288D01*
G01X4348D02*
Y-518835D01*
G01X3408D02*
X5288D01*
G01X9003Y-517995D02*
X9630Y-518520D01*
X10335Y-518835D01*
X10961D01*
X11588Y-518520D01*
X12058Y-517995D01*
X12293Y-517260D01*
X12136Y-516525D01*
X11745Y-515895D01*
X11040Y-515475D01*
X10100Y-515265D01*
X9551Y-514845D01*
X9316Y-514110D01*
X9473Y-513375D01*
X9865Y-512850D01*
X10413Y-512535D01*
X10961D01*
X11510Y-512745D01*
X11980Y-513270D01*
G01X15303Y-518835D02*
Y-512535D01*
G01X18593D02*
Y-518835D01*
G01Y-515685D02*
X15303D01*
G01X21290Y-518835D02*
X23248Y-512535D01*
X25206Y-518835D01*
G01X24501Y-516630D02*
X21995D01*
G01X27746Y-518835D02*
Y-512535D01*
X31350Y-518835D01*
Y-512535D01*
G01X40425Y-518835D02*
Y-512535D01*
X41991D01*
X42618Y-512850D01*
X43088Y-513270D01*
X43480Y-513900D01*
X43793Y-514635D01*
X43871Y-515685D01*
X43793Y-516735D01*
X43480Y-517470D01*
X43088Y-518100D01*
X42618Y-518520D01*
X41991Y-518835D01*
X40425D01*
G01X47508Y-512535D02*
X49388D01*
G01X48448D02*
Y-518835D01*
G01X47508D02*
X49388D01*
G01X53103Y-517995D02*
X53730Y-518520D01*
X54435Y-518835D01*
X55061D01*
X55688Y-518520D01*
X56158Y-517995D01*
X56393Y-517260D01*
X56236Y-516525D01*
X55845Y-515895D01*
X55140Y-515475D01*
X54200Y-515265D01*
X53651Y-514845D01*
X53416Y-514110D01*
X53573Y-513375D01*
X53965Y-512850D01*
X54513Y-512535D01*
X55061D01*
X55610Y-512745D01*
X56080Y-513270D01*
G01X61048Y-512535D02*
Y-518835D01*
G01X59246Y-512535D02*
X62850D01*
G01X67348Y-519045D02*
X67191Y-518940D01*
Y-518730D01*
X67348Y-518625D01*
X67505Y-518730D01*
Y-518940D01*
X67348Y-519045D01*
G01X73491Y-519990D02*
X73805Y-518625D01*
G01X79948Y-512535D02*
Y-518835D01*
G01X78146Y-512535D02*
X81750D01*
G01X84290Y-518835D02*
X86248Y-512535D01*
X88206Y-518835D01*
G01X87501Y-516630D02*
X84995D01*
G01X92548Y-518835D02*
X91921Y-518730D01*
X91373Y-518310D01*
X90903Y-517680D01*
X90590Y-516945D01*
X90433Y-516105D01*
Y-515265D01*
X90590Y-514425D01*
X90903Y-513690D01*
X91373Y-513060D01*
X91921Y-512640D01*
X92548Y-512535D01*
X93175Y-512640D01*
X93723Y-513060D01*
X94193Y-513690D01*
X94506Y-514425D01*
X94663Y-515265D01*
Y-516105D01*
X94506Y-516945D01*
X94193Y-517680D01*
X93723Y-518310D01*
X93175Y-518730D01*
X92548Y-518835D01*
G01X98848D02*
Y-516000D01*
X97281Y-512535D01*
G01X100415D02*
X98848Y-516000D01*
G01X103425Y-512535D02*
Y-517050D01*
X103738Y-517995D01*
X104365Y-518625D01*
X105148Y-518835D01*
X105931Y-518625D01*
X106558Y-517995D01*
X106871Y-517050D01*
Y-512535D01*
G01X109490Y-518835D02*
X111448Y-512535D01*
X113406Y-518835D01*
G01X112701Y-516630D02*
X110195D01*
G01X115946Y-518835D02*
Y-512535D01*
X119550Y-518835D01*
Y-512535D01*
G01X-6529Y-523060D02*
X-6999Y-522745D01*
X-7547Y-522535D01*
X-8174D01*
X-8879Y-522850D01*
X-9427Y-523375D01*
X-9819Y-524005D01*
X-10132Y-525055D01*
X-10210Y-526000D01*
X-10054Y-526945D01*
X-9819Y-527575D01*
X-9349Y-528205D01*
X-8800Y-528625D01*
X-8252Y-528835D01*
X-7704D01*
X-7155Y-528625D01*
X-6685Y-528310D01*
X-6294Y-527890D01*
G01X-2892Y-522535D02*
X-1012D01*
G01X-1952D02*
Y-528835D01*
G01X-2892D02*
X-1012D01*
G01X4348Y-522535D02*
Y-528835D01*
G01X2546Y-522535D02*
X6150D01*
G01X10648Y-528835D02*
Y-526000D01*
X9081Y-522535D01*
G01X12215D02*
X10648Y-526000D01*
G01X21525Y-527575D02*
X21995Y-528310D01*
X22621Y-528730D01*
X23326Y-528835D01*
X23953Y-528730D01*
X24580Y-528205D01*
X24971Y-527575D01*
X25050Y-526945D01*
X24893Y-526210D01*
X24345Y-525685D01*
X23796Y-525475D01*
X23091D01*
G01X23796D02*
X24266Y-525160D01*
X24658Y-524635D01*
X24815Y-524005D01*
X24658Y-523375D01*
X24266Y-522850D01*
X23561Y-522535D01*
X22856Y-522640D01*
X22151Y-523060D01*
G01X27825Y-527575D02*
X28295Y-528310D01*
X28921Y-528730D01*
X29626Y-528835D01*
X30253Y-528730D01*
X30880Y-528205D01*
X31271Y-527575D01*
X31350Y-526945D01*
X31193Y-526210D01*
X30645Y-525685D01*
X30096Y-525475D01*
X29391D01*
G01X30096D02*
X30566Y-525160D01*
X30958Y-524635D01*
X31115Y-524005D01*
X30958Y-523375D01*
X30566Y-522850D01*
X29861Y-522535D01*
X29156Y-522640D01*
X28451Y-523060D01*
G01X34125Y-527575D02*
X34595Y-528310D01*
X35221Y-528730D01*
X35926Y-528835D01*
X36553Y-528730D01*
X37180Y-528205D01*
X37571Y-527575D01*
X37650Y-526945D01*
X37493Y-526210D01*
X36945Y-525685D01*
X36396Y-525475D01*
X35691D01*
G01X36396D02*
X36866Y-525160D01*
X37258Y-524635D01*
X37415Y-524005D01*
X37258Y-523375D01*
X36866Y-522850D01*
X36161Y-522535D01*
X35456Y-522640D01*
X34751Y-523060D01*
G01X41991Y-528835D02*
X42148Y-527470D01*
X42383Y-526315D01*
X42696Y-525265D01*
X43088Y-524110D01*
X43715Y-522535D01*
X40581D01*
G01X48291Y-528835D02*
X48448Y-527470D01*
X48683Y-526315D01*
X48996Y-525265D01*
X49388Y-524110D01*
X50015Y-522535D01*
X46881D01*
G01X54591Y-529990D02*
X54905Y-528625D01*
G01X61048Y-522535D02*
Y-528835D01*
G01X59246Y-522535D02*
X62850D01*
G01X65390Y-528835D02*
X67348Y-522535D01*
X69306Y-528835D01*
G01X68601Y-526630D02*
X66095D01*
G01X72708Y-522535D02*
X74588D01*
G01X73648D02*
Y-528835D01*
G01X72708D02*
X74588D01*
G01X77598Y-522535D02*
X78695Y-528835D01*
X79948Y-522535D01*
X81201Y-528835D01*
X82298Y-522535D01*
G01X84290Y-528835D02*
X86248Y-522535D01*
X88206Y-528835D01*
G01X87501Y-526630D02*
X84995D01*
G01X90746Y-528835D02*
Y-522535D01*
X94350Y-528835D01*
Y-522535D01*
G01X104756Y-530935D02*
X103973Y-529885D01*
X103581Y-528835D01*
Y-524635D01*
X103973Y-523585D01*
X104756Y-522535D01*
G01X116181Y-528835D02*
Y-522535D01*
X118140D01*
X118766Y-522850D01*
X119158Y-523270D01*
X119315Y-524110D01*
X119158Y-524950D01*
X118688Y-525475D01*
X118140Y-525790D01*
X116181D01*
G01X118140D02*
X119315Y-528835D01*
G01X124048Y-529045D02*
X123891Y-528940D01*
Y-528730D01*
X124048Y-528625D01*
X124205Y-528730D01*
Y-528940D01*
X124048Y-529045D01*
G01X130348Y-528835D02*
X129721Y-528730D01*
X129173Y-528310D01*
X128703Y-527680D01*
X128390Y-526945D01*
X128233Y-526105D01*
Y-525265D01*
X128390Y-524425D01*
X128703Y-523690D01*
X129173Y-523060D01*
X129721Y-522640D01*
X130348Y-522535D01*
X130975Y-522640D01*
X131523Y-523060D01*
X131993Y-523690D01*
X132306Y-524425D01*
X132463Y-525265D01*
Y-526105D01*
X132306Y-526945D01*
X131993Y-527680D01*
X131523Y-528310D01*
X130975Y-528730D01*
X130348Y-528835D01*
G01X136648Y-529045D02*
X136491Y-528940D01*
Y-528730D01*
X136648Y-528625D01*
X136805Y-528730D01*
Y-528940D01*
X136648Y-529045D01*
G01X144671Y-523060D02*
X144201Y-522745D01*
X143653Y-522535D01*
X143026D01*
X142321Y-522850D01*
X141773Y-523375D01*
X141381Y-524005D01*
X141068Y-525055D01*
X140990Y-526000D01*
X141146Y-526945D01*
X141381Y-527575D01*
X141851Y-528205D01*
X142400Y-528625D01*
X142948Y-528835D01*
X143496D01*
X144045Y-528625D01*
X144515Y-528310D01*
X144906Y-527890D01*
G01X149248Y-529045D02*
X149091Y-528940D01*
Y-528730D01*
X149248Y-528625D01*
X149405Y-528730D01*
Y-528940D01*
X149248Y-529045D01*
G01X155940Y-530935D02*
X156723Y-529885D01*
X157115Y-528835D01*
Y-524635D01*
X156723Y-523585D01*
X155940Y-522535D01*
G01X-10054Y-508835D02*
Y-502535D01*
X-6450Y-508835D01*
Y-502535D01*
G01X-1952Y-508835D02*
X-2579Y-508730D01*
X-3127Y-508310D01*
X-3597Y-507680D01*
X-3910Y-506945D01*
X-4067Y-506105D01*
Y-505265D01*
X-3910Y-504425D01*
X-3597Y-503690D01*
X-3127Y-503060D01*
X-2579Y-502640D01*
X-1952Y-502535D01*
X-1325Y-502640D01*
X-777Y-503060D01*
X-307Y-503690D01*
X6Y-504425D01*
X163Y-505265D01*
Y-506105D01*
X6Y-506945D01*
X-307Y-507680D01*
X-777Y-508310D01*
X-1325Y-508730D01*
X-1952Y-508835D01*
G01X4348Y-509045D02*
X4191Y-508940D01*
Y-508730D01*
X4348Y-508625D01*
X4505Y-508730D01*
Y-508940D01*
X4348Y-509045D01*
G01X9160Y-503585D02*
X9630Y-502955D01*
X10178Y-502640D01*
X10805Y-502535D01*
X11588Y-502745D01*
X12136Y-503270D01*
X12293Y-503900D01*
X12215Y-504530D01*
X11901Y-505055D01*
X10335Y-506105D01*
X9630Y-506840D01*
X9160Y-507890D01*
X9003Y-508835D01*
X12293D01*
G01X16948D02*
Y-502535D01*
X16008Y-503795D01*
G01Y-508835D02*
X17888D01*
G01X23248D02*
Y-502535D01*
X22308Y-503795D01*
G01Y-508835D02*
X24188D01*
G01X29391Y-509990D02*
X29705Y-508625D01*
G01X33498Y-502535D02*
X34595Y-508835D01*
X35848Y-502535D01*
X37101Y-508835D01*
X38198Y-502535D01*
G01X43715Y-508835D02*
X40581D01*
Y-502535D01*
X43715D01*
G01X42461Y-505580D02*
X40581D01*
G01X46646Y-508835D02*
Y-502535D01*
X50250Y-508835D01*
Y-502535D01*
G01X53103Y-508835D02*
Y-502535D01*
G01X56393D02*
Y-508835D01*
G01Y-505685D02*
X53103D01*
G01X59325Y-502535D02*
Y-507050D01*
X59638Y-507995D01*
X60265Y-508625D01*
X61048Y-508835D01*
X61831Y-508625D01*
X62458Y-507995D01*
X62771Y-507050D01*
Y-502535D01*
G01X65390Y-508835D02*
X67348Y-502535D01*
X69306Y-508835D01*
G01X68601Y-506630D02*
X66095D01*
G01X78460Y-503585D02*
X78930Y-502955D01*
X79478Y-502640D01*
X80105Y-502535D01*
X80888Y-502745D01*
X81436Y-503270D01*
X81593Y-503900D01*
X81515Y-504530D01*
X81201Y-505055D01*
X79635Y-506105D01*
X78930Y-506840D01*
X78460Y-507890D01*
X78303Y-508835D01*
X81593D01*
G01X84446D02*
Y-502535D01*
X88050Y-508835D01*
Y-502535D01*
G01X90825Y-508835D02*
Y-502535D01*
X92391D01*
X93018Y-502850D01*
X93488Y-503270D01*
X93880Y-503900D01*
X94193Y-504635D01*
X94271Y-505685D01*
X94193Y-506735D01*
X93880Y-507470D01*
X93488Y-508100D01*
X93018Y-508520D01*
X92391Y-508835D01*
X90825D01*
G01X103581D02*
Y-502535D01*
X105540D01*
X106166Y-502850D01*
X106558Y-503270D01*
X106715Y-504110D01*
X106558Y-504950D01*
X106088Y-505475D01*
X105540Y-505790D01*
X103581D01*
G01X105540D02*
X106715Y-508835D01*
G01X109725D02*
Y-502535D01*
X111291D01*
X111918Y-502850D01*
X112388Y-503270D01*
X112780Y-503900D01*
X113093Y-504635D01*
X113171Y-505685D01*
X113093Y-506735D01*
X112780Y-507470D01*
X112388Y-508100D01*
X111918Y-508520D01*
X111291Y-508835D01*
X109725D01*
G01X117748Y-509045D02*
X117591Y-508940D01*
Y-508730D01*
X117748Y-508625D01*
X117905Y-508730D01*
Y-508940D01*
X117748Y-509045D01*
G01X14048Y-498135D02*
X11528Y-497718D01*
X9323Y-496052D01*
X7433Y-493552D01*
X6173Y-490635D01*
X5543Y-487302D01*
Y-483968D01*
X6173Y-480635D01*
X7433Y-477718D01*
X9323Y-475219D01*
X11528Y-473552D01*
X14048Y-473135D01*
X16568Y-473552D01*
X18773Y-475219D01*
X20663Y-477718D01*
X21923Y-480635D01*
X22553Y-483968D01*
Y-487302D01*
X21923Y-490635D01*
X20663Y-493552D01*
X18773Y-496052D01*
X16568Y-497718D01*
X14048Y-498135D01*
G01X16568Y-491468D02*
X20348Y-498135D01*
G01X33893Y-481469D02*
Y-493135D01*
X35153Y-496052D01*
X37043Y-497718D01*
X39248Y-498135D01*
X41453Y-497718D01*
X43343Y-496052D01*
X44603Y-493135D01*
G01Y-498135D02*
Y-481469D01*
G01X70118Y-498135D02*
Y-481469D01*
G01Y-484385D02*
X68858Y-482719D01*
X66968Y-481885D01*
X64763Y-481469D01*
X62558Y-482302D01*
X60668Y-483968D01*
X59408Y-486469D01*
X58778Y-489802D01*
X59408Y-493135D01*
X60668Y-495636D01*
X62558Y-497302D01*
X64763Y-498135D01*
X66968Y-497718D01*
X68858Y-496469D01*
X70118Y-494802D01*
G01X84293Y-498135D02*
Y-481469D01*
G01Y-485635D02*
X85553Y-483552D01*
X87443Y-481885D01*
X89963Y-481469D01*
X92168Y-481885D01*
X94058Y-483552D01*
X95003Y-486469D01*
Y-498135D01*
G01X114848Y-473135D02*
Y-498135D01*
G01X110438Y-481469D02*
X119258D01*
G01X145718Y-498135D02*
Y-481469D01*
G01Y-484385D02*
X144458Y-482719D01*
X142568Y-481885D01*
X140363Y-481469D01*
X138158Y-482302D01*
X136268Y-483968D01*
X135008Y-486469D01*
X134378Y-489802D01*
X135008Y-493135D01*
X136268Y-495636D01*
X138158Y-497302D01*
X140363Y-498135D01*
X142568Y-497718D01*
X144458Y-496469D01*
X145718Y-494802D01*
G01X185398Y-477835D02*
Y-485835D01*
X189398D01*
G01X197198D02*
Y-480502D01*
G01Y-481435D02*
X196798Y-480902D01*
X196198Y-480635D01*
X195498Y-480502D01*
X194798Y-480768D01*
X194198Y-481302D01*
X193798Y-482102D01*
X193598Y-483168D01*
X193798Y-484235D01*
X194198Y-485035D01*
X194798Y-485568D01*
X195498Y-485835D01*
X196198Y-485702D01*
X196798Y-485302D01*
X197198Y-484769D01*
G01X201298Y-488235D02*
X201898Y-488502D01*
X202698Y-488235D01*
X203198Y-487702D01*
X203598Y-487035D01*
X204198Y-484902D01*
X205498Y-480502D01*
G01X202298D02*
X204198Y-484902D01*
G01X209898Y-482235D02*
X213098D01*
X212798Y-481302D01*
X212298Y-480768D01*
X211598Y-480502D01*
X210898Y-480635D01*
X210298Y-481035D01*
X209898Y-481968D01*
X209698Y-482769D01*
Y-483568D01*
X209898Y-484368D01*
X210398Y-485168D01*
X210998Y-485702D01*
X211698Y-485835D01*
X212398Y-485568D01*
X213098Y-484769D01*
G01X217998Y-485835D02*
Y-480502D01*
G01Y-481568D02*
X218498Y-481035D01*
X218998Y-480635D01*
X219698Y-480502D01*
X220198Y-480635D01*
X220798Y-481035D01*
G01X211398Y-535835D02*
Y-532235D01*
X209398Y-527835D01*
G01X213398D02*
X211398Y-532235D01*
G01X217698Y-530502D02*
Y-534235D01*
X218098Y-535168D01*
X218698Y-535702D01*
X219398Y-535835D01*
X220098Y-535702D01*
X220698Y-535168D01*
X221098Y-534235D01*
G01Y-535835D02*
Y-530502D01*
G01X225698Y-535835D02*
Y-530502D01*
G01Y-531835D02*
X226098Y-531168D01*
X226698Y-530635D01*
X227498Y-530502D01*
X228198Y-530635D01*
X228798Y-531168D01*
X229098Y-532102D01*
Y-535835D01*
G01X237198D02*
Y-530502D01*
G01Y-531435D02*
X236798Y-530902D01*
X236198Y-530635D01*
X235498Y-530502D01*
X234798Y-530768D01*
X234198Y-531302D01*
X233798Y-532102D01*
X233598Y-533168D01*
X233798Y-534235D01*
X234198Y-535035D01*
X234798Y-535568D01*
X235498Y-535835D01*
X236198Y-535702D01*
X236798Y-535302D01*
X237198Y-534769D01*
G01X212698Y-505735D02*
X214698D01*
Y-508135D01*
X214098Y-508935D01*
X213398Y-509468D01*
X212398Y-509735D01*
X211398Y-509468D01*
X210698Y-508935D01*
X210098Y-508135D01*
X209698Y-507202D01*
X209498Y-506135D01*
Y-505202D01*
X209698Y-504402D01*
X210098Y-503468D01*
X210698Y-502668D01*
X211298Y-502135D01*
X212098Y-501735D01*
X212798D01*
X213598Y-502002D01*
X214198Y-502535D01*
G01X217798Y-509735D02*
Y-501735D01*
X222398Y-509735D01*
Y-501735D01*
G01X225898Y-509735D02*
Y-501735D01*
X227898D01*
X228698Y-502135D01*
X229298Y-502668D01*
X229798Y-503468D01*
X230198Y-504402D01*
X230298Y-505735D01*
X230198Y-507068D01*
X229798Y-508002D01*
X229298Y-508802D01*
X228698Y-509335D01*
X227898Y-509735D01*
X225898D01*
G01X234198Y-506402D02*
X234898Y-505468D01*
X235498Y-504935D01*
X236298Y-504668D01*
X236998Y-504935D01*
X237498Y-505468D01*
X237898Y-506268D01*
X237998Y-507202D01*
X237898Y-508002D01*
X237498Y-508802D01*
X236898Y-509468D01*
X236198Y-509735D01*
X235398Y-509468D01*
X234698Y-508669D01*
X234298Y-507468D01*
X234198Y-506135D01*
X234398Y-504402D01*
X234698Y-503468D01*
X235198Y-502535D01*
X235898Y-501868D01*
X236598Y-501735D01*
X237298Y-502002D01*
X237798Y-502668D01*
G01X244298Y-486335D02*
Y-478335D01*
X243098Y-479935D01*
G01Y-486335D02*
X245498D01*
G01X250098Y-485135D02*
X250698Y-485802D01*
X251398Y-486202D01*
X252298Y-486335D01*
X253198Y-486068D01*
X253898Y-485535D01*
X254398Y-484602D01*
X254498Y-483535D01*
X254298Y-482468D01*
X253798Y-481802D01*
X253098Y-481268D01*
X252398Y-481135D01*
X251698Y-481268D01*
X250798Y-481802D01*
X251098Y-478335D01*
X253798D01*
G01X311998Y-529168D02*
X312598Y-528368D01*
X313298Y-527968D01*
X314098Y-527835D01*
X315098Y-528102D01*
X315798Y-528768D01*
X315998Y-529568D01*
X315898Y-530369D01*
X315498Y-531035D01*
X313498Y-532368D01*
X312598Y-533302D01*
X311998Y-534635D01*
X311798Y-535835D01*
X315998D01*
G01X321898Y-527835D02*
X321098Y-528102D01*
X320498Y-528768D01*
X320098Y-529568D01*
X319798Y-530635D01*
X319698Y-531835D01*
X319798Y-533035D01*
X320098Y-534102D01*
X320498Y-534902D01*
X321098Y-535568D01*
X321898Y-535835D01*
X322698Y-535568D01*
X323298Y-534902D01*
X323698Y-534102D01*
X323998Y-533035D01*
X324098Y-531835D01*
X323998Y-530635D01*
X323698Y-529568D01*
X323298Y-528768D01*
X322698Y-528102D01*
X321898Y-527835D01*
G01X327998Y-529168D02*
X328598Y-528368D01*
X329298Y-527968D01*
X330098Y-527835D01*
X331098Y-528102D01*
X331798Y-528768D01*
X331998Y-529568D01*
X331898Y-530369D01*
X331498Y-531035D01*
X329498Y-532368D01*
X328598Y-533302D01*
X327998Y-534635D01*
X327798Y-535835D01*
X331998D01*
G01X335698Y-534235D02*
X336298Y-535168D01*
X337098Y-535702D01*
X337998Y-535835D01*
X338798Y-535702D01*
X339598Y-535035D01*
X340098Y-534235D01*
X340198Y-533435D01*
X339998Y-532502D01*
X339298Y-531835D01*
X338598Y-531568D01*
X337698D01*
G01X338598D02*
X339198Y-531168D01*
X339698Y-530502D01*
X339898Y-529702D01*
X339698Y-528902D01*
X339198Y-528235D01*
X338298Y-527835D01*
X337398Y-527968D01*
X336498Y-528502D01*
G01X344098Y-536102D02*
X347698Y-527835D01*
G01X353898D02*
X353098Y-528102D01*
X352498Y-528768D01*
X352098Y-529568D01*
X351798Y-530635D01*
X351698Y-531835D01*
X351798Y-533035D01*
X352098Y-534102D01*
X352498Y-534902D01*
X353098Y-535568D01*
X353898Y-535835D01*
X354698Y-535568D01*
X355298Y-534902D01*
X355698Y-534102D01*
X355998Y-533035D01*
X356098Y-531835D01*
X355998Y-530635D01*
X355698Y-529568D01*
X355298Y-528768D01*
X354698Y-528102D01*
X353898Y-527835D01*
G01X361898Y-535835D02*
Y-527835D01*
X360698Y-529435D01*
G01Y-535835D02*
X363098D01*
G01X368098Y-536102D02*
X371698Y-527835D01*
G01X377898D02*
X377098Y-528102D01*
X376498Y-528768D01*
X376098Y-529568D01*
X375798Y-530635D01*
X375698Y-531835D01*
X375798Y-533035D01*
X376098Y-534102D01*
X376498Y-534902D01*
X377098Y-535568D01*
X377898Y-535835D01*
X378698Y-535568D01*
X379298Y-534902D01*
X379698Y-534102D01*
X379998Y-533035D01*
X380098Y-531835D01*
X379998Y-530635D01*
X379698Y-529568D01*
X379298Y-528768D01*
X378698Y-528102D01*
X377898Y-527835D01*
G01X384198Y-534902D02*
X384898Y-535568D01*
X385698Y-535835D01*
X386498Y-535568D01*
X387198Y-534769D01*
X387698Y-533568D01*
X387898Y-532368D01*
Y-530902D01*
X387698Y-529702D01*
X387198Y-528635D01*
X386598Y-528102D01*
X385898Y-527835D01*
X385098Y-528102D01*
X384498Y-528635D01*
X384098Y-529435D01*
X383898Y-530502D01*
X384098Y-531435D01*
X384598Y-532368D01*
X385198Y-532902D01*
X385898Y-533035D01*
X386698Y-532769D01*
X387298Y-532102D01*
X387898Y-530902D01*
G01X311698Y-510835D02*
Y-502835D01*
X313698D01*
X314498Y-503235D01*
X315098Y-503768D01*
X315598Y-504568D01*
X315998Y-505502D01*
X316098Y-506835D01*
X315998Y-508168D01*
X315598Y-509102D01*
X315098Y-509902D01*
X314498Y-510435D01*
X313698Y-510835D01*
X311698D01*
G01X319398D02*
X321898Y-502835D01*
X324398Y-510835D01*
G01X323498Y-508035D02*
X320298D01*
G01X329898Y-502835D02*
X329098Y-503102D01*
X328498Y-503768D01*
X328098Y-504568D01*
X327798Y-505635D01*
X327698Y-506835D01*
X327798Y-508035D01*
X328098Y-509102D01*
X328498Y-509902D01*
X329098Y-510568D01*
X329898Y-510835D01*
X330698Y-510568D01*
X331298Y-509902D01*
X331698Y-509102D01*
X331998Y-508035D01*
X332098Y-506835D01*
X331998Y-505635D01*
X331698Y-504568D01*
X331298Y-503768D01*
X330698Y-503102D01*
X329898Y-502835D01*
G01X335998Y-510835D02*
Y-502835D01*
X339798D01*
G01X338398Y-506702D02*
X335998D01*
G01X345898Y-502835D02*
X345098Y-503102D01*
X344498Y-503768D01*
X344098Y-504568D01*
X343798Y-505635D01*
X343698Y-506835D01*
X343798Y-508035D01*
X344098Y-509102D01*
X344498Y-509902D01*
X345098Y-510568D01*
X345898Y-510835D01*
X346698Y-510568D01*
X347298Y-509902D01*
X347698Y-509102D01*
X347998Y-508035D01*
X348098Y-506835D01*
X347998Y-505635D01*
X347698Y-504568D01*
X347298Y-503768D01*
X346698Y-503102D01*
X345898Y-502835D01*
G01X353898D02*
Y-510835D01*
G01X351598Y-502835D02*
X356198D01*
G01X363898Y-510835D02*
X359898D01*
Y-502835D01*
X363898D01*
G01X362298Y-506702D02*
X359898D01*
G01X370698Y-506568D02*
X371098Y-506168D01*
X371398Y-505502D01*
X371598Y-504568D01*
X371398Y-503768D01*
X370998Y-503235D01*
X370298Y-502835D01*
X367598D01*
Y-510835D01*
X370898D01*
X371598Y-510302D01*
X371998Y-509502D01*
X372198Y-508568D01*
X371998Y-507635D01*
X371398Y-506835D01*
X370698Y-506568D01*
X367598D01*
G01X376698Y-502835D02*
X379098D01*
G01X377898D02*
Y-510835D01*
G01X376698D02*
X379098D01*
G01X383998D02*
Y-502835D01*
X387798D01*
G01X386398Y-506702D02*
X383998D01*
G01X393898Y-502835D02*
X393098Y-503102D01*
X392498Y-503768D01*
X392098Y-504568D01*
X391798Y-505635D01*
X391698Y-506835D01*
X391798Y-508035D01*
X392098Y-509102D01*
X392498Y-509902D01*
X393098Y-510568D01*
X393898Y-510835D01*
X394698Y-510568D01*
X395298Y-509902D01*
X395698Y-509102D01*
X395998Y-508035D01*
X396098Y-506835D01*
X395998Y-505635D01*
X395698Y-504568D01*
X395298Y-503768D01*
X394698Y-503102D01*
X393898Y-502835D01*
G01X329498Y-485835D02*
Y-477835D01*
X333298D01*
G01X331898Y-481702D02*
X329498D01*
G01X339398Y-477835D02*
X338598Y-478102D01*
X337998Y-478768D01*
X337598Y-479568D01*
X337298Y-480635D01*
X337198Y-481835D01*
X337298Y-483035D01*
X337598Y-484102D01*
X337998Y-484902D01*
X338598Y-485568D01*
X339398Y-485835D01*
X340198Y-485568D01*
X340798Y-484902D01*
X341198Y-484102D01*
X341498Y-483035D01*
X341598Y-481835D01*
X341498Y-480635D01*
X341198Y-479568D01*
X340798Y-478768D01*
X340198Y-478102D01*
X339398Y-477835D01*
G01X347398D02*
Y-485835D01*
G01X345098Y-477835D02*
X349698D01*
G01X352398Y-488502D02*
X358398D01*
G01X361898Y-482235D02*
X365098D01*
X364798Y-481302D01*
X364298Y-480768D01*
X363598Y-480502D01*
X362898Y-480635D01*
X362298Y-481035D01*
X361898Y-481968D01*
X361698Y-482769D01*
Y-483568D01*
X361898Y-484368D01*
X362398Y-485168D01*
X362998Y-485702D01*
X363698Y-485835D01*
X364398Y-485568D01*
X365098Y-484769D01*
G01X369898Y-480502D02*
X372898Y-485835D01*
G01Y-480502D02*
X369898Y-485835D01*
G01X377598Y-488502D02*
Y-480502D01*
G01Y-481702D02*
X378098Y-481035D01*
X378598Y-480635D01*
X379398Y-480502D01*
X380098Y-480635D01*
X380798Y-481302D01*
X381098Y-482235D01*
X381198Y-483168D01*
X381098Y-484102D01*
X380798Y-485035D01*
X380198Y-485568D01*
X379398Y-485835D01*
X378698Y-485702D01*
X377998Y-485302D01*
X377598Y-484769D01*
G01X389198Y-485835D02*
Y-480502D01*
G01Y-481435D02*
X388798Y-480902D01*
X388198Y-480635D01*
X387498Y-480502D01*
X386798Y-480768D01*
X386198Y-481302D01*
X385798Y-482102D01*
X385598Y-483168D01*
X385798Y-484235D01*
X386198Y-485035D01*
X386798Y-485568D01*
X387498Y-485835D01*
X388198Y-485702D01*
X388798Y-485302D01*
X389198Y-484769D01*
G01X393698Y-485835D02*
Y-480502D01*
G01Y-481835D02*
X394098Y-481168D01*
X394698Y-480635D01*
X395498Y-480502D01*
X396198Y-480635D01*
X396798Y-481168D01*
X397098Y-482102D01*
Y-485835D01*
G01X405198Y-477835D02*
Y-485835D01*
G01Y-484635D02*
X404798Y-485302D01*
X404198Y-485702D01*
X403498Y-485835D01*
X402698Y-485568D01*
X402098Y-484902D01*
X401698Y-484102D01*
X401598Y-483168D01*
X401698Y-482235D01*
X402098Y-481435D01*
X402698Y-480768D01*
X403498Y-480502D01*
X404198Y-480635D01*
X404698Y-480902D01*
X405198Y-481435D01*
G01X409898Y-482235D02*
X413098D01*
X412798Y-481302D01*
X412298Y-480768D01*
X411598Y-480502D01*
X410898Y-480635D01*
X410298Y-481035D01*
X409898Y-481968D01*
X409698Y-482769D01*
Y-483568D01*
X409898Y-484368D01*
X410398Y-485168D01*
X410998Y-485702D01*
X411698Y-485835D01*
X412398Y-485568D01*
X413098Y-484769D01*
G01X417998Y-485835D02*
Y-480502D01*
G01Y-481568D02*
X418498Y-481035D01*
X418998Y-480635D01*
X419698Y-480502D01*
X420198Y-480635D01*
X420798Y-481035D01*
G01X424398Y-488502D02*
X430398D01*
G01X433598Y-485835D02*
Y-477835D01*
G01Y-481835D02*
X434098Y-481035D01*
X434698Y-480635D01*
X435298Y-480502D01*
X436198Y-480768D01*
X436798Y-481302D01*
X437198Y-482235D01*
Y-483302D01*
X436998Y-484368D01*
X436598Y-485168D01*
X435898Y-485702D01*
X435298Y-485835D01*
X434698Y-485702D01*
X434098Y-485302D01*
X433598Y-484635D01*
G01X445198Y-477835D02*
Y-485835D01*
G01Y-484635D02*
X444798Y-485302D01*
X444198Y-485702D01*
X443498Y-485835D01*
X442698Y-485568D01*
X442098Y-484902D01*
X441698Y-484102D01*
X441598Y-483168D01*
X441698Y-482235D01*
X442098Y-481435D01*
X442698Y-480768D01*
X443498Y-480502D01*
X444198Y-480635D01*
X444698Y-480902D01*
X445198Y-481435D01*
G01X400398Y-538835D02*
Y-530835D01*
X399198Y-532435D01*
G01Y-538835D02*
X401598D01*
G01X406498Y-535502D02*
X407198Y-534568D01*
X407798Y-534035D01*
X408598Y-533768D01*
X409298Y-534035D01*
X409798Y-534568D01*
X410198Y-535368D01*
X410298Y-536302D01*
X410198Y-537102D01*
X409798Y-537902D01*
X409198Y-538568D01*
X408498Y-538835D01*
X407698Y-538568D01*
X406998Y-537769D01*
X406598Y-536568D01*
X406498Y-535235D01*
X406698Y-533502D01*
X406998Y-532568D01*
X407498Y-531635D01*
X408198Y-530968D01*
X408898Y-530835D01*
X409598Y-531102D01*
X410098Y-531768D01*
G01X416398Y-539102D02*
X416198Y-538968D01*
Y-538702D01*
X416398Y-538568D01*
X416598Y-538702D01*
Y-538968D01*
X416398Y-539102D01*
G01X422498Y-535502D02*
X423198Y-534568D01*
X423798Y-534035D01*
X424598Y-533768D01*
X425298Y-534035D01*
X425798Y-534568D01*
X426198Y-535368D01*
X426298Y-536302D01*
X426198Y-537102D01*
X425798Y-537902D01*
X425198Y-538568D01*
X424498Y-538835D01*
X423698Y-538568D01*
X422998Y-537769D01*
X422598Y-536568D01*
X422498Y-535235D01*
X422698Y-533502D01*
X422998Y-532568D01*
X423498Y-531635D01*
X424198Y-530968D01*
X424898Y-530835D01*
X425598Y-531102D01*
X426098Y-531768D01*
G01X445398Y-538835D02*
Y-530835D01*
X444198Y-532435D01*
G01Y-538835D02*
X446598D01*
G01X453198D02*
X453398Y-537102D01*
X453698Y-535635D01*
X454098Y-534302D01*
X454598Y-532835D01*
X455398Y-530835D01*
X451398D01*
G01X461398Y-539102D02*
X461198Y-538968D01*
Y-538702D01*
X461398Y-538568D01*
X461598Y-538702D01*
Y-538968D01*
X461398Y-539102D01*
G01X467498Y-532168D02*
X468098Y-531368D01*
X468798Y-530968D01*
X469598Y-530835D01*
X470598Y-531102D01*
X471298Y-531768D01*
X471498Y-532568D01*
X471398Y-533369D01*
X470998Y-534035D01*
X468998Y-535368D01*
X468098Y-536302D01*
X467498Y-537635D01*
X467298Y-538835D01*
X471498D01*
G01X465498Y-513835D02*
Y-505835D01*
X469298D01*
G01X467898Y-509702D02*
X465498D01*
M02*
